;LEADER: 12 
;HEADER: 
;CODE  : ASCII 
;FILE  : 9324_DA0F0TMBIJ0_F0T_Motherboard_J_v01_20230324_0910-1-18.drl for  ... layers TOP and BOTTOM
;DESIGN: 9324_DA0F0TMBIJ0_F0T_Motherboard_J_v01_20230324_0910.brd
;   Holesize 1. = 8.000000 Tolerance = +0.000000/-8.000000 PLATED MILS Quantity = 21545
;   Holesize 2. = 9.840000 Tolerance = +2.000000/-2.000000 PLATED MILS Quantity = 176
;   Holesize 3. = 10.000000 Tolerance = +0.000000/-10.000000 PLATED MILS Quantity = 16110
;   Holesize 4. = 14.170000 Tolerance = +1.960000/-1.960000 PLATED MILS Quantity = 608
;   Holesize 5. = 19.680000 Tolerance = +1.960000/-1.960000 PLATED MILS Quantity = 336
;   Holesize 6. = 22.000000 Tolerance = +3.000000/-3.000000 PLATED MILS Quantity = 40
;   Holesize 7. = 40.000000 Tolerance = +1.960000/-1.960000 PLATED MILS Quantity = 1
;   Holesize 8. = 40.000000 Tolerance = +3.000000/-3.000000 PLATED MILS Quantity = 48
;   Holesize 9. = 40.150000 Tolerance = +2.000000/-2.000000 PLATED MILS Quantity = 60
;   Holesize 10. = 41.000000 Tolerance = +3.000000/-3.000000 PLATED MILS Quantity = 46
;   Holesize 11. = 42.000000 Tolerance = +3.000000/-3.000000 PLATED MILS Quantity = 72
;   Holesize 12. = 44.000000 Tolerance = +1.960000/-1.960000 PLATED MILS Quantity = 16
;   Holesize 13. = 67.000000 Tolerance = +3.000000/-3.000000 PLATED MILS Quantity = 48
;   Holesize 14. = 79.000000 Tolerance = +3.000000/-3.000000 PLATED MILS Quantity = 2
;   Holesize 15. = 126.000000 Tolerance = +3.000000/-3.000000 PLATED MILS Quantity = 4
;   Holesize 16. = 150.000000 Tolerance = +3.000000/-3.000000 PLATED MILS Quantity = 2
;   Holesize 17. = 166.000000 Tolerance = +3.000000/-3.000000 PLATED MILS Quantity = 1
;   Holesize 18. = 221.000000 Tolerance = +3.000000/-3.000000 PLATED MILS Quantity = 21
;   Holesize 19. = 30.000000 Tolerance = +3.140000/-0.000000 NON_PLATED MILS Quantity = 2
;   Holesize 20. = 40.000000 Tolerance = +1.960000/-1.960000 NON_PLATED MILS Quantity = 2
;   Holesize 21. = 41.000000 Tolerance = +2.000000/-2.000000 NON_PLATED MILS Quantity = 130
;   Holesize 22. = 44.000000 Tolerance = +1.960000/-1.960000 NON_PLATED MILS Quantity = 8
;   Holesize 23. = 46.000000 Tolerance = +2.000000/-2.000000 NON_PLATED MILS Quantity = 1
;   Holesize 24. = 65.000000 Tolerance = +2.000000/-2.000000 NON_PLATED MILS Quantity = 1
;   Holesize 25. = 120.000000 Tolerance = +2.000000/-2.000000 NON_PLATED MILS Quantity = 2
;   Holesize 26. = 122.000000 Tolerance = +2.000000/-2.000000 NON_PLATED MILS Quantity = 3
;   Holesize 27. = 125.000000 Tolerance = +2.000000/-0.000000 NON_PLATED MILS Quantity = 4
;   Holesize 28. = 125.000000 Tolerance = +2.000000/-2.000000 NON_PLATED MILS Quantity = 6
;   Holesize 29. = 135.000000 Tolerance = +2.000000/-2.000000 NON_PLATED MILS Quantity = 12
;   Holesize 30. = 158.000000 Tolerance = +2.000000/-2.000000 NON_PLATED MILS Quantity = 2
;   Holesize 31. = 217.000000 Tolerance = +2.000000/-2.000000 NON_PLATED MILS Quantity = 2
;   Holesize 32. = 394.000000 Tolerance = +4.000000/-4.000000 NON_PLATED MILS Quantity = 6
%
G90
X0052820Y1253862
X0027699Y1255381
X0057399Y1262074
X0043841Y1252034
X0027699Y1262074
X0043841Y1258727
X0043841Y1255381
X0027699Y1258727
X0057399Y1258727
X0057399Y1265420
X0043841Y1265420
X0043841Y1262074
X0027699Y1265420
X0066099Y1195144
X0066099Y1231955
X0066099Y1191798
X0066099Y1228609
X0066099Y1201837
X0066099Y1208530
X0066099Y1215223
X0066099Y1221916
X0066099Y1238648
X0066099Y1185105
X0066099Y1245341
X0036449Y1257262
X0027699Y1188452
X0027699Y1198491
X0027699Y1205184
X0027699Y1211877
X0027699Y1218570
X0027699Y1225263
X0027699Y1235302
X0027699Y1241995
X0027699Y1248688
X0036399Y1188452
X0043841Y1185105
X0036399Y1198491
X0036399Y1205184
X0043841Y1195144
X0043841Y1201837
X0043841Y1208530
X0036399Y1211877
X0036399Y1218570
X0036399Y1225263
X0043841Y1215223
X0043841Y1221916
X0036399Y1235302
X0036399Y1241995
X0043841Y1231955
X0043841Y1238648
X0036399Y1248688
X0043841Y1245341
X0030746Y1273364
X0033546Y1273364
X0052541Y1185105
X0057399Y1188452
X0052541Y1195144
X0052541Y1201837
X0052541Y1208530
X0057399Y1198491
X0057399Y1205184
X0052541Y1215223
X0052541Y1221916
X0057399Y1211877
X0057399Y1218570
X0057399Y1225263
X0052541Y1231955
X0052541Y1238648
X0057399Y1235302
X0057399Y1241995
X0052541Y1245341
X0057399Y1248688
X0052541Y1248688
X0046746Y1273364
X0049546Y1273364
X0060446Y1273364
X0066099Y1188452
X0066099Y1198491
X0066099Y1205184
X0066099Y1211877
X0066099Y1218570
X0066099Y1225263
X0066099Y1235302
X0066099Y1241995
X0066099Y1248688
X0066189Y1257488
X0063246Y1273364
X0066099Y1084711
X0066099Y1121522
X0066099Y1158333
X0066099Y1118176
X0066099Y1154987
X0066099Y1104790
X0066099Y1111483
X0066099Y1128215
X0066099Y1134908
X0066099Y1141601
X0066099Y1148294
X0066099Y1165026
X0066099Y1171719
X0066099Y1178412
X0066099Y1091404
X0066099Y1098097
X0027699Y1088058
X0027699Y1094751
X0027699Y1101444
X0027699Y1108137
X0027699Y1114829
X0027699Y1124869
X0027699Y1131562
X0027699Y1138255
X0027699Y1144948
X0027699Y1151641
X0027699Y1161680
X0027699Y1168373
X0027699Y1175066
X0027699Y1181759
X0036399Y1088058
X0036399Y1094751
X0043841Y1084711
X0043841Y1091404
X0036399Y1101444
X0036399Y1108137
X0043841Y1098097
X0043841Y1104790
X0043841Y1111483
X0036399Y1114829
X0036399Y1124869
X0043841Y1121522
X0043841Y1128215
X0036399Y1131562
X0036399Y1138255
X0036399Y1144948
X0043841Y1134908
X0043841Y1141601
X0036399Y1151641
X0036399Y1161680
X0043841Y1148294
X0043841Y1158333
X0036399Y1168373
X0036399Y1175066
X0043841Y1165026
X0043841Y1171719
X0036399Y1181759
X0043841Y1178412
X0052541Y1084711
X0052541Y1091404
X0057399Y1088058
X0057399Y1094751
X0052541Y1098097
X0052541Y1104790
X0052541Y1111483
X0057399Y1101444
X0057399Y1108137
X0052541Y1121522
X0052541Y1128215
X0057399Y1114829
X0057399Y1124869
X0052541Y1134908
X0052541Y1141601
X0057399Y1131562
X0057399Y1138255
X0057399Y1144948
X0052541Y1148294
X0052541Y1158333
X0057399Y1151641
X0057399Y1161680
X0052541Y1165026
X0052541Y1171719
X0057399Y1168373
X0057399Y1175066
X0052541Y1178412
X0057399Y1181759
X0066099Y1088058
X0066099Y1094751
X0066099Y1101444
X0066099Y1108137
X0066099Y1114829
X0066099Y1124869
X0066099Y1131562
X0066099Y1138255
X0066099Y1144948
X0066099Y1151641
X0066099Y1161680
X0066099Y1168373
X0066099Y1175066
X0066099Y1181759
X0043841Y0994357
X0066099Y0987664
X0066099Y0994357
X0066099Y1021129
X0066099Y1081365
X0066099Y1054593
X0052541Y1051247
X0036399Y1054593
X0066099Y1067979
X0066099Y1074672
X0066099Y1027822
X0066099Y1034515
X0066099Y1041207
X0066099Y1047900
X0052541Y1024475
X0052541Y1021129
X0066099Y1061286
X0027699Y0984318
X0027699Y0991011
X0027699Y1017782
X0027699Y1024475
X0027699Y1031168
X0027699Y1037861
X0027699Y1044554
X0027699Y1051247
X0027699Y1057940
X0027699Y1064633
X0027699Y1071326
X0027699Y1078018
X0036399Y0984318
X0036399Y0991011
X0043841Y0987664
X0036399Y1017782
X0036399Y1024475
X0036399Y1031168
X0043841Y1017782
X0043841Y1027822
X0036399Y1037861
X0036399Y1044554
X0043841Y1034515
X0043841Y1041207
X0043841Y1047900
X0036399Y1051247
X0036399Y1057940
X0043841Y1054593
X0043841Y1061286
X0036399Y1064633
X0036399Y1071326
X0036399Y1078018
X0043841Y1067979
X0043841Y1074672
X0052541Y0987664
X0057399Y0984318
X0057399Y0991011
X0052541Y1017782
X0052541Y1027822
X0057399Y1017782
X0057399Y1024475
X0057399Y1031168
X0052541Y1034515
X0052541Y1041207
X0052541Y1047900
X0057399Y1037861
X0057399Y1044554
X0052541Y1054593
X0052541Y1061286
X0057399Y1051247
X0057399Y1057940
X0052541Y1067979
X0052541Y1074672
X0057399Y1064633
X0057399Y1071326
X0057399Y1078018
X0066099Y0984318
X0066099Y0991011
X0066099Y1017782
X0066099Y1024475
X0066099Y1031168
X0066099Y1037861
X0066099Y1044554
X0066099Y1051247
X0066099Y1057940
X0066099Y1064633
X0066099Y1071326
X0066099Y1078018
X0052541Y0954200
X0052541Y0957546
X0066099Y0957546
X0036399Y0957546
X0066099Y0937467
X0066099Y0900656
X0066099Y0934121
X0066099Y0897310
X0066099Y0883924
X0066099Y0890617
X0066099Y0907349
X0066099Y0914042
X0066099Y0967585
X0052541Y0964239
X0036399Y0967585
X0066099Y0944160
X0066099Y0950853
X0066099Y0920735
X0066099Y0927428
X0066099Y0974278
X0066099Y0980971
X0066099Y0960892
X0036399Y0960892
X0027699Y0887270
X0027699Y0893963
X0027699Y0904003
X0027699Y0910696
X0027699Y0917389
X0027699Y0924081
X0027699Y0930774
X0027699Y0940814
X0027699Y0947507
X0027699Y0954200
X0027699Y0964239
X0027699Y0970932
X0027699Y0977625
X0043841Y0883924
X0036399Y0887270
X0036399Y0893963
X0043841Y0890617
X0043841Y0900656
X0036399Y0904003
X0036399Y0910696
X0036399Y0917389
X0043841Y0907349
X0043841Y0914042
X0036399Y0924081
X0036399Y0930774
X0043841Y0920735
X0043841Y0927428
X0036399Y0940814
X0036399Y0947507
X0043841Y0937467
X0043841Y0944160
X0036399Y0954200
X0036399Y0964239
X0043841Y0950853
X0043841Y0960892
X0036399Y0970932
X0036399Y0977625
X0043841Y0967585
X0043841Y0974278
X0043841Y0980971
X0052541Y0883924
X0052541Y0890617
X0052541Y0900656
X0057399Y0887270
X0057399Y0893963
X0052541Y0907349
X0052541Y0914042
X0057399Y0904003
X0057399Y0910696
X0057399Y0917389
X0052541Y0920735
X0052541Y0927428
X0057399Y0924081
X0057399Y0930774
X0052541Y0937467
X0052541Y0944160
X0057399Y0940814
X0057399Y0947507
X0052541Y0950853
X0052541Y0960892
X0057399Y0954200
X0057399Y0964239
X0052541Y0967585
X0052541Y0974278
X0052541Y0980971
X0057399Y0970932
X0057399Y0977625
X0066099Y0887270
X0066099Y0893963
X0066099Y0904003
X0066099Y0910696
X0066099Y0917389
X0066099Y0924081
X0066099Y0930774
X0066099Y0940814
X0066099Y0947507
X0066099Y0954200
X0066099Y0964239
X0066099Y0970932
X0066099Y0977625
X0066099Y0790223
X0066099Y0827034
X0066099Y0863845
X0066099Y0786877
X0066099Y0823688
X0066099Y0860499
X0066099Y0870538
X0066099Y0877231
X0066099Y0796916
X0066099Y0803609
X0066099Y0810302
X0066099Y0816995
X0066099Y0833727
X0066099Y0840420
X0066099Y0847113
X0066099Y0853806
X0027699Y0793570
X0027699Y0800263
X0027699Y0806955
X0027699Y0813648
X0027699Y0820341
X0027699Y0830381
X0027699Y0837074
X0027699Y0843766
X0027699Y0850459
X0027699Y0857152
X0027699Y0867192
X0027699Y0873885
X0027699Y0880577
X0036399Y0793570
X0036399Y0800263
X0043841Y0790223
X0043841Y0796916
X0043841Y0803609
X0036399Y0806955
X0036399Y0813648
X0036399Y0820341
X0043841Y0810302
X0043841Y0816995
X0036399Y0830381
X0043841Y0827034
X0043841Y0833727
X0036399Y0837074
X0036399Y0843766
X0036399Y0850459
X0043841Y0840420
X0043841Y0847113
X0036399Y0857152
X0036399Y0867192
X0043841Y0853806
X0043841Y0863845
X0036399Y0873885
X0036399Y0880577
X0043841Y0870538
X0043841Y0877231
X0052541Y0790223
X0052541Y0796916
X0052541Y0803609
X0057399Y0793570
X0057399Y0800263
X0052541Y0810302
X0052541Y0816995
X0057399Y0806955
X0057399Y0813648
X0057399Y0820341
X0052541Y0827034
X0052541Y0833727
X0057399Y0830381
X0052541Y0840420
X0052541Y0847113
X0057399Y0837074
X0057399Y0843766
X0057399Y0850459
X0052541Y0853806
X0052541Y0863845
X0057399Y0857152
X0057399Y0867192
X0052541Y0870538
X0052541Y0877231
X0057399Y0873885
X0057399Y0880577
X0066099Y0793570
X0066099Y0800263
X0066099Y0806955
X0066099Y0813648
X0066099Y0820341
X0066099Y0830381
X0066099Y0837074
X0066099Y0843766
X0066099Y0850459
X0066099Y0857152
X0066099Y0867192
X0066099Y0873885
X0066099Y0880577
X0057299Y0766798
X0066099Y0773491
X0066099Y0780184
X0027699Y0770144
X0027699Y0776837
X0027699Y0783530
X0036399Y0770144
X0043841Y0766798
X0036399Y0776837
X0036399Y0783530
X0043841Y0773491
X0043841Y0780184
X0052541Y0766798
X0057399Y0770144
X0052541Y0773491
X0052541Y0780184
X0057399Y0776837
X0057399Y0783530
X0066099Y0770144
X0066099Y0776837
X0066099Y0783530
X0116567Y0766775
X0086999Y0766798
X0146367Y0766775
X0082241Y0783530
X0082241Y0770144
X0082241Y0776837
X0141641Y0783530
X0141641Y0770144
X0141641Y0776837
X0125499Y0773491
X0125499Y0780184
X0073541Y0766798
X0073541Y0773491
X0073541Y0780184
X0082241Y0766798
X0087099Y0770144
X0082241Y0773491
X0082241Y0780184
X0087099Y0776837
X0087099Y0783530
X0095799Y0770144
X0103241Y0766798
X0095799Y0776837
X0095799Y0783530
X0103241Y0773491
X0103241Y0780184
X0111941Y0766798
X0116799Y0770144
X0125499Y0770144
X0111941Y0773491
X0111941Y0780184
X0116799Y0776837
X0125499Y0776837
X0116799Y0783530
X0125499Y0783530
X0132941Y0766798
X0141641Y0766798
X0132941Y0780184
X0141641Y0780184
X0132941Y0773491
X0141641Y0773491
X0155199Y0770144
X0146499Y0770144
X0155199Y0776837
X0146499Y0776837
X0155199Y0783530
X0146499Y0783530
X0171341Y0766798
X0162641Y0766798
X0162641Y0773491
X0171341Y0773491
X0171341Y0780184
X0162641Y0780184
X0082241Y0820341
X0082241Y0857152
X0082241Y0786877
X0082241Y0823688
X0082241Y0860499
X0082241Y0880577
X0082241Y0793570
X0082241Y0800263
X0082241Y0806955
X0082241Y0813648
X0082241Y0830381
X0082241Y0837074
X0082241Y0843766
X0082241Y0850459
X0082241Y0867192
X0082241Y0873885
X0141641Y0820341
X0141641Y0857152
X0125499Y0790223
X0125499Y0827034
X0125499Y0863845
X0141641Y0786877
X0141641Y0823688
X0141641Y0860499
X0125499Y0786877
X0125499Y0823688
X0125499Y0860499
X0125499Y0870538
X0125499Y0877231
X0141641Y0880577
X0141641Y0793570
X0141641Y0800263
X0125499Y0796916
X0125499Y0803609
X0141641Y0806955
X0141641Y0813648
X0125499Y0810302
X0125499Y0816995
X0141641Y0830381
X0141641Y0837074
X0125499Y0833727
X0125499Y0840420
X0141641Y0843766
X0141641Y0850459
X0125499Y0847113
X0125499Y0853806
X0141641Y0867192
X0141641Y0873885
X0073541Y0790223
X0073541Y0796916
X0073541Y0803609
X0073541Y0810302
X0073541Y0816995
X0073541Y0827034
X0073541Y0833727
X0073541Y0840420
X0073541Y0847113
X0073541Y0853806
X0073541Y0863845
X0073541Y0870538
X0073541Y0877231
X0082241Y0790223
X0082241Y0796916
X0082241Y0803609
X0087099Y0793570
X0087099Y0800263
X0082241Y0810302
X0082241Y0816995
X0087099Y0806955
X0087099Y0813648
X0087099Y0820341
X0082241Y0827034
X0082241Y0833727
X0087099Y0830381
X0082241Y0840420
X0082241Y0847113
X0087099Y0837074
X0087099Y0843766
X0087099Y0850459
X0082241Y0853806
X0082241Y0863845
X0087099Y0857152
X0087099Y0867192
X0082241Y0870538
X0082241Y0877231
X0087099Y0873885
X0087099Y0880577
X0095799Y0793570
X0095799Y0800263
X0103241Y0790223
X0103241Y0796916
X0103241Y0803609
X0095799Y0806955
X0095799Y0813648
X0095799Y0820341
X0103241Y0810302
X0103241Y0816995
X0095799Y0830381
X0103241Y0827034
X0103241Y0833727
X0095799Y0837074
X0095799Y0843766
X0095799Y0850459
X0103241Y0840420
X0103241Y0847113
X0095799Y0857152
X0095799Y0867192
X0103241Y0853806
X0103241Y0863845
X0095799Y0873885
X0095799Y0880577
X0103241Y0870538
X0103241Y0877231
X0111941Y0790223
X0111941Y0796916
X0111941Y0803609
X0116799Y0793570
X0125499Y0793570
X0116799Y0800263
X0125499Y0800263
X0111941Y0810302
X0111941Y0816995
X0116799Y0806955
X0125499Y0806955
X0116799Y0813648
X0125499Y0813648
X0116799Y0820341
X0125499Y0820341
X0111941Y0827034
X0111941Y0833727
X0116799Y0830381
X0125499Y0830381
X0111941Y0840420
X0111941Y0847113
X0116799Y0837074
X0125499Y0837074
X0116799Y0843766
X0125499Y0843766
X0116799Y0850459
X0125499Y0850459
X0111941Y0853806
X0111941Y0863845
X0116799Y0857152
X0125499Y0857152
X0116799Y0867192
X0125499Y0867192
X0111941Y0870538
X0111941Y0877231
X0116799Y0873885
X0125499Y0873885
X0116799Y0880577
X0125499Y0880577
X0132941Y0796916
X0141641Y0796916
X0132941Y0790223
X0141641Y0790223
X0132941Y0803609
X0141641Y0803609
X0132941Y0810302
X0141641Y0810302
X0132941Y0816995
X0141641Y0816995
X0132941Y0827034
X0141641Y0827034
X0132941Y0833727
X0141641Y0833727
X0132941Y0847113
X0141641Y0847113
X0132941Y0840420
X0141641Y0840420
X0132941Y0853806
X0141641Y0853806
X0141641Y0863845
X0132941Y0863845
X0141641Y0877231
X0132941Y0877231
X0141641Y0870538
X0132941Y0870538
X0155199Y0793570
X0146499Y0793570
X0155199Y0800263
X0146499Y0800263
X0155199Y0806955
X0146499Y0806955
X0155199Y0813648
X0146499Y0813648
X0155199Y0820341
X0146499Y0820341
X0155199Y0830381
X0146499Y0830381
X0155199Y0837074
X0146499Y0837074
X0155199Y0843766
X0146499Y0843766
X0155199Y0850459
X0146499Y0850459
X0155199Y0857152
X0146499Y0857152
X0146499Y0867192
X0155199Y0867192
X0146499Y0873885
X0155199Y0873885
X0146499Y0880577
X0155199Y0880577
X0171341Y0790223
X0162641Y0790223
X0171341Y0796916
X0162641Y0796916
X0171341Y0803609
X0162641Y0803609
X0171341Y0810302
X0162641Y0810302
X0171341Y0816995
X0162641Y0816995
X0171341Y0827034
X0162641Y0827034
X0171341Y0833727
X0162641Y0833727
X0171341Y0840420
X0162641Y0840420
X0171341Y0847113
X0162641Y0847113
X0171341Y0853806
X0162641Y0853806
X0162641Y0863845
X0171341Y0863845
X0162641Y0870538
X0171341Y0870538
X0162641Y0877231
X0171341Y0877231
X0082241Y0954200
X0082241Y0957546
X0141641Y0954200
X0141641Y0957546
X0111941Y0954200
X0111941Y0957546
X0171341Y0954200
X0171341Y0957546
X0082241Y0970932
X0082241Y0893963
X0082241Y0930774
X0082241Y0897310
X0082241Y0934121
X0082241Y0887270
X0082241Y0904003
X0082241Y0910696
X0082241Y0964239
X0082241Y0940814
X0082241Y0947507
X0082241Y0917389
X0082241Y0924081
X0082241Y0977625
X0125499Y0957546
X0095799Y0957546
X0141641Y0970932
X0125499Y0937467
X0141641Y0893963
X0141641Y0930774
X0125499Y0900656
X0125499Y0934121
X0141641Y0897310
X0141641Y0934121
X0125499Y0897310
X0141641Y0887270
X0125499Y0883924
X0125499Y0890617
X0141641Y0904003
X0141641Y0910696
X0125499Y0907349
X0125499Y0914042
X0141641Y0964239
X0125499Y0967585
X0111941Y0964239
X0095799Y0967585
X0141641Y0940814
X0141641Y0947507
X0125499Y0944160
X0125499Y0950853
X0141641Y0917389
X0141641Y0924081
X0125499Y0920735
X0125499Y0927428
X0125499Y0974278
X0141641Y0977625
X0125499Y0980971
X0125499Y0960892
X0095799Y0960892
X0155199Y0957546
X0171341Y0964239
X0155199Y0967585
X0155199Y0960892
X0073541Y0883924
X0073541Y0890617
X0073541Y0900656
X0073541Y0907349
X0073541Y0914042
X0073541Y0920735
X0073541Y0927428
X0073541Y0937467
X0073541Y0944160
X0073541Y0950853
X0073541Y0960892
X0073541Y0967585
X0073541Y0974278
X0073541Y0980971
X0082241Y0883924
X0082241Y0890617
X0082241Y0900656
X0087099Y0887270
X0087099Y0893963
X0082241Y0907349
X0082241Y0914042
X0087099Y0904003
X0087099Y0910696
X0087099Y0917389
X0082241Y0920735
X0082241Y0927428
X0087099Y0924081
X0087099Y0930774
X0082241Y0937467
X0082241Y0944160
X0087099Y0940814
X0087099Y0947507
X0082241Y0950853
X0082241Y0960892
X0087099Y0954200
X0087099Y0964239
X0082241Y0967585
X0082241Y0974278
X0082241Y0980971
X0087099Y0970932
X0087099Y0977625
X0103241Y0883924
X0095799Y0887270
X0095799Y0893963
X0103241Y0890617
X0103241Y0900656
X0095799Y0904003
X0095799Y0910696
X0095799Y0917389
X0103241Y0907349
X0103241Y0914042
X0095799Y0924081
X0095799Y0930774
X0103241Y0920735
X0103241Y0927428
X0095799Y0940814
X0095799Y0947507
X0103241Y0937467
X0103241Y0944160
X0095799Y0954200
X0095799Y0964239
X0103241Y0950853
X0103241Y0960892
X0095799Y0970932
X0095799Y0977625
X0103241Y0967585
X0103241Y0974278
X0103241Y0980971
X0111941Y0883924
X0111941Y0890617
X0111941Y0900656
X0116799Y0887270
X0125499Y0887270
X0116799Y0893963
X0125499Y0893963
X0111941Y0907349
X0111941Y0914042
X0116799Y0904003
X0125499Y0904003
X0116799Y0910696
X0125499Y0910696
X0116799Y0917389
X0125499Y0917389
X0111941Y0920735
X0111941Y0927428
X0116799Y0924081
X0125499Y0924081
X0116799Y0930774
X0125499Y0930774
X0111941Y0937467
X0111941Y0944160
X0116799Y0940814
X0125499Y0940814
X0116799Y0947507
X0125499Y0947507
X0111941Y0950853
X0111941Y0960892
X0116799Y0954200
X0125499Y0954200
X0116799Y0964239
X0125499Y0964239
X0111941Y0967585
X0111941Y0974278
X0111941Y0980971
X0116799Y0970932
X0125499Y0970932
X0116799Y0977625
X0125499Y0977625
X0141641Y0883924
X0132941Y0883924
X0141641Y0890617
X0132941Y0890617
X0141641Y0900656
X0132941Y0900656
X0141641Y0914042
X0132941Y0914042
X0141641Y0907349
X0132941Y0907349
X0141641Y0927428
X0132941Y0927428
X0141641Y0920735
X0132941Y0920735
X0141641Y0944160
X0132941Y0944160
X0141641Y0937467
X0132941Y0937467
X0141641Y0950853
X0132941Y0950853
X0141641Y0960892
X0132941Y0960892
X0141641Y0967585
X0132941Y0967585
X0141641Y0974278
X0132941Y0974278
X0141641Y0980971
X0132941Y0980971
X0146499Y0887270
X0155199Y0887270
X0146499Y0893963
X0155199Y0893963
X0146499Y0904003
X0155199Y0904003
X0146499Y0910696
X0155199Y0910696
X0146499Y0917389
X0155199Y0917389
X0146499Y0924081
X0155199Y0924081
X0146499Y0930774
X0155199Y0930774
X0146499Y0940814
X0155199Y0940814
X0146499Y0947507
X0155199Y0947507
X0146499Y0954200
X0155199Y0954200
X0146499Y0964239
X0155199Y0964239
X0146499Y0970932
X0155199Y0970932
X0146499Y0977625
X0155199Y0977625
X0162641Y0883924
X0171341Y0883924
X0162641Y0890617
X0171341Y0890617
X0162641Y0900656
X0171341Y0900656
X0162641Y0907349
X0171341Y0907349
X0162641Y0914042
X0171341Y0914042
X0162641Y0920735
X0171341Y0920735
X0162641Y0927428
X0171341Y0927428
X0162641Y0937467
X0171341Y0937467
X0162641Y0944160
X0171341Y0944160
X0162641Y0950853
X0171341Y0950853
X0162641Y0960892
X0171341Y0960892
X0162641Y0967585
X0171341Y0967585
X0162641Y0974278
X0171341Y0974278
X0162641Y0980971
X0171341Y0980971
X0082241Y0994357
X0141641Y0994357
X0103241Y0994357
X0162641Y0994357
X0141641Y1057940
X0082241Y0984318
X0082241Y0991011
X0082241Y1078018
X0082241Y1081365
X0082241Y1051247
X0082241Y1064633
X0082241Y1071326
X0082241Y1031168
X0082241Y1037861
X0082241Y1044554
X0082241Y1024475
X0082241Y1021129
X0141641Y0984318
X0125499Y0987664
X0141641Y0991011
X0125499Y0994357
X0125499Y1021129
X0141641Y1078018
X0141641Y1081365
X0125499Y1081365
X0141641Y1051247
X0125499Y1054593
X0111941Y1051247
X0095799Y1054593
X0141641Y1064633
X0141641Y1071326
X0125499Y1067979
X0125499Y1074672
X0125499Y1027822
X0141641Y1031168
X0125499Y1034515
X0141641Y1037861
X0125499Y1041207
X0141641Y1044554
X0125499Y1047900
X0141641Y1024475
X0111941Y1024475
X0141641Y1021129
X0111941Y1021129
X0125499Y1061286
X0171341Y1051247
X0155199Y1054593
X0171341Y1024475
X0171341Y1021129
X0073541Y0987664
X0073541Y1017782
X0073541Y1027822
X0073541Y1034515
X0073541Y1041207
X0073541Y1047900
X0073541Y1054593
X0073541Y1061286
X0073541Y1067979
X0073541Y1074672
X0082241Y0987664
X0087099Y0984318
X0087099Y0991011
X0082241Y1017782
X0082241Y1027822
X0087099Y1017782
X0087099Y1024475
X0087099Y1031168
X0082241Y1034515
X0082241Y1041207
X0082241Y1047900
X0087099Y1037861
X0087099Y1044554
X0082241Y1054593
X0082241Y1061286
X0087099Y1051247
X0087099Y1057940
X0082241Y1067979
X0082241Y1074672
X0087099Y1064633
X0087099Y1071326
X0087099Y1078018
X0095799Y0984318
X0095799Y0991011
X0103241Y0987664
X0095799Y1017782
X0095799Y1024475
X0095799Y1031168
X0103241Y1017782
X0103241Y1027822
X0095799Y1037861
X0095799Y1044554
X0103241Y1034515
X0103241Y1041207
X0103241Y1047900
X0095799Y1051247
X0095799Y1057940
X0103241Y1054593
X0103241Y1061286
X0095799Y1064633
X0095799Y1071326
X0095799Y1078018
X0103241Y1067979
X0103241Y1074672
X0111941Y0987664
X0116799Y0984318
X0125499Y0984318
X0116799Y0991011
X0125499Y0991011
X0111941Y1017782
X0111941Y1027822
X0116799Y1017782
X0125499Y1017782
X0116799Y1024475
X0125499Y1024475
X0116799Y1031168
X0125499Y1031168
X0111941Y1034515
X0111941Y1041207
X0111941Y1047900
X0116799Y1037861
X0125499Y1037861
X0116799Y1044554
X0125499Y1044554
X0111941Y1054593
X0111941Y1061286
X0116799Y1051247
X0125499Y1051247
X0116799Y1057940
X0125499Y1057940
X0111941Y1067979
X0111941Y1074672
X0116799Y1064633
X0125499Y1064633
X0116799Y1071326
X0125499Y1071326
X0116799Y1078018
X0125499Y1078018
X0141641Y0987664
X0132941Y0987664
X0141641Y1017782
X0132941Y1017782
X0141641Y1027822
X0132941Y1027822
X0141641Y1034515
X0132941Y1034515
X0141641Y1041207
X0132941Y1041207
X0141641Y1047900
X0132941Y1047900
X0132941Y1054593
X0141641Y1054593
X0132941Y1061286
X0141641Y1061286
X0132941Y1067979
X0141641Y1067979
X0132941Y1074672
X0141641Y1074672
X0146499Y0984318
X0155199Y0984318
X0146499Y0991011
X0155199Y0991011
X0146499Y1017782
X0155199Y1017782
X0146499Y1024475
X0155199Y1024475
X0146499Y1031168
X0155199Y1031168
X0146499Y1037861
X0155199Y1037861
X0146499Y1044554
X0155199Y1044554
X0146499Y1051247
X0155199Y1051247
X0146499Y1057940
X0155199Y1057940
X0146499Y1064633
X0155199Y1064633
X0146499Y1071326
X0155199Y1071326
X0146499Y1078018
X0155199Y1078018
X0162641Y0987664
X0171341Y0987664
X0162641Y1017782
X0171341Y1017782
X0162641Y1027822
X0171341Y1027822
X0162641Y1034515
X0171341Y1034515
X0162641Y1041207
X0171341Y1041207
X0162641Y1047900
X0171341Y1047900
X0162641Y1054593
X0171341Y1054593
X0162641Y1061286
X0171341Y1061286
X0162641Y1067979
X0171341Y1067979
X0162641Y1074672
X0171341Y1074672
X0082241Y1114829
X0082241Y1151641
X0082241Y1118176
X0082241Y1154987
X0082241Y1101444
X0082241Y1108137
X0082241Y1124869
X0082241Y1131562
X0082241Y1138255
X0082241Y1144948
X0082241Y1161680
X0082241Y1168373
X0082241Y1175066
X0082241Y1181759
X0082241Y1088058
X0082241Y1094751
X0141641Y1114829
X0141641Y1151641
X0125499Y1084711
X0125499Y1121522
X0125499Y1158333
X0141641Y1118176
X0141641Y1154987
X0125499Y1118176
X0125499Y1154987
X0141641Y1101444
X0141641Y1108137
X0125499Y1104790
X0125499Y1111483
X0141641Y1124869
X0141641Y1131562
X0125499Y1128215
X0125499Y1134908
X0141641Y1138255
X0141641Y1144948
X0125499Y1141601
X0125499Y1148294
X0141641Y1161680
X0141641Y1168373
X0125499Y1165026
X0125499Y1171719
X0141641Y1175066
X0141641Y1181759
X0125499Y1178412
X0141641Y1088058
X0141641Y1094751
X0125499Y1091404
X0125499Y1098097
X0073541Y1084711
X0073541Y1091404
X0073541Y1098097
X0073541Y1104790
X0073541Y1111483
X0073541Y1121522
X0073541Y1128215
X0073541Y1134908
X0073541Y1141601
X0073541Y1148294
X0073541Y1158333
X0073541Y1165026
X0073541Y1171719
X0073541Y1178412
X0082241Y1084711
X0082241Y1091404
X0087099Y1088058
X0087099Y1094751
X0082241Y1098097
X0082241Y1104790
X0082241Y1111483
X0087099Y1101444
X0087099Y1108137
X0082241Y1121522
X0082241Y1128215
X0087099Y1114829
X0087099Y1124869
X0082241Y1134908
X0082241Y1141601
X0087099Y1131562
X0087099Y1138255
X0087099Y1144948
X0082241Y1148294
X0082241Y1158333
X0087099Y1151641
X0087099Y1161680
X0082241Y1165026
X0082241Y1171719
X0087099Y1168373
X0087099Y1175066
X0082241Y1178412
X0087099Y1181759
X0095799Y1088058
X0095799Y1094751
X0103241Y1084711
X0103241Y1091404
X0095799Y1101444
X0095799Y1108137
X0103241Y1098097
X0103241Y1104790
X0103241Y1111483
X0095799Y1114829
X0095799Y1124869
X0103241Y1121522
X0103241Y1128215
X0095799Y1131562
X0095799Y1138255
X0095799Y1144948
X0103241Y1134908
X0103241Y1141601
X0095799Y1151641
X0095799Y1161680
X0103241Y1148294
X0103241Y1158333
X0095799Y1168373
X0095799Y1175066
X0103241Y1165026
X0103241Y1171719
X0095799Y1181759
X0103241Y1178412
X0111941Y1084711
X0111941Y1091404
X0116799Y1088058
X0125499Y1088058
X0116799Y1094751
X0125499Y1094751
X0111941Y1098097
X0111941Y1104790
X0111941Y1111483
X0116799Y1101444
X0125499Y1101444
X0116799Y1108137
X0125499Y1108137
X0111941Y1121522
X0111941Y1128215
X0116799Y1114829
X0125499Y1114829
X0116799Y1124869
X0125499Y1124869
X0111941Y1134908
X0111941Y1141601
X0116799Y1131562
X0125499Y1131562
X0116799Y1138255
X0125499Y1138255
X0116799Y1144948
X0125499Y1144948
X0111941Y1148294
X0111941Y1158333
X0116799Y1151641
X0125499Y1151641
X0116799Y1161680
X0125499Y1161680
X0111941Y1165026
X0111941Y1171719
X0116799Y1168373
X0125499Y1168373
X0116799Y1175066
X0125499Y1175066
X0111941Y1178412
X0116799Y1181759
X0125499Y1181759
X0132941Y1084711
X0141641Y1084711
X0132941Y1091404
X0141641Y1091404
X0132941Y1098097
X0141641Y1098097
X0132941Y1104790
X0141641Y1104790
X0132941Y1111483
X0141641Y1111483
X0132941Y1121522
X0141641Y1121522
X0132941Y1128215
X0141641Y1128215
X0132941Y1134908
X0141641Y1134908
X0132941Y1141601
X0141641Y1141601
X0132941Y1148294
X0141641Y1148294
X0132941Y1158333
X0141641Y1158333
X0132941Y1165026
X0141641Y1165026
X0132941Y1171719
X0141641Y1171719
X0132941Y1178412
X0141641Y1178412
X0146499Y1088058
X0155199Y1088058
X0146499Y1094751
X0155199Y1094751
X0146499Y1101444
X0155199Y1101444
X0146499Y1108137
X0155199Y1108137
X0146499Y1114829
X0155199Y1114829
X0146499Y1124869
X0155199Y1124869
X0146499Y1131562
X0155199Y1131562
X0146499Y1138255
X0155199Y1138255
X0146499Y1144948
X0155199Y1144948
X0146499Y1151641
X0155199Y1151641
X0146499Y1161680
X0155199Y1161680
X0146499Y1168373
X0155199Y1168373
X0146499Y1175066
X0155199Y1175066
X0146499Y1181759
X0155199Y1181759
X0162641Y1084711
X0171341Y1084711
X0162641Y1091404
X0171341Y1091404
X0162641Y1098097
X0171341Y1098097
X0162641Y1104790
X0171341Y1104790
X0162641Y1111483
X0171341Y1111483
X0162641Y1121522
X0171341Y1121522
X0162641Y1128215
X0171341Y1128215
X0162641Y1134908
X0171341Y1134908
X0162641Y1141601
X0171341Y1141601
X0162641Y1148294
X0171341Y1148294
X0162641Y1158333
X0171341Y1158333
X0162641Y1165026
X0171341Y1165026
X0162641Y1171719
X0171341Y1171719
X0162641Y1178412
X0171341Y1178412
X0114191Y1254604
X0084334Y1254263
X0143675Y1255567
X0082241Y1248688
X0073541Y1252034
X0141641Y1248688
X0132941Y1252034
X0116799Y1262074
X0111941Y1248688
X0103241Y1252034
X0087099Y1262074
X0171341Y1248688
X0162641Y1252034
X0146499Y1262074
X0073541Y1258727
X0132941Y1258727
X0103241Y1258727
X0162641Y1258727
X0073541Y1255381
X0132941Y1255381
X0103241Y1255381
X0162641Y1255381
X0146499Y1258727
X0087099Y1258727
X0116799Y1258727
X0162641Y1262074
X0162641Y1265420
X0146499Y1265420
X0132941Y1262074
X0132941Y1265420
X0116799Y1265420
X0103241Y1262074
X0103241Y1265420
X0087099Y1265420
X0073541Y1262074
X0073541Y1265420
X0082241Y1188452
X0082241Y1225263
X0082241Y1191798
X0082241Y1228609
X0082241Y1211877
X0082241Y1218570
X0082241Y1235302
X0082241Y1241995
X0082241Y1198491
X0082241Y1205184
X0141641Y1188452
X0141641Y1225263
X0125499Y1195144
X0125499Y1231955
X0141641Y1191798
X0141641Y1228609
X0125499Y1191798
X0125499Y1228609
X0125499Y1201837
X0125499Y1208530
X0141641Y1211877
X0141641Y1218570
X0125499Y1215223
X0125499Y1221916
X0141641Y1235302
X0141641Y1241995
X0125499Y1238648
X0125499Y1185105
X0141641Y1198491
X0141641Y1205184
X0125499Y1245341
X0129933Y1238461
X0160130Y1251847
X0073541Y1185105
X0073541Y1195144
X0073541Y1201837
X0073541Y1208530
X0073541Y1215223
X0073541Y1221916
X0073541Y1231955
X0073541Y1238648
X0073541Y1245341
X0076446Y1273364
X0082241Y1185105
X0087099Y1188452
X0082241Y1195144
X0082241Y1201837
X0082241Y1208530
X0087099Y1198491
X0087099Y1205184
X0082241Y1215223
X0082241Y1221916
X0087099Y1211877
X0087099Y1218570
X0087099Y1225263
X0082241Y1231955
X0082241Y1238648
X0087099Y1235302
X0087099Y1241995
X0082241Y1245341
X0087099Y1248688
X0079246Y1273364
X0090146Y1273364
X0092946Y1273364
X0095799Y1188452
X0103241Y1185105
X0095799Y1198491
X0095799Y1205184
X0103241Y1195144
X0103241Y1201837
X0103241Y1208530
X0095799Y1211877
X0095799Y1218570
X0095799Y1225263
X0103241Y1215223
X0103241Y1221916
X0095799Y1235302
X0095799Y1241995
X0103241Y1231955
X0103241Y1238648
X0095799Y1248688
X0103241Y1245341
X0095849Y1257262
X0106146Y1273364
X0108946Y1273364
X0111941Y1185105
X0116799Y1188452
X0125499Y1188452
X0111941Y1195144
X0111941Y1201837
X0111941Y1208530
X0116799Y1198491
X0125499Y1198491
X0116799Y1205184
X0125499Y1205184
X0111941Y1215223
X0111941Y1221916
X0116799Y1211877
X0125499Y1211877
X0116799Y1218570
X0125499Y1218570
X0116799Y1225263
X0125499Y1225263
X0111941Y1231955
X0111941Y1238648
X0116799Y1235302
X0125499Y1235302
X0116799Y1241995
X0125499Y1241995
X0111941Y1245341
X0116799Y1248688
X0125499Y1248688
X0125412Y1257102
X0122646Y1273364
X0119846Y1273364
X0132941Y1185105
X0141641Y1185105
X0132941Y1195144
X0141641Y1195144
X0132941Y1201837
X0141641Y1201837
X0132941Y1208530
X0141641Y1208530
X0141641Y1215223
X0132941Y1215223
X0141641Y1221916
X0132941Y1221916
X0141641Y1231955
X0132941Y1231955
X0141641Y1238648
X0132941Y1238648
X0141641Y1245341
X0132941Y1245341
X0138646Y1273364
X0135846Y1273364
X0146499Y1188452
X0155199Y1188452
X0146499Y1198491
X0155199Y1198491
X0146499Y1205184
X0155199Y1205184
X0146499Y1211877
X0155199Y1211877
X0146499Y1218570
X0155199Y1218570
X0146499Y1225263
X0155199Y1225263
X0146499Y1235302
X0155199Y1235302
X0146499Y1241995
X0155199Y1241995
X0146499Y1248688
X0155199Y1248688
X0155135Y1257134
X0152346Y1273364
X0149546Y1273364
X0162641Y1185105
X0171341Y1185105
X0162641Y1195144
X0171341Y1195144
X0162641Y1201837
X0171341Y1201837
X0162641Y1208530
X0171341Y1208530
X0162641Y1215223
X0171341Y1215223
X0171341Y1221916
X0162641Y1221916
X0162641Y1231955
X0171341Y1231955
X0162641Y1238648
X0171341Y1238648
X0162641Y1245341
X0171341Y1245341
X0168346Y1273364
X0165546Y1273364
X0264764Y1717903
X0264764Y1722440
X0264764Y1726974
X0256890Y1721840
X0256890Y1726377
X0256890Y1730911
X0256890Y1716737
X0249016Y1717903
X0249016Y1722440
X0249016Y1726974
X0241142Y1721840
X0241142Y1726377
X0241142Y1730911
X0241142Y1716737
X0233268Y1726974
X0233268Y1722440
X0233268Y1717903
X0264764Y1712800
X0264764Y1708266
X0264764Y1703729
X0256890Y1712203
X0256890Y1707666
X0256890Y1702564
X0249016Y1712800
X0249016Y1708266
X0249016Y1703729
X0241142Y1712203
X0241142Y1707666
X0241142Y1702564
X0233268Y1703729
X0233268Y1708266
X0233268Y1712800
X0264764Y1698627
X0264764Y1694093
X0264764Y1689556
X0264764Y1684454
X0256890Y1698030
X0256890Y1693493
X0256890Y1688391
X0256890Y1683857
X0249016Y1698627
X0249016Y1694093
X0249016Y1689556
X0249016Y1684454
X0241142Y1698030
X0241142Y1693493
X0241142Y1688391
X0241142Y1683857
X0233268Y1684454
X0233268Y1689556
X0233268Y1694093
X0233268Y1698627
X0264764Y1679920
X0264764Y1675383
X0256890Y1679320
X0249016Y1679920
X0249016Y1675383
X0241142Y1679320
X0233268Y1675383
X0233268Y1679920
X0264357Y1602380
X0264357Y1614292
X0260097Y1614292
X0260097Y1602380
X0252297Y1614292
X0252297Y1602380
X0248037Y1614292
X0248037Y1602380
X0240237Y1614292
X0240237Y1602380
X0235977Y1602380
X0228177Y1602380
X0235977Y1614292
X0228177Y1614292
X0216117Y1602380
X0223917Y1602380
X0216117Y1614292
X0223917Y1614292
X0211857Y1602380
X0211857Y1614292
X0204057Y1602380
X0204057Y1614292
X0199797Y1602380
X0199797Y1614292
X0191997Y1614292
X0191997Y1602380
X0271117Y1590094
X0259057Y1590094
X0266857Y1590094
X0254797Y1590094
X0246997Y1590094
X0242737Y1590094
X0234937Y1590094
X0230677Y1590094
X0222877Y1590094
X0210817Y1590094
X0218617Y1590094
X0198757Y1590094
X0206557Y1590094
X0194497Y1590094
X0186697Y1590094
X0271117Y1578182
X0259057Y1578182
X0266857Y1578182
X0254797Y1578182
X0246997Y1578182
X0242737Y1578182
X0234937Y1578182
X0230677Y1578182
X0222877Y1578182
X0210817Y1578182
X0218617Y1578182
X0198757Y1578182
X0206557Y1578182
X0194497Y1578182
X0186697Y1578182
X0201193Y1257900
X0171947Y1255837
X0201041Y1248688
X0192341Y1252034
X0176199Y1262074
X0260441Y1248688
X0251707Y1252034
X0235599Y1262074
X0230741Y1248688
X0222041Y1252034
X0205899Y1262074
X0192341Y1258727
X0250467Y1259175
X0219660Y1260492
X0192341Y1255381
X0248047Y1259155
X0222041Y1255381
X0235599Y1258727
X0205899Y1258727
X0176199Y1258727
X0251699Y1265254
X0249603Y1266204
X0235480Y1265406
X0222041Y1262074
X0222041Y1265420
X0205899Y1265420
X0192341Y1262074
X0192341Y1265420
X0176199Y1265420
X0201141Y1188452
X0201141Y1225263
X0184899Y1195144
X0184899Y1231955
X0201141Y1191799
X0201141Y1228609
X0184899Y1191798
X0184899Y1228609
X0184899Y1201837
X0184899Y1208530
X0201141Y1211877
X0201141Y1218570
X0184899Y1215223
X0184899Y1221916
X0201141Y1235302
X0201141Y1241995
X0184899Y1238648
X0184899Y1185105
X0201141Y1198491
X0201141Y1205184
X0184899Y1245341
X0260441Y1188452
X0244299Y1195144
X0260441Y1191798
X0244299Y1191798
X0244299Y1201837
X0244299Y1208530
X0244299Y1185105
X0260441Y1198491
X0260441Y1205184
X0257197Y1273640
X0254897Y1274040
X0244789Y1260093
X0238971Y1274353
X0240966Y1273143
X0224987Y1273535
X0227746Y1273364
X0251741Y1245341
X0260441Y1245341
X0251741Y1238648
X0260441Y1238648
X0176199Y1188452
X0176199Y1198491
X0176199Y1205184
X0176199Y1211877
X0176199Y1218570
X0176199Y1225263
X0176199Y1235302
X0176199Y1241995
X0176199Y1248688
X0184899Y1188452
X0192341Y1185105
X0184899Y1198491
X0184899Y1205184
X0192341Y1195144
X0192341Y1201837
X0192341Y1208530
X0184899Y1211877
X0184899Y1218570
X0184899Y1225263
X0192341Y1215223
X0192341Y1221916
X0184899Y1235302
X0184899Y1241995
X0191491Y1231955
X0192341Y1238648
X0184899Y1248688
X0192341Y1245341
X0184923Y1258871
X0179246Y1273364
X0182046Y1273364
X0192605Y1268774
X0192594Y1271262
X0201041Y1185105
X0205899Y1188452
X0201041Y1195144
X0201041Y1201837
X0201041Y1208530
X0205899Y1198491
X0205899Y1205184
X0201041Y1215223
X0201041Y1221916
X0205899Y1218570
X0205899Y1211877
X0205049Y1225263
X0201041Y1231955
X0201041Y1238648
X0205049Y1235302
X0205899Y1241995
X0201041Y1245341
X0205899Y1248688
X0206337Y1268720
X0206268Y1271348
X0214599Y1188452
X0222041Y1185105
X0214599Y1198491
X0214599Y1205184
X0222041Y1195144
X0222041Y1201837
X0222041Y1208530
X0214599Y1218570
X0214599Y1211877
X0215449Y1225263
X0222041Y1215223
X0222041Y1221916
X0215449Y1235302
X0214599Y1241995
X0221191Y1238648
X0221191Y1231955
X0214599Y1248688
X0214824Y1258711
X0222041Y1245341
X0230741Y1185105
X0235599Y1188452
X0230741Y1195144
X0230741Y1201837
X0230741Y1208530
X0235599Y1198491
X0235599Y1205184
X0230741Y1215223
X0230741Y1221916
X0235599Y1211877
X0235599Y1218570
X0234749Y1225263
X0231591Y1238648
X0231591Y1231955
X0235186Y1234977
X0235599Y1241995
X0230741Y1245341
X0235599Y1248688
X0244299Y1188452
X0251741Y1185105
X0244299Y1198491
X0244299Y1205184
X0250891Y1195144
X0251741Y1201837
X0251741Y1208530
X0244299Y1211877
X0244299Y1218570
X0245149Y1225263
X0251741Y1215223
X0250891Y1221916
X0245149Y1235302
X0244299Y1241995
X0250891Y1231955
X0244299Y1248688
X0260441Y1185105
X0260441Y1195144
X0260441Y1201837
X0260441Y1208530
X0260441Y1215223
X0261291Y1221916
X0261291Y1231955
X0201141Y1114830
X0201141Y1151641
X0184899Y1084711
X0184899Y1121522
X0184899Y1158333
X0201141Y1118177
X0201141Y1154988
X0184899Y1118176
X0184899Y1154987
X0201141Y1101444
X0201141Y1108137
X0184899Y1104790
X0184899Y1111483
X0201041Y1124869
X0201041Y1131562
X0184899Y1128215
X0184899Y1134908
X0201141Y1138255
X0201141Y1144948
X0184899Y1141601
X0184899Y1148294
X0201141Y1161680
X0201141Y1168373
X0184899Y1165026
X0184899Y1171719
X0201141Y1175066
X0201141Y1181759
X0184899Y1178412
X0201141Y1088059
X0201141Y1094752
X0184899Y1091404
X0184899Y1098097
X0260441Y1175066
X0260441Y1181759
X0244299Y1178412
X0176199Y1088058
X0176199Y1094751
X0176199Y1101444
X0176199Y1108137
X0176199Y1114829
X0176199Y1124869
X0176199Y1131562
X0176199Y1138255
X0176199Y1144948
X0176199Y1151641
X0176199Y1161680
X0176199Y1168373
X0176199Y1175066
X0176199Y1181759
X0184899Y1088058
X0184899Y1094751
X0191491Y1084711
X0192341Y1091404
X0184899Y1101444
X0184899Y1108137
X0192341Y1098097
X0192341Y1104790
X0192341Y1111483
X0184899Y1114829
X0184899Y1124869
X0192341Y1121522
X0192341Y1128215
X0184899Y1131562
X0184899Y1138255
X0184899Y1144948
X0192341Y1134908
X0192341Y1141601
X0184899Y1151641
X0184899Y1161680
X0192341Y1148294
X0191491Y1158333
X0184899Y1168373
X0184899Y1175066
X0192341Y1165026
X0192341Y1171719
X0184899Y1181759
X0192341Y1178412
X0201041Y1084711
X0201041Y1091404
X0205049Y1088058
X0205899Y1094751
X0201041Y1098097
X0201041Y1104790
X0201041Y1111483
X0205899Y1108137
X0205899Y1101444
X0201041Y1121522
X0201041Y1128215
X0205899Y1124869
X0205899Y1114829
X0201041Y1134908
X0201041Y1141601
X0205899Y1131562
X0205899Y1138255
X0205899Y1144948
X0201041Y1148294
X0201041Y1158333
X0205049Y1151641
X0205049Y1161680
X0201041Y1165026
X0201041Y1171719
X0205899Y1175066
X0205899Y1168373
X0201041Y1178412
X0205899Y1181759
X0215449Y1088058
X0214599Y1094751
X0221191Y1084711
X0222041Y1091404
X0214599Y1108137
X0214599Y1101444
X0222041Y1104790
X0222041Y1098097
X0222041Y1111483
X0214599Y1124869
X0214599Y1114829
X0222041Y1121522
X0222041Y1128215
X0214599Y1131562
X0214599Y1138255
X0214599Y1144948
X0221191Y1134908
X0222041Y1141601
X0215449Y1151641
X0215449Y1161680
X0221191Y1148294
X0222041Y1158333
X0214599Y1175066
X0214599Y1168373
X0222041Y1171719
X0222041Y1165026
X0214599Y1181759
X0222041Y1178412
X0230741Y1084711
X0230741Y1091404
X0234749Y1088058
X0235599Y1094751
X0230741Y1104790
X0230741Y1098097
X0230741Y1111483
X0235599Y1101444
X0235599Y1108137
X0230741Y1121522
X0230741Y1128215
X0235599Y1114829
X0234749Y1124869
X0231591Y1134908
X0230741Y1141601
X0234749Y1131562
X0235599Y1138255
X0235599Y1144948
X0231591Y1148294
X0230741Y1158333
X0235599Y1161680
X0235599Y1151641
X0230741Y1171719
X0230741Y1165026
X0235599Y1168373
X0235599Y1175066
X0230741Y1178412
X0235599Y1181759
X0245149Y1088058
X0244299Y1094751
X0251741Y1084711
X0251741Y1091404
X0244299Y1101444
X0244299Y1108137
X0251741Y1098097
X0250891Y1111483
X0251741Y1104790
X0244299Y1114829
X0245149Y1124869
X0250891Y1121522
X0251741Y1128215
X0245149Y1131562
X0244299Y1138255
X0244299Y1144948
X0251741Y1141601
X0251741Y1134908
X0244299Y1161680
X0244299Y1151641
X0251741Y1148294
X0251741Y1158333
X0244299Y1168373
X0244299Y1175066
X0251741Y1165026
X0251741Y1171719
X0244299Y1181759
X0251741Y1178412
X0260441Y1084711
X0260441Y1091404
X0260441Y1098097
X0261291Y1111483
X0260441Y1104790
X0261291Y1121522
X0260441Y1128215
X0260441Y1141601
X0260441Y1134908
X0260441Y1148294
X0260441Y1158333
X0260441Y1165026
X0260441Y1171719
X0260441Y1178412
X0201041Y0994357
X0251741Y0994357
X0222041Y0994357
X0260441Y1057940
X0257561Y0999608
X0254881Y0999650
X0228891Y1002557
X0231391Y1002557
X0233891Y1002557
X0237841Y1000437
X0240521Y1000395
X0236391Y1002557
X0201041Y0984318
X0184899Y0987664
X0201041Y0991011
X0184899Y0994357
X0184899Y1021129
X0201141Y1078018
X0201141Y1081366
X0184899Y1081365
X0201141Y1051247
X0184899Y1054593
X0201141Y1064633
X0201141Y1071326
X0184899Y1067979
X0184899Y1074672
X0184899Y1027822
X0201141Y1031168
X0184899Y1034515
X0201141Y1037861
X0184899Y1041207
X0201141Y1044554
X0184899Y1047900
X0201141Y1024475
X0201141Y1021129
X0184899Y1061286
X0244299Y1061286
X0176199Y0984318
X0176199Y0991011
X0176199Y1017782
X0176199Y1024475
X0176199Y1031168
X0176199Y1037861
X0176199Y1044554
X0176199Y1051247
X0176199Y1057940
X0176199Y1064633
X0176199Y1071326
X0176199Y1078018
X0184899Y0984318
X0184899Y0991011
X0192341Y0987664
X0184899Y1017782
X0184899Y1024475
X0184899Y1031168
X0192341Y1017782
X0192341Y1027822
X0184899Y1037861
X0184899Y1044554
X0192341Y1034515
X0192341Y1041207
X0192341Y1047900
X0184899Y1051247
X0184899Y1057940
X0192341Y1061286
X0192341Y1054593
X0184899Y1064633
X0184899Y1071326
X0184899Y1078018
X0192341Y1067979
X0192341Y1074672
X0201041Y0987664
X0205899Y0984318
X0205899Y0991011
X0201041Y1017782
X0201041Y1027822
X0205899Y1024475
X0205899Y1017782
X0205899Y1031168
X0201041Y1034515
X0201041Y1041207
X0201041Y1047900
X0205899Y1037861
X0205899Y1044554
X0201041Y1061286
X0201041Y1054593
X0205899Y1051247
X0205899Y1057940
X0201041Y1067979
X0201041Y1074672
X0205899Y1064633
X0205899Y1071326
X0205049Y1078018
X0222041Y0987664
X0214599Y0984318
X0214599Y0991011
X0214599Y1024475
X0214599Y1017782
X0214599Y1031168
X0222041Y1017782
X0222041Y1027822
X0214599Y1037861
X0214599Y1044554
X0222041Y1034515
X0222041Y1041207
X0222041Y1047900
X0214599Y1051247
X0214599Y1057940
X0222041Y1061286
X0222041Y1054593
X0214599Y1064633
X0214599Y1071326
X0215449Y1078018
X0221191Y1074672
X0222041Y1067979
X0235599Y0984318
X0230741Y0987664
X0235599Y0991011
X0235599Y1024475
X0235599Y1017782
X0230741Y1017782
X0230741Y1027822
X0235599Y1031168
X0230741Y1034515
X0230741Y1041207
X0230741Y1047900
X0235599Y1037861
X0235599Y1044554
X0230741Y1061286
X0230741Y1054593
X0235599Y1057940
X0235599Y1051247
X0231591Y1074672
X0230741Y1067979
X0235599Y1064633
X0235599Y1071326
X0234749Y1078018
X0244299Y0984318
X0244299Y0991011
X0251741Y0987664
X0244299Y1024475
X0244299Y1017782
X0251741Y1017782
X0251741Y1027822
X0244299Y1031168
X0244299Y1037861
X0244299Y1044554
X0251741Y1034515
X0251741Y1041207
X0251741Y1047900
X0244299Y1057940
X0244299Y1051247
X0251741Y1054593
X0251741Y1061286
X0244299Y1064633
X0244299Y1071326
X0245149Y1078018
X0250891Y1067979
X0250891Y1074672
X0260441Y0987664
X0260441Y1017782
X0260441Y1027822
X0260441Y1034515
X0260441Y1041207
X0260441Y1047900
X0260441Y1054593
X0260441Y1061286
X0261291Y1067979
X0261291Y1074672
X0201041Y0954200
X0201041Y0957546
X0251741Y0954200
X0251741Y0957546
X0222041Y0954200
X0222041Y0957546
X0184899Y0957546
X0201041Y0970932
X0184899Y0937467
X0201041Y0893963
X0201041Y0930774
X0184899Y0900656
X0184899Y0934121
X0201041Y0897310
X0201041Y0934121
X0184899Y0897310
X0201041Y0887270
X0184899Y0883924
X0184899Y0890617
X0201041Y0904003
X0201041Y0910696
X0184899Y0907349
X0184899Y0914042
X0201041Y0964239
X0184899Y0967585
X0201041Y0940814
X0201041Y0947507
X0184899Y0944160
X0184899Y0950853
X0201041Y0917389
X0201041Y0924081
X0184899Y0920735
X0184899Y0927428
X0184899Y0974278
X0201041Y0977625
X0184899Y0980971
X0184899Y0960892
X0244299Y0957546
X0214599Y0957546
X0260441Y0893963
X0244299Y0900656
X0260441Y0897310
X0244299Y0897310
X0260441Y0887270
X0244299Y0883924
X0244299Y0890617
X0260441Y0904003
X0260441Y0910696
X0244299Y0907349
X0244299Y0914042
X0244299Y0960892
X0214599Y0960892
X0176199Y0887270
X0176199Y0893963
X0176199Y0904003
X0176199Y0910696
X0176199Y0917389
X0176199Y0924081
X0176199Y0930774
X0176199Y0940814
X0176199Y0947507
X0176199Y0954200
X0176199Y0964239
X0176199Y0970932
X0176199Y0977625
X0192341Y0883924
X0184899Y0887270
X0184899Y0893963
X0192341Y0890617
X0192341Y0900656
X0184899Y0904003
X0184899Y0910696
X0184899Y0917389
X0192341Y0907349
X0192341Y0914042
X0184899Y0924081
X0184899Y0930774
X0192341Y0920735
X0191491Y0927428
X0184899Y0940814
X0184899Y0947507
X0192341Y0944160
X0192341Y0937467
X0184899Y0954200
X0184899Y0964239
X0192341Y0950853
X0192341Y0960892
X0184899Y0970932
X0184899Y0977625
X0192341Y0967585
X0192341Y0980971
X0192341Y0974278
X0201041Y0883924
X0201041Y0890617
X0201041Y0900656
X0205899Y0887270
X0205899Y0893963
X0201041Y0907349
X0201041Y0914042
X0205899Y0904003
X0205899Y0910696
X0205899Y0917389
X0201041Y0920735
X0201041Y0927428
X0205049Y0924081
X0205049Y0930774
X0201041Y0944160
X0201041Y0937467
X0205899Y0947507
X0205899Y0940814
X0201041Y0950853
X0201041Y0960892
X0205899Y0954200
X0205899Y0964239
X0201041Y0967585
X0201041Y0980971
X0201041Y0974278
X0205899Y0977625
X0205899Y0970932
X0222041Y0883924
X0214599Y0887270
X0214599Y0893963
X0222041Y0890617
X0222041Y0900656
X0214599Y0904003
X0214599Y0910696
X0214599Y0917389
X0222041Y0907349
X0222041Y0914042
X0215449Y0924081
X0215449Y0930774
X0222041Y0920735
X0221241Y0927428
X0214599Y0947507
X0214599Y0940814
X0221191Y0937467
X0222041Y0944160
X0214599Y0954200
X0214599Y0964239
X0222041Y0950853
X0222041Y0960892
X0214599Y0977625
X0214599Y0970932
X0222041Y0967585
X0222041Y0974278
X0222041Y0980971
X0230741Y0883924
X0230741Y0890617
X0230741Y0900656
X0235599Y0887270
X0235599Y0893963
X0230741Y0907349
X0230741Y0914042
X0235599Y0904003
X0235599Y0910696
X0235599Y0917389
X0230741Y0920735
X0231541Y0927428
X0235599Y0924081
X0235599Y0930774
X0231591Y0937467
X0230741Y0944660
X0234859Y0940814
X0235599Y0947507
X0230741Y0950853
X0230741Y0960892
X0235599Y0954200
X0235599Y0964239
X0230741Y0967585
X0230741Y0974278
X0230741Y0980971
X0235599Y0970932
X0235599Y0977625
X0251741Y0883924
X0244299Y0887270
X0244299Y0893963
X0251741Y0890617
X0250891Y0900656
X0244299Y0904003
X0244299Y0910696
X0244299Y0917389
X0251741Y0907349
X0251741Y0914042
X0244299Y0924081
X0245149Y0930774
X0251741Y0920735
X0250891Y0927428
X0245149Y0940814
X0244299Y0947507
X0250891Y0937467
X0251741Y0944160
X0244299Y0954200
X0244299Y0964239
X0251741Y0950853
X0251741Y0960892
X0244299Y0970932
X0244299Y0977625
X0251741Y0967585
X0251741Y0974278
X0251741Y0980971
X0260441Y0883924
X0260441Y0890617
X0260441Y0900656
X0260441Y0907349
X0260441Y0914042
X0260441Y0920735
X0261291Y0927428
X0261291Y0937467
X0260441Y0944160
X0260441Y0950853
X0260441Y0960892
X0260441Y0967585
X0260441Y0974278
X0260441Y0980971
X0201041Y0820341
X0201041Y0857152
X0184899Y0790223
X0184899Y0827034
X0184899Y0863845
X0201041Y0786877
X0201041Y0823688
X0201041Y0860499
X0184899Y0786877
X0184899Y0823688
X0184899Y0860499
X0184899Y0870538
X0184899Y0877231
X0201041Y0880577
X0201041Y0793570
X0201041Y0800263
X0184899Y0796916
X0184899Y0803609
X0201041Y0806955
X0201041Y0813648
X0184899Y0810302
X0184899Y0816995
X0201041Y0830381
X0201041Y0837074
X0184899Y0833727
X0184899Y0840420
X0201041Y0843766
X0201041Y0850459
X0184899Y0847113
X0184899Y0853806
X0201041Y0867192
X0201041Y0873885
X0260441Y0880577
X0176199Y0793570
X0176199Y0800263
X0176199Y0806955
X0176199Y0813648
X0176199Y0820341
X0176199Y0830381
X0176199Y0837074
X0176199Y0843766
X0176199Y0850459
X0176199Y0857152
X0176199Y0867192
X0176199Y0873885
X0176199Y0880577
X0184899Y0793570
X0184899Y0800263
X0192341Y0790223
X0192341Y0796916
X0192341Y0803609
X0184899Y0806955
X0184899Y0813648
X0184899Y0820341
X0192341Y0810302
X0192341Y0816995
X0184899Y0830381
X0191491Y0827034
X0192341Y0833727
X0184899Y0837074
X0184899Y0843766
X0184899Y0850459
X0192341Y0840420
X0192341Y0847113
X0184899Y0857152
X0192341Y0853806
X0184899Y0867192
X0191491Y0863845
X0184899Y0873885
X0184899Y0880577
X0192341Y0870538
X0192341Y0877231
X0201041Y0790223
X0201041Y0796916
X0201041Y0803609
X0205899Y0793570
X0205899Y0800263
X0201041Y0810302
X0201041Y0816995
X0205049Y0820341
X0205899Y0806955
X0205899Y0813648
X0201041Y0827034
X0201041Y0833727
X0205049Y0830381
X0201041Y0840420
X0201041Y0847113
X0205899Y0843766
X0205899Y0837074
X0205899Y0850459
X0201041Y0853806
X0205049Y0857152
X0201041Y0863845
X0205049Y0867192
X0201041Y0870538
X0201041Y0877231
X0205899Y0880577
X0205899Y0873885
X0214599Y0793570
X0214599Y0800263
X0222041Y0790223
X0222041Y0796916
X0222041Y0803609
X0215449Y0820341
X0214599Y0806955
X0214599Y0813648
X0221191Y0816995
X0222041Y0810302
X0215449Y0830381
X0221191Y0827034
X0222041Y0833727
X0214599Y0843766
X0214599Y0837074
X0214599Y0850459
X0222041Y0840420
X0222041Y0847113
X0215449Y0857152
X0222041Y0853806
X0215449Y0867192
X0221191Y0863845
X0214599Y0880577
X0214599Y0873885
X0221191Y0870538
X0222041Y0877231
X0230741Y0790223
X0230741Y0796916
X0230741Y0803609
X0235599Y0793570
X0235599Y0800263
X0231006Y0817554
X0230741Y0810302
X0235599Y0806955
X0234749Y0813648
X0234749Y0820341
X0231591Y0827034
X0230741Y0833727
X0235599Y0830381
X0230741Y0840420
X0230741Y0847113
X0235599Y0843766
X0235599Y0837074
X0235599Y0850459
X0230741Y0853806
X0234749Y0857152
X0231591Y0863845
X0234749Y0867492
X0231059Y0871084
X0230741Y0877231
X0235599Y0880577
X0235599Y0874185
X0244299Y0793570
X0244299Y0800263
X0251741Y0790223
X0251741Y0796916
X0251741Y0803609
X0244299Y0806955
X0245149Y0813648
X0245149Y0820341
X0251741Y0810302
X0250891Y0816995
X0244299Y0830381
X0250891Y0827034
X0251741Y0833727
X0244299Y0843766
X0244299Y0837074
X0244299Y0850459
X0251741Y0840420
X0251741Y0847113
X0245149Y0857152
X0245149Y0867192
X0250891Y0853806
X0250891Y0863845
X0244299Y0880577
X0244299Y0873885
X0251741Y0877231
X0251741Y0870538
X0260441Y0790223
X0260441Y0796916
X0260441Y0803609
X0260441Y0810302
X0261291Y0816995
X0261291Y0827034
X0260441Y0833727
X0260441Y0840420
X0260441Y0847113
X0261291Y0853806
X0261291Y0863845
X0260441Y0877231
X0260441Y0870538
X0176099Y0766798
X0235499Y0766798
X0205799Y0766798
X0201041Y0783530
X0201041Y0770144
X0201041Y0776837
X0184899Y0773491
X0184899Y0780184
X0176199Y0770144
X0176199Y0776837
X0176199Y0783530
X0184899Y0770144
X0192341Y0766798
X0184899Y0776837
X0184899Y0783530
X0192341Y0773491
X0192341Y0780184
X0201041Y0766798
X0205899Y0770144
X0201041Y0773491
X0201041Y0780184
X0205899Y0776837
X0205899Y0783530
X0214599Y0770144
X0222041Y0766798
X0214599Y0776837
X0214599Y0783530
X0222041Y0773491
X0222041Y0780184
X0230741Y0766798
X0235599Y0770144
X0230741Y0773491
X0230741Y0780184
X0235599Y0776837
X0235599Y0783530
X0244299Y0770144
X0251741Y0766798
X0244299Y0776837
X0244299Y0783530
X0251741Y0773491
X0251741Y0780184
X0260441Y0766798
X0260441Y0773491
X0260441Y0780184
X0367378Y0848176
X0365527Y0844971
X0359978Y0848176
X0358127Y0844971
X0352578Y0848176
X0348878Y0848176
X0371079Y0841467
X0369227Y0844971
X0363679Y0841467
X0361827Y0844971
X0356279Y0841467
X0354427Y0844971
X0350727Y0851380
X0369229Y0857789
X0367378Y0860993
X0361829Y0857789
X0359978Y0860993
X0354429Y0857789
X0352578Y0860993
X0371078Y0854584
X0365529Y0857789
X0363678Y0854584
X0358129Y0857789
X0356278Y0854584
X0350729Y0857789
X0348878Y0880219
X0347029Y0877014
X0363678Y0873810
X0356278Y0873810
X0371078Y0873810
X0363678Y0860993
X0371078Y0860993
X0356278Y0860993
X0348879Y0860993
X0348879Y0873810
X0363678Y0848176
X0371078Y0848176
X0356278Y0848176
X0369229Y0883423
X0361829Y0883423
X0354429Y0883423
X0371078Y0880219
X0365529Y0883423
X0363678Y0880219
X0358129Y0883423
X0356278Y0880219
X0369229Y0870606
X0367378Y0873810
X0363678Y0867401
X0359978Y0873810
X0356278Y0867401
X0352578Y0873810
X0371078Y0867401
X0365529Y0870606
X0361829Y0870606
X0358129Y0870606
X0354429Y0870606
X0350729Y0870606
X0343329Y0883423
X0335928Y0883423
X0341479Y0880219
X0337779Y0880219
X0367379Y0880219
X0369229Y0877014
X0358129Y0877014
X0359979Y0880219
X0361829Y0877014
X0365529Y0877014
X0350729Y0883423
X0347029Y0883423
X0339629Y0883423
X0350729Y0877014
X0352579Y0880219
X0343329Y0877014
X0345179Y0873810
X0345179Y0880219
X0341479Y0873810
X0339629Y0877014
X0354429Y0877014
X0347029Y0870606
X0335928Y0877014
X0332228Y0877014
X0334079Y0880219
X0367379Y0867401
X0359979Y0867401
X0367379Y0854584
X0369229Y0864197
X0358129Y0864197
X0359979Y0854584
X0361829Y0864197
X0365529Y0864197
X0352579Y0867401
X0348879Y0867401
X0341479Y0867401
X0350729Y0864197
X0354429Y0864197
X0352579Y0854584
X0343327Y0857789
X0345179Y0860993
X0348878Y0854584
X0347029Y0857789
X0347029Y0864197
X0339628Y0857789
X0341478Y0854584
X0335924Y0857789
X0337778Y0854584
X0369229Y0851380
X0358129Y0851380
X0361829Y0851380
X0365529Y0851380
X0367379Y0841467
X0359979Y0841467
X0354429Y0851380
X0343327Y0851380
X0347027Y0851380
X0350727Y0844971
X0345178Y0848176
X0347028Y0844971
X0345178Y0854584
X0338042Y0849978
X0331284Y0978814
X0371078Y0886627
X0363678Y0886627
X0367378Y0886627
X0359978Y0886627
X0367379Y0893036
X0363679Y0893036
X0371078Y0963530
X0363678Y0944304
X0371078Y0905853
X0371078Y0944304
X0363678Y0905853
X0359978Y0944304
X0367378Y0905853
X0367378Y0944304
X0359978Y0905853
X0371078Y0893036
X0367378Y0899445
X0369229Y0902649
X0363678Y0899445
X0361829Y0902649
X0369229Y0909057
X0367378Y0912262
X0361829Y0909057
X0363678Y0912262
X0367378Y0957122
X0369229Y0960326
X0363678Y0957122
X0361829Y0960326
X0369229Y0947509
X0367378Y0950713
X0361829Y0947509
X0363678Y0950713
X0367378Y0937896
X0369229Y0941100
X0363678Y0937896
X0361829Y0941100
X0359978Y0963530
X0369229Y0966735
X0361829Y0966735
X0367378Y0969939
X0363678Y0969939
X0358129Y0973143
X0347030Y0953917
X0345179Y0886627
X0358129Y0896240
X0358129Y0915466
X0371078Y0925079
X0354429Y0953917
X0337779Y0886627
X0350729Y0896240
X0350729Y0915466
X0363678Y0925079
X0350729Y0953917
X0341479Y0886627
X0354429Y0896240
X0354429Y0915466
X0367378Y0925079
X0358129Y0953917
X0334079Y0886627
X0347029Y0896240
X0347029Y0915466
X0359978Y0925079
X0348878Y0918670
X0350729Y0921875
X0367378Y0918670
X0369229Y0921875
X0363678Y0918670
X0361829Y0921875
X0369229Y0928283
X0367378Y0931488
X0343328Y0889832
X0341478Y0893036
X0335928Y0889832
X0337779Y0893036
X0354429Y0889832
X0356278Y0893036
X0350729Y0889832
X0348878Y0893036
X0361829Y0928283
X0356278Y0899445
X0354429Y0902649
X0348878Y0899445
X0350729Y0902649
X0354429Y0909057
X0356278Y0912262
X0350729Y0909057
X0348878Y0912262
X0356278Y0918670
X0354429Y0921875
X0363678Y0931488
X0354429Y0966735
X0356278Y0969939
X0350729Y0966735
X0348878Y0969939
X0356278Y0957122
X0354429Y0960326
X0348878Y0957122
X0350729Y0960326
X0354429Y0947509
X0356278Y0950713
X0350729Y0947509
X0348878Y0950713
X0347029Y0973143
X0356278Y0976347
X0348878Y0976347
X0354429Y0979552
X0350729Y0979552
X0363678Y0976347
X0361829Y0979552
X0367378Y0976347
X0369229Y0979552
X0371078Y0982756
X0363678Y0982756
X0367378Y0982756
X0359978Y0982756
X0358129Y0934691
X0350729Y0934691
X0354429Y0934691
X0347029Y0934691
X0354429Y0928283
X0356278Y0931488
X0350729Y0928283
X0348879Y0931488
X0356278Y0937896
X0354429Y0941100
X0348878Y0937896
X0350729Y0941100
X0371078Y0937896
X0369229Y0934691
X0359979Y0937896
X0361828Y0934691
X0365529Y0934691
X0343328Y0934692
X0345179Y0937896
X0339629Y0934692
X0352578Y0937896
X0332228Y0953917
X0335928Y0953917
X0334079Y0957122
X0334079Y0976347
X0332229Y0973143
X0347029Y0947509
X0348878Y0944304
X0347029Y0941100
X0352578Y0944304
X0341478Y0944304
X0352578Y0950713
X0345179Y0950713
X0341479Y0950713
X0352578Y0963530
X0347029Y0966735
X0352578Y0957122
X0345179Y0957122
X0343328Y0953917
X0339629Y0953917
X0339629Y0966735
X0343329Y0966735
X0343328Y0960326
X0347029Y0960326
X0348878Y0963530
X0343329Y0973143
X0339629Y0979552
X0352578Y0982756
X0348878Y0982756
X0352578Y0969939
X0352579Y0976347
X0347029Y0979552
X0350729Y0973143
X0345179Y0969939
X0345179Y0976347
X0339629Y0973143
X0354428Y0973143
X0365529Y0941100
X0365529Y0947509
X0356279Y0944304
X0358129Y0941100
X0358128Y0947509
X0369229Y0953917
X0365528Y0966735
X0365529Y0960326
X0363679Y0963530
X0367378Y0963530
X0365529Y0953917
X0371079Y0950713
X0371078Y0957122
X0359978Y0950713
X0361829Y0953917
X0358128Y0966735
X0359979Y0957122
X0358129Y0960326
X0356279Y0963530
X0365529Y0973143
X0365529Y0979552
X0369229Y0973143
X0371079Y0969939
X0371078Y0976347
X0356279Y0982756
X0361828Y0973143
X0359978Y0969939
X0358129Y0979552
X0359979Y0976347
X0335928Y0934692
X0332228Y0934692
X0332229Y0941100
X0371079Y0931488
X0359978Y0931488
X0371078Y0918670
X0358129Y0921875
X0358128Y0928283
X0359979Y0918670
X0365529Y0921875
X0365529Y0928283
X0356279Y0925079
X0352578Y0931488
X0345179Y0931488
X0341479Y0931488
X0345179Y0918670
X0347029Y0921875
X0347029Y0928283
X0341478Y0925079
X0352578Y0918670
X0352578Y0925079
X0348878Y0925079
X0332229Y0921875
X0369229Y0915466
X0361828Y0915466
X0365529Y0915466
X0371079Y0912262
X0358129Y0902649
X0358128Y0909057
X0359978Y0912262
X0365529Y0902649
X0365529Y0909057
X0356278Y0905853
X0343329Y0915466
X0339629Y0915466
X0352578Y0912262
X0345179Y0912262
X0347029Y0902649
X0347029Y0909057
X0341478Y0905853
X0341479Y0912262
X0352578Y0905853
X0348878Y0905853
X0335928Y0915466
X0332228Y0915466
X0332229Y0902649
X0371078Y0899445
X0359979Y0899445
X0369229Y0889832
X0369229Y0896240
X0358128Y0889832
X0359979Y0893036
X0361829Y0889832
X0361828Y0896240
X0365529Y0889832
X0365529Y0896240
X0356278Y0886627
X0345179Y0899445
X0352578Y0886627
X0352578Y0893036
X0343328Y0896240
X0345179Y0893036
X0347029Y0889832
X0348879Y0886627
X0339629Y0889832
X0339629Y0896240
X0352578Y0899445
X0335928Y0896240
X0334078Y0893036
X0343761Y0999684
X0369662Y0999684
X0371511Y1002888
X0362262Y0999684
X0367811Y1054157
X0364111Y1054157
X0371511Y1054157
X0360411Y1054157
X0367811Y1047749
X0369662Y1050952
X0364111Y1047749
X0362262Y1050952
X0369662Y1057361
X0367811Y1060565
X0362262Y1057361
X0364111Y1060565
X0369662Y1018910
X0367811Y1022114
X0362262Y1018910
X0364111Y1022114
X0364111Y1002888
X0367811Y1009297
X0364111Y1009297
X0369662Y1012501
X0362262Y1012501
X0371511Y1015705
X0360411Y1015705
X0358562Y1025318
X0367811Y1034931
X0358562Y1044544
X0367811Y1073383
X0358562Y1082995
X0351162Y1025318
X0364111Y1034931
X0351161Y1044544
X0364111Y1073383
X0351161Y1082995
X0354862Y1025318
X0371511Y1034931
X0354861Y1044544
X0371511Y1073383
X0354861Y1082995
X0347461Y1025318
X0360411Y1034931
X0347461Y1044544
X0360411Y1073383
X0347461Y1082995
X0362262Y1076587
X0364111Y1079791
X0354861Y1076587
X0356711Y1079791
X0351161Y1076587
X0349311Y1079791
X0367811Y1028523
X0369662Y1031727
X0364111Y1028523
X0362262Y1031727
X0369662Y1038136
X0367811Y1041340
X0362262Y1038136
X0364111Y1041340
X0354861Y1038136
X0356711Y1041340
X0351161Y1038136
X0349311Y1041340
X0356711Y1047749
X0354861Y1050952
X0349311Y1047749
X0351161Y1050952
X0367811Y1066974
X0369662Y1070178
X0364111Y1066974
X0362262Y1070178
X0369662Y1076587
X0367811Y1079791
X0356711Y1009297
X0354861Y1012501
X0349311Y1009297
X0351161Y1012501
X0354861Y1018910
X0356711Y1022114
X0351161Y1018910
X0349311Y1022114
X0356711Y1028523
X0354861Y1031727
X0349311Y1028523
X0351162Y1031727
X0354861Y0999684
X0351161Y0999684
X0356711Y1002888
X0349311Y1002888
X0358562Y1006093
X0347461Y1006093
X0367811Y1002888
X0354861Y1063770
X0351161Y1063770
X0358562Y1063770
X0347461Y1063770
X0349311Y1066974
X0351162Y1070178
X0354861Y1057361
X0356711Y1060565
X0351161Y1057361
X0349311Y1060565
X0356711Y1066974
X0354861Y1070178
X0369662Y1082995
X0362261Y1082995
X0365962Y1082995
X0340060Y1082995
X0343760Y1082995
X0336360Y1082995
X0371511Y1079791
X0360412Y1079791
X0371512Y1066974
X0358562Y1076587
X0358561Y1070178
X0360411Y1066974
X0365962Y1076587
X0365962Y1070178
X0356712Y1073383
X0353011Y1079791
X0341911Y1079791
X0345611Y1079791
X0353011Y1066974
X0345611Y1066974
X0349312Y1073383
X0347461Y1070178
X0347461Y1076587
X0340062Y1076587
X0343761Y1070178
X0343761Y1076587
X0353011Y1073383
X0369662Y1063770
X0362261Y1063770
X0365962Y1063770
X0371511Y1060565
X0358561Y1050952
X0358562Y1057361
X0360412Y1060565
X0365962Y1050952
X0365962Y1057361
X0356712Y1054157
X0343761Y1063770
X0345611Y1060565
X0347461Y1057361
X0347461Y1050952
X0343761Y1050952
X0343761Y1057361
X0353011Y1054157
X0353011Y1060565
X0349311Y1054157
X0333834Y1062790
X0338211Y1060565
X0371511Y1047749
X0360411Y1047749
X0371511Y1041340
X0369662Y1044544
X0358562Y1038136
X0360412Y1041340
X0362261Y1044544
X0365962Y1038136
X0365962Y1044544
X0356712Y1034931
X0345611Y1047749
X0353011Y1041340
X0343761Y1044544
X0345611Y1041340
X0347461Y1038136
X0349311Y1034931
X0343761Y1038136
X0341911Y1041340
X0353011Y1047749
X0353011Y1034931
X0334511Y1041340
X0338211Y1041340
X0332661Y1044544
X0358561Y1031727
X0365962Y1031727
X0371511Y1022114
X0371511Y1028523
X0367811Y1015705
X0369662Y1025318
X0358562Y1018910
X0360412Y1022114
X0362261Y1025318
X0360411Y1028523
X0364112Y1015705
X0365962Y1018910
X0365962Y1025318
X0356712Y1015705
X0347461Y1031727
X0343761Y1031727
X0353011Y1022114
X0345611Y1015705
X0345611Y1022114
X0343761Y1018910
X0345611Y1028523
X0347461Y1018910
X0349311Y1015705
X0341911Y1015705
X0341911Y1022114
X0353011Y1015705
X0353011Y1028523
X0338211Y1022114
X0338211Y1015705
X0332661Y1018910
X0332661Y1025318
X0358561Y1012501
X0365961Y1012501
X0371512Y1009297
X0369662Y1006093
X0358562Y0999684
X0360412Y1002888
X0360411Y1009297
X0362261Y1006093
X0365962Y1006093
X0365962Y0999684
X0347461Y1012501
X0353011Y1002888
X0353011Y1009297
X0354861Y1006093
X0351162Y1006093
X0345611Y1002888
X0343761Y1006093
X0345611Y1009297
X0347461Y0999684
X0341911Y1002888
X0341911Y1009297
X0338211Y1002888
X0332661Y1006093
X0338210Y0996480
X0335349Y0985939
X0367812Y1111834
X0369661Y1115039
X0365961Y1108630
X0358561Y1115039
X0362261Y1108630
X0345611Y1124651
X0347461Y1127856
X0341911Y1131060
X0343761Y1121447
X0340061Y1121447
X0369661Y1108630
X0365961Y1115039
X0364112Y1105426
X0360412Y1111834
X0358561Y1108630
X0347461Y1121447
X0343761Y1127856
X0340061Y1127856
X0341912Y1118243
X0336361Y1121447
X0351162Y1108630
X0353012Y1111834
X0354861Y1102221
X0347461Y1115039
X0341912Y1111834
X0345611Y1105426
X0353011Y1105426
X0349312Y1111834
X0351161Y1102221
X0345611Y1111834
X0343762Y1108630
X0341911Y1105426
X0362262Y1134264
X0369662Y1134264
X0362261Y1121447
X0369662Y1121447
X0360412Y1105426
X0358562Y1102221
X0369661Y1102221
X0367811Y1105426
X0354861Y1134264
X0347461Y1134264
X0354861Y1121447
X0353011Y1118243
X0351162Y1127856
X0349311Y1105426
X0338211Y1131060
X0338211Y1118243
X0369662Y1127856
X0365962Y1121447
X0362262Y1127856
X0356712Y1124651
X0354861Y1127856
X0371511Y1124651
X0367811Y1124651
X0364111Y1124651
X0360412Y1124651
X0358561Y1121447
X0353011Y1124651
X0371512Y1137469
X0367812Y1137469
X0364112Y1137469
X0360412Y1137469
X0356712Y1137469
X0351161Y1134264
X0369661Y1140973
X0365962Y1134264
X0362261Y1140973
X0358561Y1134264
X0349312Y1137469
X0371511Y1092608
X0364111Y1092608
X0367811Y1092608
X0360411Y1092608
X0367811Y1086200
X0369662Y1089404
X0364111Y1086200
X0362262Y1089404
X0369662Y1095813
X0367811Y1099017
X0362262Y1095813
X0364111Y1099017
X0356711Y1086200
X0354861Y1089404
X0349311Y1086200
X0351161Y1089404
X0371511Y1131060
X0367811Y1131060
X0356712Y1131060
X0358561Y1140973
X0360412Y1131060
X0364112Y1131060
X0365961Y1140973
X0353011Y1131060
X0353011Y1137469
X0343761Y1134264
X0349311Y1131060
X0345611Y1131060
X0345611Y1137469
X0358561Y1127856
X0365962Y1127856
X0371511Y1118243
X0367811Y1118243
X0356711Y1118243
X0360411Y1118243
X0362261Y1115039
X0364111Y1118243
X0351161Y1115039
X0351161Y1121447
X0354861Y1115039
X0341911Y1124651
X0343761Y1115039
X0345611Y1118243
X0349312Y1118243
X0349311Y1124651
X0340061Y1115039
X0336361Y1127856
X0336361Y1115039
X0338211Y1124651
X0371512Y1111834
X0356712Y1111834
X0364112Y1111834
X0371512Y1099017
X0371512Y1105426
X0356711Y1099017
X0356711Y1105426
X0360411Y1099017
X0362262Y1102221
X0365962Y1102221
X0343761Y1102221
X0347461Y1102221
X0349311Y1099017
X0340061Y1102221
X0340061Y1108630
X0353011Y1099017
X0354861Y1108630
X0347461Y1108630
X0335344Y1097289
X0338211Y1105426
X0338211Y1111834
X0358561Y1095813
X0365962Y1095813
X0371512Y1086200
X0356712Y1092608
X0358561Y1089404
X0360411Y1086200
X0365962Y1089404
X0340061Y1095813
X0353011Y1092608
X0343707Y1091513
X0345610Y1086200
X0347461Y1089404
X0349310Y1092609
X0353011Y1086200
X0329632Y1092168
X0367597Y1578182
X0355537Y1578182
X0363337Y1578088
X0351277Y1578182
X0343477Y1578182
X0339217Y1578182
X0331417Y1578182
X0327157Y1578182
X0319357Y1578182
X0307297Y1578182
X0315097Y1578182
X0303037Y1578182
X0295237Y1578182
X0290977Y1578182
X0283177Y1578182
X0278917Y1578182
X0355315Y1679320
X0347441Y1675383
X0347441Y1679920
X0339567Y1679320
X0331693Y1675383
X0331693Y1679920
X0323819Y1679320
X0315945Y1675383
X0315945Y1679920
X0308071Y1679320
X0300197Y1675383
X0300197Y1679920
X0280512Y1679920
X0280512Y1675383
X0272638Y1679320
X0360837Y1602380
X0368637Y1602286
X0360837Y1614292
X0368637Y1614292
X0356577Y1614292
X0356577Y1602380
X0348777Y1614292
X0348777Y1602380
X0344517Y1614292
X0344517Y1602380
X0336717Y1614292
X0336717Y1602380
X0332457Y1614292
X0324657Y1614292
X0332457Y1602380
X0324657Y1602380
X0312597Y1602380
X0320397Y1602380
X0312597Y1614292
X0320397Y1614292
X0308337Y1614292
X0308337Y1602380
X0300537Y1614292
X0300537Y1602380
X0296277Y1602380
X0296277Y1614292
X0288477Y1602380
X0288477Y1614292
X0276417Y1602380
X0276417Y1614292
X0284217Y1614292
X0284217Y1602380
X0272157Y1614292
X0272157Y1602380
X0367597Y1590094
X0355537Y1590094
X0363337Y1590094
X0351277Y1590094
X0343477Y1590094
X0339217Y1590094
X0331417Y1590094
X0327157Y1590094
X0319357Y1590094
X0307297Y1590094
X0315097Y1590094
X0303037Y1590094
X0295237Y1590094
X0290977Y1590094
X0283177Y1590094
X0278917Y1590094
X0355315Y1730911
X0355315Y1726377
X0355315Y1721840
X0355315Y1716737
X0347441Y1726974
X0347441Y1722440
X0347441Y1717903
X0339567Y1730911
X0339567Y1726377
X0339567Y1721840
X0339567Y1716737
X0331693Y1726974
X0331693Y1722440
X0331693Y1717903
X0323819Y1730911
X0323819Y1726377
X0323819Y1721840
X0323819Y1716737
X0315945Y1726974
X0315945Y1722440
X0315945Y1717903
X0308071Y1730911
X0308071Y1726377
X0308071Y1721840
X0308071Y1716737
X0300197Y1726974
X0300197Y1722440
X0300197Y1717903
X0280512Y1717903
X0280512Y1722440
X0280512Y1726974
X0272638Y1721840
X0272638Y1726377
X0272638Y1730911
X0272638Y1716737
X0355315Y1707666
X0355315Y1712203
X0355315Y1702564
X0347441Y1703729
X0347441Y1708266
X0347441Y1712800
X0339567Y1707666
X0339567Y1712203
X0339567Y1702564
X0331693Y1703729
X0331693Y1708266
X0331693Y1712800
X0323819Y1707666
X0323819Y1712203
X0323819Y1702564
X0315945Y1703729
X0315945Y1708266
X0315945Y1712800
X0308071Y1707666
X0308071Y1712203
X0308071Y1702564
X0300197Y1703729
X0300197Y1708266
X0300197Y1712800
X0280512Y1712800
X0280512Y1708266
X0280512Y1703729
X0272638Y1712203
X0272638Y1707666
X0272638Y1702564
X0355315Y1688391
X0355315Y1693493
X0355315Y1698030
X0355315Y1683857
X0347441Y1684454
X0347441Y1689556
X0347441Y1694093
X0347441Y1698627
X0339567Y1688391
X0339567Y1693493
X0339567Y1698030
X0339567Y1683857
X0331693Y1684454
X0331693Y1689556
X0331693Y1694093
X0331693Y1698627
X0323819Y1688391
X0323819Y1693493
X0323819Y1698030
X0323819Y1683857
X0315945Y1684454
X0315945Y1689556
X0315945Y1694093
X0315945Y1698627
X0308071Y1688391
X0308071Y1693493
X0308071Y1698030
X0308071Y1683857
X0300197Y1684454
X0300197Y1689556
X0300197Y1694093
X0300197Y1698627
X0280512Y1698627
X0280512Y1694093
X0280512Y1689556
X0280512Y1684454
X0272638Y1698030
X0272638Y1693493
X0272638Y1688391
X0272638Y1683857
X0380697Y1614292
X0372897Y1614292
X0380697Y1602380
X0372897Y1602380
X0470851Y1590094
X0375397Y1590094
X0470851Y1578182
X0375397Y1578182
X0462161Y1089403
X0458461Y1089403
X0454761Y1095812
X0464012Y1092607
X0460312Y1099016
X0465861Y1095812
X0471412Y1092607
X0460311Y1086200
X0454761Y1089403
X0456612Y1092607
X0465861Y1089403
X0458461Y1095812
X0462161Y1095812
X0471412Y1086199
X0414062Y1127856
X0412212Y1137469
X0406661Y1121447
X0399262Y1121447
X0415911Y1105426
X0419611Y1111834
X0412211Y1105426
X0414062Y1115039
X0408511Y1111834
X0410362Y1108630
X0401111Y1111834
X0402962Y1115039
X0399262Y1108630
X0391862Y1115039
X0395562Y1108630
X0402962Y1102221
X0408511Y1099017
X0419611Y1105426
X0417762Y1108630
X0414062Y1102221
X0415911Y1111834
X0412211Y1111834
X0408511Y1105426
X0402962Y1108630
X0399262Y1115039
X0397411Y1105426
X0393711Y1111834
X0391862Y1108630
X0401111Y1099017
X0404811Y1099017
X0380762Y1115039
X0382611Y1105426
X0375211Y1111834
X0378912Y1105426
X0412211Y1086200
X0427012Y1086200
X0428861Y1089404
X0423311Y1086200
X0430711Y1092608
X0425162Y1095813
X0419611Y1092608
X0402961Y1089404
X0414062Y1089404
X0408511Y1092608
X0386311Y1111834
X0384462Y1108630
X0378911Y1111834
X0380762Y1102221
X0377062Y1108630
X0375211Y1105426
X0430710Y1086200
X0419611Y1086200
X0427011Y1092608
X0423311Y1092608
X0421462Y1089404
X0404811Y1086200
X0410362Y1089404
X0406662Y1089404
X0382611Y1111834
X0386311Y1105426
X0414061Y1095813
X0469561Y1134264
X0465861Y1140973
X0467712Y1131060
X0465861Y1134264
X0467712Y1137469
X0454761Y1140973
X0458461Y1140973
X0462161Y1140973
X0454761Y1134264
X0456611Y1131060
X0460312Y1131060
X0462161Y1134264
X0464012Y1131060
X0456612Y1137469
X0460312Y1137469
X0464012Y1137469
X0465861Y1127856
X0454761Y1127856
X0462161Y1127856
X0454761Y1115039
X0456611Y1118243
X0460312Y1118243
X0462161Y1115039
X0464011Y1118243
X0454761Y1121447
X0456611Y1124651
X0460312Y1124651
X0462161Y1121447
X0464012Y1124651
X0456611Y1111834
X0460312Y1111834
X0454761Y1102221
X0454761Y1108630
X0456612Y1105426
X0458461Y1108630
X0451061Y1134264
X0449212Y1131060
X0449212Y1137769
X0452912Y1131060
X0452912Y1137769
X0445511Y1131060
X0438112Y1131060
X0439961Y1134264
X0441812Y1131060
X0443661Y1134264
X0445511Y1137769
X0438112Y1137769
X0441812Y1137769
X0451061Y1127856
X0443661Y1127856
X0439961Y1127856
X0451061Y1115039
X0449212Y1118243
X0449212Y1124651
X0451061Y1121447
X0452912Y1118243
X0452912Y1124651
X0443661Y1115039
X0445511Y1118243
X0439961Y1115039
X0441812Y1118243
X0438112Y1118243
X0443661Y1121447
X0445511Y1124651
X0441812Y1124651
X0439961Y1121447
X0438112Y1124651
X0449212Y1111834
X0452912Y1111834
X0445511Y1111834
X0438112Y1111834
X0441812Y1111834
X0449212Y1099017
X0451061Y1102221
X0449212Y1105426
X0451061Y1108630
X0452912Y1105426
X0445511Y1099017
X0443661Y1102221
X0438112Y1099017
X0441812Y1099017
X0439961Y1102221
X0445511Y1105426
X0443661Y1108630
X0439961Y1108630
X0438112Y1105426
X0441812Y1105426
X0447361Y1095813
X0443661Y1095813
X0439961Y1095813
X0449211Y1092608
X0438112Y1086200
X0447361Y1089404
X0445511Y1092608
X0443661Y1089404
X0438112Y1092608
X0441812Y1092608
X0439961Y1089404
X0445511Y1086200
X0441812Y1086200
X0432561Y1134264
X0436261Y1134264
X0421461Y1140973
X0425161Y1140973
X0428861Y1140973
X0421461Y1134264
X0425162Y1134264
X0427012Y1131060
X0428861Y1134264
X0430711Y1131060
X0427012Y1137569
X0430711Y1137769
X0432561Y1127856
X0436262Y1127856
X0421461Y1127856
X0425162Y1127856
X0428861Y1127856
X0432561Y1115039
X0432561Y1121447
X0436262Y1115039
X0436262Y1121447
X0425162Y1115039
X0427012Y1118243
X0428861Y1115039
X0430711Y1118243
X0421461Y1121447
X0425162Y1121447
X0427012Y1124651
X0428861Y1121447
X0430711Y1124651
X0427012Y1111834
X0430711Y1111834
X0434412Y1099017
X0432561Y1102221
X0432561Y1108630
X0436262Y1102221
X0436262Y1108630
X0428861Y1102221
X0430711Y1099017
X0430711Y1105426
X0425162Y1108630
X0427012Y1105426
X0428861Y1108630
X0436261Y1095813
X0436262Y1089404
X0417761Y1140973
X0417761Y1134264
X0419612Y1131060
X0419612Y1137469
X0414061Y1140973
X0415912Y1131060
X0415912Y1137469
X0417761Y1127856
X0417761Y1121447
X0419612Y1118243
X0419612Y1124651
X0415912Y1124651
X0462162Y1102221
X0467711Y1099017
X0452911Y1086200
X0423311Y1099017
X0421462Y1102221
X0406662Y1134264
X0417762Y1095813
X0404811Y1092608
X0399262Y1134264
X0391862Y1134264
X0391862Y1121447
X0393711Y1105426
X0391862Y1102221
X0377062Y1134264
X0384462Y1134264
X0377062Y1121447
X0384462Y1121447
X0382611Y1099017
X0380762Y1095813
X0388162Y1121447
X0384462Y1127856
X0380762Y1121447
X0377062Y1127856
X0373362Y1121447
X0410362Y1121447
X0406662Y1127856
X0402962Y1121447
X0399262Y1127856
X0393711Y1124651
X0391862Y1127856
X0386311Y1124651
X0382611Y1124651
X0378911Y1124651
X0375211Y1124651
X0408511Y1124651
X0404811Y1124651
X0401111Y1124651
X0397411Y1124651
X0395562Y1121447
X0390011Y1124651
X0386312Y1137469
X0382612Y1137469
X0378912Y1137469
X0375212Y1137469
X0408512Y1137469
X0404812Y1137469
X0401112Y1137469
X0397412Y1137469
X0393712Y1137469
X0390012Y1137469
X0388162Y1134264
X0384461Y1140973
X0380762Y1134264
X0377061Y1140973
X0373362Y1134264
X0410362Y1134264
X0406661Y1140973
X0402962Y1134264
X0399261Y1140973
X0395562Y1134264
X0391861Y1140973
X0471411Y1124651
X0469562Y1121447
X0419612Y1099017
X0375211Y1099017
X0397411Y1092608
X0390011Y1092608
X0393711Y1092608
X0386311Y1092608
X0388162Y1095813
X0390011Y1099017
X0382611Y1086200
X0380762Y1089404
X0375211Y1086200
X0393711Y1086200
X0395562Y1089404
X0390011Y1086200
X0388162Y1089404
X0395562Y1095813
X0393711Y1099017
X0377062Y1089404
X0469561Y1140973
X0471412Y1131060
X0471412Y1137469
X0458462Y1134264
X0447361Y1134264
X0434411Y1131060
X0434412Y1137769
X0423311Y1131060
X0423312Y1137469
X0404811Y1131060
X0408511Y1131060
X0410361Y1140973
X0412212Y1131060
X0414062Y1134264
X0401111Y1131060
X0402961Y1140973
X0388161Y1140973
X0390011Y1131060
X0393711Y1131060
X0395561Y1140973
X0397411Y1131060
X0386311Y1131060
X0373361Y1140973
X0375211Y1131060
X0378911Y1131060
X0380761Y1140973
X0382611Y1131060
X0469562Y1127856
X0469561Y1115039
X0471411Y1118243
X0458462Y1127856
X0465862Y1115039
X0465862Y1121447
X0467711Y1118243
X0467712Y1124651
X0458462Y1115039
X0458462Y1121447
X0447361Y1127856
X0447361Y1115039
X0447361Y1121447
X0434411Y1118243
X0434411Y1124651
X0421462Y1115039
X0423311Y1118243
X0423311Y1124651
X0410361Y1127856
X0417761Y1115039
X0404811Y1118243
X0406661Y1115039
X0408511Y1118243
X0410361Y1115039
X0412211Y1118243
X0412211Y1124651
X0414061Y1121447
X0415911Y1118243
X0402961Y1127856
X0388161Y1127856
X0395561Y1127856
X0401111Y1118243
X0388161Y1115039
X0390011Y1118243
X0393711Y1118243
X0395561Y1115039
X0397411Y1118243
X0373361Y1127856
X0380761Y1127856
X0384461Y1115039
X0386311Y1118243
X0373361Y1115039
X0375211Y1118243
X0377061Y1115039
X0378911Y1118243
X0382611Y1118243
X0471411Y1105426
X0469562Y1108630
X0471411Y1111834
X0469562Y1102221
X0471411Y1099017
X0467711Y1111834
X0467711Y1105426
X0464012Y1111834
X0465861Y1102221
X0465861Y1108630
X0462162Y1108630
X0464012Y1099017
X0464012Y1105426
X0456611Y1099017
X0458462Y1102221
X0460312Y1105426
X0452911Y1099017
X0447361Y1102221
X0447361Y1108630
X0434411Y1111834
X0423311Y1111834
X0434411Y1105426
X0421462Y1108630
X0423311Y1105426
X0425161Y1102221
X0427011Y1099017
X0404812Y1111834
X0417762Y1102221
X0404812Y1105426
X0406661Y1102221
X0406661Y1108630
X0410362Y1102221
X0412211Y1099017
X0414062Y1108630
X0415912Y1099017
X0390011Y1111834
X0397411Y1111834
X0401111Y1105426
X0388162Y1102221
X0388162Y1108630
X0390011Y1105426
X0395562Y1102221
X0397412Y1099017
X0399262Y1102221
X0384462Y1102221
X0386312Y1099017
X0373361Y1102221
X0373361Y1108630
X0377062Y1102221
X0378911Y1099017
X0380762Y1108630
X0469562Y1095813
X0469561Y1089404
X0467712Y1092608
X0467712Y1086200
X0464011Y1086200
X0460311Y1092608
X0456611Y1086200
X0451062Y1095813
X0449212Y1086200
X0451062Y1089404
X0452911Y1092608
X0432561Y1095813
X0421462Y1095813
X0428861Y1095813
X0434411Y1086200
X0434411Y1092608
X0432561Y1089404
X0425162Y1089404
X0406662Y1095813
X0410362Y1095813
X0417761Y1089404
X0408511Y1086200
X0412211Y1092608
X0415912Y1086200
X0415911Y1092608
X0402962Y1095813
X0391862Y1095813
X0399261Y1095813
X0401111Y1086200
X0401112Y1092608
X0391862Y1089404
X0397412Y1086200
X0399262Y1089404
X0384462Y1095813
X0373362Y1095813
X0384461Y1089404
X0386311Y1086200
X0373362Y1089404
X0375211Y1092608
X0378911Y1086200
X0378911Y1092608
X0382611Y1092608
X0458462Y1076587
X0451060Y1082995
X0454760Y1082995
X0430711Y1079791
X0428861Y1076587
X0406662Y1082995
X0410362Y1082995
X0414062Y1082995
X0425162Y1082995
X0402962Y1082995
X0408511Y1079791
X0430711Y1060565
X0428861Y1063770
X0427011Y1060565
X0423311Y1060565
X0419611Y1060565
X0430711Y1066974
X0428862Y1070178
X0425162Y1070178
X0414062Y1063770
X0419611Y1066974
X0412211Y1066974
X0421462Y1070178
X0417762Y1070178
X0414062Y1070178
X0415911Y1073383
X0412211Y1073383
X0425162Y1063770
X0417762Y1063770
X0451062Y1057361
X0454762Y1057361
X0460311Y1060565
X0458460Y1050952
X0454762Y1050952
X0402962Y1038136
X0464012Y1060565
X0458462Y1044544
X0462162Y1044544
X0464011Y1041340
X0401111Y1015705
X0464011Y1073383
X0451062Y1070178
X0456611Y1041340
X0451062Y1050952
X0452911Y1054157
X0465862Y1076587
X0421462Y1044544
X0402962Y1012501
X0401111Y1009297
X0456611Y1066974
X0454761Y1063770
X0457942Y1034409
X0458671Y1037069
X0463271Y1037069
X0460971Y1037069
X0457942Y1031909
X0449211Y1066974
X0452911Y1066974
X0451061Y1063770
X0471404Y1000080
X0471404Y0985580
X0453403Y1014499
X0461295Y1014510
X0458404Y1014540
X0468904Y1000080
X0453403Y1000699
X0461424Y1000080
X0458404Y1000080
X0453403Y1012199
X0453403Y0998399
X0468904Y0985580
X0453403Y0984599
X0458404Y0985580
X0461424Y0985580
X0453403Y0986899
X0439961Y1082995
X0443661Y1082995
X0445511Y1079791
X0438112Y1079791
X0441812Y1079791
X0445511Y1066974
X0438112Y1066974
X0441812Y1066974
X0445511Y1073383
X0443661Y1076587
X0443661Y1070178
X0438112Y1073383
X0441812Y1073383
X0439961Y1070178
X0439961Y1076587
X0443661Y1063770
X0439961Y1063770
X0443661Y1050952
X0439961Y1050952
X0445511Y1054157
X0445511Y1060565
X0443661Y1057361
X0441812Y1060565
X0441812Y1054157
X0439961Y1057361
X0438112Y1054157
X0438112Y1060565
X0438112Y1047749
X0441812Y1047749
X0445510Y1047749
X0449213Y1034932
X0449211Y1041340
X0451062Y1038137
X0441813Y1034932
X0438113Y1034932
X0445512Y1034932
X0445511Y1041340
X0447361Y1044544
X0443661Y1044544
X0441812Y1041340
X0439961Y1044544
X0438112Y1041340
X0443662Y1038137
X0439962Y1038137
X0451062Y1031728
X0443662Y1031728
X0439962Y1031728
X0449213Y1028524
X0451062Y1025319
X0449213Y1015706
X0451062Y1018911
X0449213Y1022115
X0438113Y1028524
X0441813Y1028524
X0445511Y1028524
X0439962Y1025319
X0443662Y1025319
X0443662Y1018911
X0441813Y1015706
X0439962Y1018911
X0438113Y1015706
X0445512Y1015706
X0441813Y1022115
X0438113Y1022115
X0445511Y1022115
X0451062Y1012502
X0443662Y1012502
X0439962Y1012502
X0451062Y0999685
X0449213Y1002889
X0449213Y1009298
X0451062Y1006094
X0443662Y0999685
X0439962Y0999685
X0441813Y1002889
X0438113Y1002889
X0445512Y1002889
X0441813Y1009298
X0438113Y1009298
X0445511Y1009298
X0443662Y1006094
X0439962Y1006094
X0436262Y1082995
X0436262Y1076587
X0436262Y1070178
X0436262Y1063770
X0436262Y1050952
X0436262Y1057361
X0434412Y1047749
X0432561Y1044544
X0434412Y1041340
X0432562Y1038137
X0436261Y1044544
X0436262Y1038137
X0423285Y1034584
X0423285Y1032284
X0427875Y1033604
X0430712Y1034932
X0430711Y1041340
X0423285Y1036884
X0432562Y1031728
X0436263Y1031728
X0427875Y1031304
X0427875Y1029004
X0436263Y1025319
X0432562Y1025319
X0432562Y1018911
X0436263Y1018911
X0430712Y1028524
X0427875Y1026704
X0430712Y1015706
X0430712Y1022115
X0432562Y1012502
X0436263Y1012502
X0423015Y1014470
X0427875Y1014452
X0432562Y0999685
X0432562Y1006094
X0436263Y0999685
X0436263Y1006094
X0422685Y1000060
X0427875Y0999821
X0430712Y1002889
X0427875Y1012152
X0430712Y1009298
X0427875Y0997521
X0427875Y0985411
X0422685Y0985580
X0420405Y1014470
X0420215Y1000040
X0410085Y1000080
X0412385Y1000080
X0420145Y0985550
X0410065Y0985610
X0412365Y0985610
X0469561Y1050952
X0469561Y1057361
X0469562Y1063770
X0471412Y1060565
X0470724Y1028827
X0467712Y1060565
X0467712Y1054157
X0425162Y1044544
X0423312Y1041340
X0419611Y1041340
X0415911Y1041340
X0412211Y1041340
X0469562Y1082995
X0462162Y1082995
X0465862Y1082995
X0458180Y1028855
X0460680Y1028855
X0463180Y1028855
X0465680Y1028855
X0423311Y1079791
X0421961Y1028855
X0415911Y1079791
X0419461Y1028855
X0416961Y1028855
X0411961Y1028855
X0414461Y1028855
X0399262Y1082995
X0404811Y1041340
X0411685Y1014540
X0407085Y1014540
X0409385Y1014540
X0401111Y1041340
X0402962Y1044544
X0399262Y1044544
X0399262Y1025318
X0402962Y1025318
X0402960Y1018910
X0401111Y1022114
X0458462Y1057361
X0460312Y1054157
X0471411Y1079791
X0471411Y1073383
X0462162Y1076587
X0410362Y1057361
X0454762Y1038136
X0460312Y1079791
X0464012Y1079791
X0454762Y1044544
X0469562Y1076587
X0408511Y1066974
X0414062Y1044544
X0414062Y1057361
X0404811Y1054157
X0408511Y1047749
X0402962Y1050952
X0410362Y1044544
X0412211Y1054157
X0410362Y1063770
X0406662Y1044544
X0408511Y1060565
X0406662Y1063770
X0401111Y1047749
X0419611Y1054157
X0421462Y1050952
X0428862Y1050952
X0401111Y1054157
X0423311Y1054157
X0425162Y1050952
X0421462Y1057361
X0417762Y1057361
X0419611Y1047749
X0414060Y1050952
X0415911Y1047749
X0471411Y1066974
X0469560Y1070178
X0399262Y1063770
X0401112Y1066974
X0432561Y1057361
X0428861Y1057361
X0401113Y1060565
X0402962Y1063770
X0465860Y1070178
X0464011Y1066974
X0462161Y1063770
X0460311Y1066974
X0458460Y1070178
X0460311Y1073383
X0417762Y1076587
X0449213Y1060565
X0402962Y1057361
X0469562Y1044544
X0449211Y1054157
X0452911Y1047749
X0467711Y1041340
X0471411Y1041340
X0427012Y1041340
X0401111Y1028523
X0382611Y1009297
X0380762Y1012501
X0375211Y1009297
X0377062Y1012501
X0397411Y1034931
X0397411Y1054157
X0397411Y1073383
X0380762Y1082995
X0390011Y1034931
X0390011Y1054157
X0390011Y1073383
X0377062Y1082995
X0393711Y1034931
X0393711Y1054157
X0393711Y1073383
X0384462Y1082995
X0386311Y1034931
X0386311Y1054157
X0386311Y1073383
X0373362Y1082995
X0380762Y1076587
X0382611Y1079791
X0377062Y1076587
X0375211Y1079791
X0393711Y1047749
X0395562Y1050952
X0390011Y1047749
X0388162Y1050952
X0395562Y1057361
X0393711Y1060565
X0388162Y1057361
X0390011Y1060565
X0393711Y1066974
X0395562Y1070178
X0390011Y1066974
X0388162Y1070178
X0395562Y1076587
X0393711Y1079791
X0388162Y1076587
X0390011Y1079791
X0395562Y1018910
X0393711Y1022114
X0388162Y1018910
X0390011Y1022114
X0393711Y1028523
X0395562Y1031727
X0390011Y1028523
X0388162Y1031727
X0395562Y1038136
X0393711Y1041340
X0388162Y1038136
X0390011Y1041340
X0393711Y1009297
X0390011Y1009297
X0395562Y1012501
X0388162Y1012501
X0397411Y1015705
X0386311Y1015705
X0402962Y0999684
X0380762Y0999684
X0382611Y1002888
X0377062Y0999684
X0375211Y1002888
X0380760Y1025318
X0384462Y1044544
X0380762Y1063770
X0373360Y1025318
X0377062Y1044544
X0377062Y1063770
X0384462Y1025318
X0380762Y1044544
X0384462Y1063770
X0377062Y1025318
X0373362Y1044544
X0373362Y1063770
X0375211Y1066974
X0377062Y1070178
X0380762Y1038136
X0382611Y1041340
X0377062Y1038136
X0375211Y1041340
X0382611Y1047749
X0380762Y1050952
X0375211Y1047749
X0377062Y1050952
X0380762Y1057361
X0382611Y1060565
X0377062Y1057361
X0375211Y1060565
X0382611Y1066974
X0380762Y1070178
X0380762Y1018910
X0382611Y1022114
X0377062Y1018910
X0375211Y1022114
X0382611Y1028523
X0380762Y1031727
X0375211Y1028523
X0377062Y1031727
X0384462Y1006093
X0377062Y1006093
X0380762Y1006093
X0373362Y1006093
X0399262Y0999684
X0395562Y0999684
X0393711Y1002888
X0388162Y0999684
X0390011Y1002888
X0402962Y1006093
X0399262Y1006093
X0427011Y1047749
X0458461Y1082995
X0447361Y1082995
X0432561Y1082995
X0421462Y1082995
X0428861Y1082995
X0417761Y1082995
X0388161Y1082995
X0391862Y1082995
X0395562Y1082995
X0467711Y1079791
X0456612Y1079791
X0467711Y1066974
X0467711Y1073383
X0462162Y1070178
X0454762Y1070178
X0456611Y1073383
X0454761Y1076587
X0449211Y1079791
X0452911Y1079791
X0449211Y1073383
X0447361Y1070178
X0447361Y1076587
X0434411Y1079791
X0427012Y1079791
X0434411Y1066974
X0434411Y1073383
X0432561Y1076587
X0423311Y1066974
X0425162Y1076587
X0427011Y1066974
X0427011Y1073383
X0430711Y1073383
X0404811Y1079791
X0412211Y1079791
X0419611Y1073383
X0404811Y1066974
X0406661Y1076587
X0410362Y1070178
X0410362Y1076587
X0415911Y1066974
X0401111Y1079791
X0397411Y1079791
X0401111Y1073383
X0391862Y1070178
X0391862Y1076587
X0397412Y1066974
X0399262Y1070178
X0399261Y1076587
X0386311Y1079791
X0378911Y1079791
X0384461Y1070178
X0384462Y1076587
X0386311Y1066974
X0373362Y1070178
X0373361Y1076587
X0375211Y1073383
X0378911Y1066974
X0378911Y1073383
X0382612Y1073383
X0471411Y1054157
X0465862Y1063770
X0458462Y1063770
X0465862Y1057361
X0462162Y1050952
X0456611Y1054157
X0447361Y1063770
X0452911Y1060565
X0447361Y1050952
X0447361Y1057361
X0421462Y1063770
X0434411Y1054157
X0434411Y1060565
X0432561Y1050952
X0425162Y1057361
X0417761Y1050952
X0404811Y1060565
X0408511Y1054157
X0410361Y1050952
X0412211Y1060565
X0415911Y1054157
X0415911Y1060565
X0388161Y1063770
X0391862Y1063770
X0395562Y1063770
X0391862Y1050952
X0391862Y1057361
X0397411Y1060565
X0399262Y1050952
X0399261Y1057361
X0384461Y1050952
X0384462Y1057361
X0386312Y1060565
X0373362Y1050952
X0373361Y1057361
X0375211Y1054157
X0378911Y1054157
X0378911Y1060565
X0382612Y1054157
X0471411Y1047749
X0464011Y1047749
X0456611Y1047749
X0465861Y1044544
X0467372Y1036874
X0471282Y1036526
X0460311Y1041340
X0449211Y1047749
X0451061Y1044544
X0452911Y1041340
X0447360Y1038136
X0423311Y1047749
X0430712Y1047749
X0434412Y1034932
X0428862Y1044544
X0404811Y1047749
X0412211Y1047749
X0417762Y1044544
X0408511Y1041340
X0397411Y1047749
X0388161Y1044544
X0391862Y1038136
X0391862Y1044544
X0395562Y1044544
X0397411Y1041340
X0399261Y1038136
X0386311Y1047749
X0378911Y1047749
X0384462Y1038136
X0386312Y1041340
X0373361Y1038136
X0375211Y1034931
X0378911Y1034931
X0378911Y1041340
X0382612Y1034931
X0447362Y1031728
X0447362Y1018911
X0447362Y1025319
X0434412Y1015706
X0434411Y1022115
X0434411Y1028524
X0391862Y1031727
X0399262Y1031727
X0388161Y1025318
X0390012Y1015705
X0391862Y1018910
X0391862Y1025318
X0393711Y1015705
X0395562Y1025318
X0397411Y1022114
X0397411Y1028523
X0399261Y1018910
X0384461Y1031727
X0373362Y1031727
X0384462Y1018910
X0386312Y1022114
X0386311Y1028523
X0373361Y1018910
X0375211Y1015705
X0378911Y1015705
X0378911Y1022114
X0378911Y1028523
X0382612Y1015705
X0447362Y1012502
X0447362Y0999685
X0447362Y1006094
X0434412Y1002889
X0434411Y1009298
X0391861Y1012501
X0399262Y1012501
X0401111Y1002888
X0388161Y1006093
X0391862Y0999684
X0391862Y1006093
X0395562Y1006093
X0397411Y1002888
X0397412Y1009297
X0384461Y1012501
X0373362Y1012501
X0384462Y0999684
X0386312Y1002888
X0386311Y1009297
X0378911Y1002888
X0378911Y1009297
X0373361Y0999684
X0375210Y0996480
X0463874Y0985580
X0466272Y0985580
X0454463Y0992999
X0454463Y0995299
X0468895Y1014550
X0463874Y1000060
X0466272Y1000060
X0454443Y1007109
X0454443Y1009409
X0463874Y1014540
X0466272Y1014540
X0454434Y1019886
X0454434Y1022186
X0471204Y1014540
X0417575Y0985580
X0415185Y0985580
X0404861Y0988721
X0405101Y0995271
X0405101Y0992971
X0404861Y0986421
X0415185Y1000060
X0417575Y1000060
X0405231Y1004848
X0405227Y1007156
X0417575Y1014540
X0415185Y1014540
X0404998Y1026821
X0404986Y1022427
X0408325Y1034271
X0408325Y1031971
X0426905Y0992422
X0426905Y0994722
X0426905Y1009175
X0426905Y1006875
X0426905Y1019663
X0426905Y1021963
X0404811Y1073383
X0406662Y1070178
X0402962Y1070178
X0402962Y1076587
X0408511Y1073383
X0462161Y1057361
X0402962Y1031727
X0456611Y1060565
X0421462Y1076587
X0419611Y1079791
X0430711Y1054157
X0406662Y1050952
X0427011Y1054157
X0460311Y1047750
X0452911Y1073383
X0451061Y1076587
X0432560Y1070178
X0423311Y1073383
X0406662Y1057361
X0467711Y1047750
X0465860Y1050952
X0464011Y1054157
X0433979Y0912262
X0435830Y0928283
X0437679Y0925079
X0439530Y0928283
X0445079Y0925079
X0439530Y0934692
X0445079Y0931487
X0443230Y0934692
X0448780Y0925079
X0450630Y0928283
X0432130Y0934692
X0430279Y0931487
X0432130Y0928283
X0430279Y0925079
X0435830Y0934692
X0437679Y0931487
X0448780Y0931487
X0443230Y0928283
X0446930Y0934692
X0469129Y0909057
X0411779Y0918670
X0415479Y0918670
X0459878Y0912262
X0463578Y0912262
X0459878Y0918670
X0454329Y0915466
X0448779Y0918670
X0458029Y0915466
X0452478Y0912262
X0470978Y0899445
X0452478Y0918670
X0450629Y0915466
X0458029Y0921875
X0465429Y0921875
X0463578Y0918670
X0469129Y0921875
X0404378Y0899445
X0461729Y0909057
X0467278Y0905853
X0470978Y0905853
X0461729Y0915466
X0465429Y0896240
X0463578Y0899445
X0458029Y0896240
X0456178Y0899445
X0450630Y0896240
X0448778Y0899445
X0443229Y0896240
X0445078Y0899445
X0467278Y0893036
X0461729Y0896240
X0459878Y0893036
X0454329Y0896240
X0452479Y0893036
X0446929Y0896240
X0445078Y0893036
X0441378Y0899445
X0435829Y0896240
X0433978Y0899445
X0428429Y0896240
X0426578Y0899445
X0421029Y0896240
X0419178Y0899445
X0413629Y0896240
X0411778Y0899445
X0437678Y0893036
X0432129Y0896240
X0430278Y0893036
X0424729Y0896240
X0422878Y0893036
X0417329Y0896240
X0415478Y0893036
X0409929Y0896240
X0417329Y0915466
X0415478Y0912262
X0411778Y0912262
X0459878Y0905853
X0415478Y0905853
X0426578Y0918670
X0411872Y0925264
X0417329Y0921875
X0421029Y0921875
X0422878Y0918670
X0424729Y0921875
X0443229Y0921875
X0445078Y0918670
X0402529Y0902649
X0425676Y0929465
X0422427Y0927255
X0423176Y0929465
X0424927Y0927255
X0422878Y0899445
X0430278Y0899445
X0415478Y0899445
X0408078Y0899445
X0471404Y0956620
X0453403Y0970799
X0453403Y0973099
X0461424Y0971140
X0458404Y0971100
X0468904Y0956620
X0453403Y0959299
X0458404Y0956620
X0461424Y0956620
X0453403Y0956999
X0453585Y0944538
X0453585Y0939938
X0453585Y0942238
X0450630Y0979553
X0448780Y0982757
X0443229Y0979553
X0439529Y0979553
X0441380Y0982757
X0437680Y0982757
X0445079Y0982757
X0448780Y0969940
X0448780Y0976348
X0450630Y0973144
X0441380Y0969940
X0437680Y0969940
X0441380Y0976348
X0437680Y0976348
X0443229Y0973144
X0439529Y0973144
X0445079Y0969940
X0445079Y0976348
X0450630Y0966736
X0448780Y0963531
X0443229Y0966736
X0439529Y0966736
X0441380Y0963531
X0437680Y0963531
X0445079Y0963531
X0448780Y0950714
X0450630Y0960327
X0450630Y0953918
X0448780Y0957123
X0445079Y0950714
X0441380Y0950714
X0437680Y0950714
X0439529Y0953918
X0443229Y0953918
X0443229Y0960327
X0439529Y0960327
X0441380Y0957123
X0437680Y0957123
X0445079Y0957123
X0450630Y0947510
X0439529Y0947510
X0443229Y0947510
X0448780Y0944305
X0450630Y0941101
X0439530Y0941101
X0445079Y0944305
X0443230Y0941101
X0441380Y0944305
X0437680Y0944305
X0435830Y0979553
X0427875Y0983111
X0432129Y0979553
X0430280Y0982757
X0435830Y0973144
X0427875Y0968967
X0422685Y0971100
X0427875Y0971267
X0430280Y0969940
X0432129Y0973144
X0430268Y0976348
X0435830Y0966736
X0430280Y0963531
X0432129Y0966736
X0435830Y0953918
X0435830Y0960327
X0430280Y0950714
X0432129Y0953918
X0432129Y0960327
X0430280Y0957123
X0425185Y0956620
X0422685Y0956620
X0427875Y0954073
X0427875Y0956373
X0435830Y0947510
X0432129Y0947510
X0435830Y0941101
X0432130Y0941101
X0430280Y0944305
X0427875Y0944230
X0427875Y0941930
X0420205Y0971100
X0417685Y0956620
X0409385Y0956620
X0411685Y0956620
X0415185Y0956620
X0470536Y0928349
X0459036Y0928349
X0461336Y0928349
X0463636Y0928349
X0465936Y0928349
X0468236Y0928349
X0467278Y0899445
X0459878Y0899445
X0467278Y0886627
X0459878Y0886627
X0452478Y0899445
X0445078Y0886627
X0452478Y0886627
X0430278Y0886627
X0422878Y0886627
X0406229Y0896240
X0408078Y0886627
X0415478Y0886627
X0471550Y0942152
X0469251Y0942246
X0409889Y0942164
X0405289Y0942164
X0407589Y0942164
X0400678Y0886627
X0393278Y0886627
X0385878Y0886627
X0378478Y0886627
X0471404Y0971100
X0468904Y0971100
X0411685Y0971100
X0409385Y0971100
X0407085Y0971100
X0404785Y0971100
X0400680Y0950713
X0402529Y0953917
X0398829Y0953917
X0402529Y0947509
X0406229Y0902649
X0408078Y0912262
X0435829Y0921875
X0400678Y0912262
X0400678Y0893036
X0421029Y0915466
X0443229Y0915466
X0458029Y0909057
X0404378Y0893036
X0398829Y0896240
X0441378Y0886627
X0448778Y0886627
X0456178Y0886627
X0463578Y0886627
X0419178Y0886627
X0426578Y0886627
X0433978Y0886627
X0470978Y0886627
X0389578Y0886627
X0382178Y0886627
X0374778Y0886627
X0411778Y0886627
X0404378Y0886627
X0396978Y0886627
X0406308Y0928626
X0408569Y0929108
X0408078Y0905853
X0411778Y0905853
X0469129Y0915466
X0467278Y0912262
X0470978Y0918670
X0445080Y0912262
X0439529Y0909057
X0396979Y0893036
X0393279Y0893036
X0402529Y0960326
X0402529Y0966735
X0408078Y0918670
X0406229Y0915466
X0441380Y0912262
X0448780Y0912262
X0448779Y0905853
X0452479Y0905853
X0426578Y0905853
X0430278Y0905853
X0450630Y0909057
X0454329Y0909057
X0450629Y0921875
X0422878Y0905853
X0424728Y0909057
X0433978Y0905853
X0432128Y0909057
X0441379Y0905853
X0445079Y0905853
X0400679Y0944304
X0402529Y0941100
X0384029Y0973143
X0389578Y0963530
X0396978Y0905853
X0384029Y0915466
X0396978Y0925079
X0396978Y0944304
X0393278Y0963530
X0389578Y0905853
X0376629Y0915466
X0389578Y0925079
X0389578Y0944304
X0385878Y0963530
X0393278Y0905853
X0380329Y0915466
X0393278Y0925079
X0393278Y0944304
X0396978Y0963530
X0385878Y0905853
X0372929Y0915466
X0385878Y0925079
X0385878Y0944304
X0387729Y0928283
X0389578Y0931488
X0393278Y0937896
X0395129Y0941100
X0389578Y0937896
X0387729Y0941100
X0395129Y0947509
X0393278Y0899445
X0395129Y0902649
X0393278Y0950713
X0389578Y0899445
X0387729Y0902649
X0395129Y0909057
X0393278Y0912262
X0387729Y0909057
X0389578Y0912262
X0380329Y0909057
X0382178Y0912262
X0376629Y0909057
X0374778Y0912262
X0387729Y0947509
X0382178Y0918670
X0380329Y0921875
X0374778Y0918670
X0376629Y0921875
X0393278Y0918670
X0395129Y0921875
X0389578Y0918670
X0387729Y0921875
X0395129Y0928283
X0393278Y0931488
X0389578Y0950713
X0376629Y0966735
X0380329Y0966735
X0382178Y0969939
X0374778Y0969939
X0395129Y0966735
X0393278Y0969939
X0387729Y0966735
X0389578Y0969939
X0393278Y0957122
X0395129Y0960326
X0389578Y0957122
X0387729Y0960326
X0372929Y0973143
X0382178Y0976347
X0374778Y0976347
X0380329Y0979552
X0376629Y0979552
X0389579Y0976347
X0387729Y0979552
X0395129Y0979552
X0393278Y0976347
X0396978Y0982756
X0389578Y0982756
X0393278Y0982756
X0385878Y0982756
X0384029Y0896240
X0384029Y0934691
X0384029Y0953917
X0376629Y0896240
X0376629Y0934691
X0376629Y0953917
X0380329Y0896240
X0380329Y0934691
X0380329Y0953917
X0372929Y0896240
X0372929Y0934691
X0372929Y0953917
X0374778Y0937896
X0376629Y0941100
X0380329Y0947509
X0382178Y0950713
X0376629Y0947509
X0374778Y0950713
X0382178Y0957122
X0385878Y0893036
X0374778Y0893036
X0380329Y0960326
X0382178Y0893036
X0382178Y0899445
X0380329Y0902649
X0374778Y0899445
X0376629Y0902649
X0374778Y0957122
X0380329Y0928283
X0382178Y0931488
X0376629Y0928283
X0374778Y0931488
X0382178Y0937896
X0380329Y0941100
X0376629Y0960326
X0402529Y0973143
X0402529Y0979552
X0400678Y0976347
X0398829Y0973143
X0433979Y0918670
X0439529Y0915466
X0435829Y0915466
X0441378Y0918670
X0443229Y0909057
X0435829Y0909057
X0413629Y0915466
X0421029Y0909057
X0400678Y0899445
X0402529Y0909057
X0432129Y0921875
X0469129Y0902649
X0402529Y0896240
X0402529Y0915466
X0454329Y0921875
X0400678Y0905853
X0413629Y0909057
X0406229Y0909057
X0417329Y0909057
X0432129Y0915466
X0430278Y0912262
X0467278Y0918670
X0454263Y0978909
X0454263Y0981209
X0446930Y0973144
X0446930Y0979553
X0433980Y0982757
X0433980Y0969940
X0433980Y0976348
X0400678Y0969939
X0400678Y0982756
X0404861Y0978969
X0404861Y0981269
X0426905Y0978036
X0426905Y0980336
X0391429Y0973143
X0391429Y0979552
X0395129Y0973143
X0396979Y0969939
X0396978Y0976347
X0398828Y0979552
X0446930Y0966736
X0446930Y0953918
X0446930Y0960327
X0433980Y0963531
X0433980Y0950714
X0433980Y0957123
X0400678Y0963530
X0391429Y0966735
X0398829Y0966735
X0400678Y0957122
X0391429Y0953917
X0391429Y0960326
X0395129Y0953917
X0396979Y0950713
X0396978Y0957122
X0398828Y0960326
X0454423Y0949139
X0454423Y0951439
X0466272Y0956540
X0463874Y0956540
X0454393Y0966129
X0454393Y0963829
X0463874Y0971140
X0466272Y0971100
X0446930Y0947510
X0446929Y0941101
X0433980Y0944305
X0391429Y0947509
X0398829Y0947509
X0400678Y0937896
X0391429Y0934691
X0391429Y0941100
X0395129Y0934691
X0396978Y0937896
X0398828Y0941100
X0387728Y0934691
X0385879Y0937896
X0378478Y0937896
X0378478Y0944304
X0382179Y0944304
X0372928Y0941100
X0372929Y0947509
X0374778Y0944304
X0384028Y0947509
X0384029Y0941100
X0378478Y0950713
X0385878Y0950713
X0384028Y0966735
X0385879Y0957122
X0384029Y0960326
X0378478Y0957122
X0378478Y0963530
X0382179Y0963530
X0372929Y0966735
X0374778Y0963530
X0372928Y0960326
X0387729Y0953917
X0372928Y0979552
X0378478Y0982756
X0382179Y0982756
X0374778Y0982756
X0385878Y0969939
X0384029Y0979552
X0385879Y0976347
X0378478Y0969939
X0378479Y0976347
X0380328Y0973143
X0376629Y0973143
X0387728Y0973143
X0456178Y0918670
X0461729Y0921875
X0437678Y0918670
X0446929Y0921875
X0428429Y0921875
X0405048Y0930812
X0418693Y0942098
X0416393Y0942098
X0405048Y0935746
X0405048Y0938046
X0414093Y0942098
X0405145Y0948539
X0405145Y0946239
X0405122Y0963596
X0405122Y0965896
X0416755Y0971140
X0414365Y0971140
X0433980Y0931487
X0433980Y0925079
X0427875Y0936470
X0426875Y0949499
X0426875Y0947199
X0433979Y0937897
X0430279Y0937897
X0426905Y0963635
X0426905Y0965935
X0441379Y0931487
X0441379Y0925079
X0446930Y0928283
X0448779Y0937897
X0437679Y0937897
X0445079Y0937897
X0441379Y0937897
X0454103Y0933659
X0454103Y0931359
X0466861Y0942152
X0464561Y0942152
X0462261Y0942152
X0419178Y0918670
X0418229Y0926896
X0404378Y0918670
X0409929Y0921875
X0396979Y0931488
X0400678Y0925079
X0391429Y0921875
X0391429Y0928283
X0396978Y0918670
X0398828Y0921875
X0398829Y0928283
X0385878Y0931488
X0378478Y0931488
X0384029Y0921875
X0384028Y0928283
X0385879Y0918670
X0372928Y0921875
X0372929Y0928283
X0374778Y0925079
X0378478Y0918670
X0378478Y0925079
X0382179Y0925079
X0465429Y0915466
X0465429Y0909057
X0465429Y0902649
X0454329Y0902649
X0456178Y0905853
X0456178Y0912262
X0458029Y0902649
X0461729Y0902649
X0446929Y0915466
X0450629Y0902649
X0437679Y0905853
X0437678Y0912262
X0439528Y0902649
X0443229Y0902649
X0446929Y0902649
X0446929Y0909057
X0428429Y0915466
X0435829Y0902649
X0421029Y0902649
X0428429Y0902649
X0428429Y0909057
X0432129Y0902649
X0409929Y0915466
X0417329Y0902649
X0419179Y0905853
X0419178Y0912262
X0404378Y0905853
X0404378Y0912262
X0409929Y0902649
X0409929Y0909057
X0413629Y0902649
X0391429Y0915466
X0395129Y0915466
X0391429Y0902649
X0391429Y0909057
X0396979Y0912262
X0398828Y0902649
X0398829Y0909057
X0387728Y0915466
X0384029Y0902649
X0384028Y0909057
X0385878Y0912262
X0372928Y0902649
X0372929Y0909057
X0374778Y0905853
X0378478Y0905853
X0378478Y0912262
X0382179Y0905853
X0470979Y0893036
X0465429Y0889832
X0469129Y0889832
X0469129Y0896240
X0463579Y0893036
X0454329Y0889832
X0456179Y0893036
X0458029Y0889832
X0461729Y0889832
X0437679Y0899445
X0450629Y0889832
X0437678Y0886627
X0439529Y0889832
X0439529Y0896240
X0441379Y0893036
X0443229Y0889832
X0446929Y0889832
X0448779Y0893036
X0435829Y0889832
X0433979Y0893036
X0421029Y0889832
X0424729Y0889832
X0426579Y0893036
X0428429Y0889832
X0432129Y0889832
X0417329Y0889832
X0419179Y0893036
X0406229Y0889832
X0408079Y0893036
X0409929Y0889832
X0411779Y0893036
X0413629Y0889832
X0396978Y0899445
X0402529Y0889832
X0389579Y0893036
X0391429Y0889832
X0391428Y0896240
X0395129Y0889832
X0395129Y0896240
X0398829Y0889832
X0385879Y0899445
X0378478Y0899445
X0387729Y0889832
X0387729Y0896240
X0384029Y0889832
X0372929Y0889832
X0376629Y0889832
X0378479Y0893036
X0380329Y0889832
X0424729Y0902649
X0439529Y0921875
X0430278Y0918670
X0426578Y0912262
X0424729Y0915466
X0422878Y0912262
X0406229Y0921875
X0402529Y0921875
X0470980Y0912262
X0463578Y0905853
X0402529Y0928283
X0400678Y0931488
X0402529Y0934691
X0398829Y0934691
X0445078Y0873810
X0452479Y0873810
X0400678Y0873810
X0408078Y0873810
X0437679Y0873810
X0430278Y0873810
X0441378Y0860993
X0446929Y0857789
X0448779Y0860993
X0454329Y0857789
X0456178Y0860993
X0461729Y0857789
X0463578Y0860993
X0469129Y0857789
X0470978Y0860993
X0443229Y0857789
X0445078Y0854584
X0450629Y0857789
X0452478Y0854584
X0458029Y0857789
X0459878Y0854584
X0465429Y0857789
X0467278Y0854584
X0382178Y0848176
X0378479Y0841467
X0374778Y0848176
X0372927Y0844971
X0437678Y0848176
X0430278Y0848176
X0426578Y0848176
X0422879Y0841467
X0419178Y0848176
X0415479Y0841467
X0411778Y0848176
X0408079Y0841467
X0404378Y0848176
X0402527Y0844971
X0396978Y0848176
X0393279Y0841467
X0389578Y0848176
X0385879Y0841467
X0384027Y0844971
X0380327Y0844971
X0376627Y0844971
X0435829Y0844671
X0433978Y0848176
X0428427Y0844971
X0424727Y0844971
X0421027Y0844971
X0417327Y0844971
X0413627Y0844971
X0409927Y0844971
X0406227Y0844971
X0400679Y0841467
X0398827Y0844971
X0395127Y0844971
X0391427Y0844971
X0387727Y0844971
X0385878Y0854584
X0382178Y0860993
X0376629Y0857789
X0374778Y0860993
X0435829Y0857789
X0432129Y0857789
X0428429Y0857789
X0426578Y0860993
X0421029Y0857789
X0419178Y0860993
X0413629Y0857789
X0411778Y0860993
X0406229Y0857789
X0404378Y0860993
X0398829Y0857789
X0396978Y0860993
X0391429Y0857789
X0389578Y0860993
X0384029Y0857789
X0380329Y0857789
X0378478Y0854584
X0372929Y0857789
X0437679Y0854584
X0433979Y0860993
X0430278Y0854584
X0424729Y0857789
X0422878Y0854584
X0417329Y0857789
X0415478Y0854584
X0409929Y0857789
X0408078Y0854584
X0402529Y0857789
X0400678Y0854584
X0395129Y0857789
X0393278Y0854584
X0387729Y0857789
X0443227Y0844671
X0448778Y0848176
X0452479Y0841467
X0456178Y0848176
X0461727Y0844971
X0465427Y0844971
X0469127Y0844971
X0446927Y0844671
X0450628Y0844971
X0454327Y0844971
X0458027Y0844971
X0459879Y0841467
X0463578Y0848176
X0467279Y0841467
X0470978Y0848176
X0459878Y0873810
X0467278Y0873810
X0467278Y0860993
X0459878Y0860993
X0467278Y0848176
X0459878Y0848176
X0393278Y0873810
X0393278Y0860993
X0385878Y0873810
X0378478Y0873810
X0385878Y0860993
X0378478Y0860993
X0393278Y0848176
X0378478Y0848176
X0385878Y0848176
X0452479Y0860993
X0445078Y0860993
X0422878Y0873810
X0422878Y0860993
X0430278Y0860993
X0422878Y0848176
X0415478Y0873810
X0408078Y0860993
X0415478Y0860993
X0415478Y0848176
X0408078Y0848176
X0400678Y0860993
X0400678Y0848176
X0435829Y0883423
X0443229Y0883423
X0450629Y0883423
X0458029Y0883423
X0465429Y0883423
X0413629Y0883423
X0421029Y0883423
X0428429Y0883423
X0437678Y0880219
X0439529Y0883423
X0445078Y0880219
X0446929Y0883423
X0452479Y0880219
X0454329Y0883423
X0459878Y0880219
X0461729Y0883423
X0467278Y0880219
X0415478Y0880219
X0417329Y0883423
X0422878Y0880219
X0424729Y0883423
X0430278Y0880219
X0432129Y0883423
X0469129Y0883423
X0435829Y0870606
X0437678Y0867401
X0443229Y0870606
X0445078Y0867401
X0450629Y0870606
X0452478Y0867401
X0458029Y0870606
X0459878Y0867401
X0465429Y0870606
X0413629Y0870606
X0415478Y0867401
X0421029Y0870606
X0422878Y0867401
X0428429Y0870606
X0430278Y0867401
X0467278Y0867401
X0433979Y0873810
X0439529Y0870606
X0441378Y0873810
X0446929Y0870606
X0448779Y0873810
X0454329Y0870606
X0456178Y0873810
X0461729Y0870606
X0463578Y0873810
X0411778Y0873810
X0417329Y0870606
X0419178Y0873810
X0424729Y0870606
X0426578Y0873810
X0432129Y0870606
X0469129Y0870606
X0384029Y0883423
X0376629Y0883423
X0406229Y0883423
X0398829Y0883423
X0391429Y0883423
X0387729Y0883423
X0385878Y0880219
X0380329Y0883423
X0378478Y0880219
X0372929Y0883423
X0409929Y0883423
X0408078Y0880219
X0402529Y0883423
X0400678Y0880219
X0395129Y0883423
X0393278Y0880219
X0384029Y0870606
X0382178Y0873810
X0376629Y0870606
X0374778Y0873810
X0406229Y0870606
X0404378Y0873810
X0398829Y0870606
X0396978Y0873810
X0393278Y0867401
X0389578Y0873810
X0385878Y0867401
X0380329Y0870606
X0378478Y0867401
X0372929Y0870606
X0408078Y0867401
X0402529Y0870606
X0400678Y0867401
X0395129Y0870606
X0391429Y0870606
X0387729Y0870606
X0470979Y0873810
X0470979Y0880219
X0465429Y0877014
X0469129Y0877014
X0463579Y0880219
X0454329Y0877014
X0456179Y0880219
X0458029Y0877014
X0461729Y0877014
X0450629Y0877014
X0439529Y0877014
X0441379Y0880219
X0443229Y0877014
X0446929Y0877014
X0448779Y0880219
X0435829Y0877014
X0433979Y0880219
X0421029Y0877014
X0424729Y0877014
X0426579Y0880219
X0428429Y0877014
X0432129Y0877014
X0417329Y0877014
X0419179Y0880219
X0406229Y0877014
X0409929Y0870606
X0409929Y0877014
X0411779Y0880219
X0413629Y0877014
X0404379Y0880219
X0402529Y0877014
X0389579Y0880219
X0391429Y0877014
X0395129Y0877014
X0396979Y0880219
X0398829Y0877014
X0387729Y0877014
X0384029Y0877014
X0372929Y0877014
X0374779Y0880219
X0376629Y0877014
X0380329Y0877014
X0382179Y0880219
X0470979Y0867401
X0470979Y0854584
X0463579Y0867401
X0456179Y0867401
X0465429Y0864197
X0469129Y0864197
X0454329Y0864197
X0458029Y0864197
X0461729Y0864197
X0441379Y0867401
X0448779Y0867401
X0450629Y0864197
X0437680Y0860992
X0439528Y0857789
X0439529Y0864197
X0441379Y0854584
X0443229Y0864197
X0446929Y0864197
X0448779Y0854584
X0433979Y0867401
X0426579Y0867401
X0435829Y0864197
X0433979Y0854584
X0421029Y0864197
X0424729Y0864197
X0426579Y0854584
X0428429Y0864197
X0432129Y0864197
X0419179Y0867401
X0411779Y0867401
X0404379Y0867401
X0417329Y0864197
X0419179Y0854584
X0406229Y0864197
X0409929Y0864197
X0411779Y0854584
X0413629Y0864197
X0404379Y0854584
X0389579Y0867401
X0396979Y0867401
X0402529Y0864197
X0389579Y0854584
X0391429Y0864197
X0395129Y0864197
X0396979Y0854584
X0398829Y0864197
X0374779Y0867401
X0382179Y0867401
X0387729Y0864197
X0384029Y0864197
X0372929Y0864197
X0374779Y0854584
X0376629Y0864197
X0380329Y0864197
X0382179Y0854584
X0470979Y0841467
X0465429Y0851380
X0469129Y0851380
X0463579Y0841467
X0450629Y0851380
X0439529Y0851380
X0443228Y0851380
X0446929Y0851380
X0439529Y0844671
X0441378Y0848176
X0445078Y0848176
X0435829Y0851380
X0421029Y0851380
X0424729Y0851380
X0428429Y0851380
X0432129Y0851380
X0417329Y0851380
X0406229Y0851380
X0409929Y0851380
X0413629Y0851380
X0402529Y0851380
X0391429Y0851380
X0395129Y0851380
X0398829Y0851380
X0389579Y0841467
X0396979Y0841467
X0411779Y0841467
X0404379Y0841467
X0419179Y0841467
X0426579Y0841467
X0432128Y0844671
X0452478Y0848176
X0456179Y0841467
X0454328Y0851380
X0458029Y0851380
X0461729Y0851380
X0463579Y0854584
X0456179Y0854584
X0387729Y0851380
X0384029Y0851380
X0372929Y0851380
X0376629Y0851380
X0380329Y0851380
X0374779Y0841467
X0382179Y0841467
X0493178Y0860993
X0496878Y0854584
X0502429Y0857789
X0504278Y0854584
X0507978Y0860993
X0511678Y0854584
X0515378Y0860993
X0519078Y0854584
X0524629Y0857789
X0476529Y0857789
X0478378Y0860993
X0483929Y0857789
X0485778Y0860993
X0491329Y0857789
X0526478Y0854584
X0495029Y0857789
X0498729Y0857789
X0500578Y0860993
X0506129Y0857789
X0509829Y0857789
X0513529Y0857789
X0517229Y0857789
X0520929Y0857789
X0522778Y0860993
X0472829Y0857789
X0474678Y0854584
X0480229Y0857789
X0482078Y0854584
X0487629Y0857789
X0489478Y0854584
X0528329Y0857789
X0498727Y0844971
X0502427Y0844971
X0506127Y0844971
X0507978Y0848176
X0513527Y0844971
X0515378Y0848176
X0520927Y0844971
X0522778Y0848176
X0530178Y0848176
X0472827Y0844971
X0474679Y0841467
X0478378Y0848176
X0482079Y0841467
X0485778Y0848176
X0491327Y0844971
X0495027Y0844971
X0533878Y0848176
X0496878Y0841467
X0500578Y0848176
X0504279Y0841467
X0509827Y0844971
X0511679Y0841467
X0517227Y0844971
X0519079Y0841467
X0524627Y0844971
X0526478Y0848176
X0476527Y0844971
X0480227Y0844971
X0483927Y0844971
X0487627Y0844971
X0489478Y0841467
X0493178Y0848176
X0532028Y0844671
X0489478Y0873810
X0496878Y0873810
X0496878Y0860993
X0489478Y0860993
X0496878Y0848176
X0489478Y0848176
X0482078Y0873810
X0474678Y0873810
X0482078Y0860993
X0474678Y0860993
X0482078Y0848176
X0474678Y0848176
X0519078Y0873810
X0526479Y0873810
X0519078Y0860993
X0526479Y0860993
X0519078Y0848176
X0504278Y0873810
X0511678Y0873810
X0504278Y0860993
X0511678Y0860993
X0504278Y0848176
X0511678Y0848176
X0502429Y0883423
X0495029Y0883423
X0487629Y0883423
X0480229Y0883423
X0524629Y0883423
X0517229Y0883423
X0509829Y0883423
X0472829Y0883423
X0506129Y0883423
X0504278Y0880219
X0498729Y0883423
X0496878Y0880219
X0491329Y0883423
X0489478Y0880219
X0483929Y0883423
X0482078Y0880219
X0476529Y0883423
X0528329Y0883423
X0526479Y0880219
X0520929Y0883423
X0519078Y0880219
X0513529Y0883423
X0511678Y0880219
X0474678Y0880219
X0507978Y0873810
X0506129Y0870606
X0500578Y0873810
X0498729Y0870606
X0493178Y0873810
X0491329Y0870606
X0485778Y0873810
X0483929Y0870606
X0478378Y0873810
X0530178Y0873810
X0528329Y0870606
X0522778Y0873810
X0520929Y0870606
X0515378Y0873810
X0513529Y0870606
X0476529Y0870606
X0509829Y0870606
X0504278Y0867401
X0502429Y0870606
X0496878Y0867401
X0495029Y0870606
X0489478Y0867401
X0487629Y0870606
X0482078Y0867401
X0480229Y0870606
X0532029Y0870606
X0526479Y0867401
X0524629Y0870606
X0519078Y0867401
X0517229Y0870606
X0511678Y0867401
X0474678Y0867401
X0541279Y0854584
X0541279Y0860993
X0539429Y0857789
X0543130Y0857789
X0539429Y0851380
X0543129Y0851380
X0533879Y0854584
X0535729Y0857789
X0546828Y0864197
X0543128Y0864197
X0532029Y0864197
X0535729Y0864197
X0543129Y0877014
X0535729Y0877014
X0546828Y0877014
X0539428Y0877014
X0543129Y0870606
X0544979Y0873810
X0539429Y0870606
X0537578Y0873810
X0544979Y0880219
X0543129Y0883423
X0537578Y0880219
X0539429Y0883423
X0546829Y0883423
X0541279Y0880219
X0535729Y0883423
X0535729Y0870606
X0541279Y0873810
X0546829Y0870606
X0532028Y0883423
X0533879Y0873810
X0533879Y0880219
X0532029Y0877014
X0524629Y0877014
X0530179Y0880219
X0520929Y0877014
X0522779Y0880219
X0528329Y0877014
X0517229Y0877014
X0515379Y0880219
X0506129Y0877014
X0513529Y0877014
X0502429Y0877014
X0507979Y0880219
X0509829Y0877014
X0498729Y0877014
X0500579Y0880219
X0485779Y0880219
X0487629Y0877014
X0491329Y0877014
X0493179Y0880219
X0495029Y0877014
X0483929Y0877014
X0472828Y0870606
X0472829Y0877014
X0476529Y0877014
X0478379Y0880219
X0480229Y0877014
X0537579Y0867401
X0541279Y0867401
X0544979Y0867401
X0537579Y0860993
X0537579Y0854584
X0539428Y0864197
X0544979Y0854584
X0544979Y0860993
X0533879Y0867401
X0522779Y0867401
X0530178Y0867401
X0533879Y0860993
X0532028Y0857789
X0522779Y0854584
X0530179Y0854584
X0530179Y0860993
X0520929Y0864197
X0524629Y0864197
X0528329Y0864197
X0515379Y0867401
X0507979Y0867401
X0517229Y0864197
X0515379Y0854584
X0507979Y0854584
X0502429Y0864197
X0506129Y0864197
X0509829Y0864197
X0513529Y0864197
X0500579Y0867401
X0485779Y0867401
X0493179Y0867401
X0500579Y0854584
X0498729Y0864197
X0485779Y0854584
X0487629Y0864197
X0491329Y0864197
X0493179Y0854584
X0495029Y0864197
X0478379Y0867401
X0483929Y0864197
X0472829Y0864197
X0476529Y0864197
X0478379Y0854584
X0480229Y0864197
X0535729Y0851380
X0535729Y0844671
X0537580Y0848176
X0532029Y0851380
X0520929Y0851380
X0524629Y0851380
X0528329Y0851380
X0522779Y0841467
X0528329Y0844671
X0517229Y0851380
X0509829Y0851380
X0513529Y0851380
X0502429Y0851380
X0506129Y0851380
X0515379Y0841467
X0507979Y0841467
X0498729Y0851380
X0487629Y0851380
X0491329Y0851380
X0495029Y0851380
X0500579Y0841467
X0483929Y0851380
X0472829Y0851380
X0480229Y0851380
X0476529Y0851380
X0478379Y0841467
X0485779Y0841467
X0493179Y0841467
X0476529Y0909057
X0472829Y0909057
X0476529Y0896240
X0482078Y0963529
X0480229Y0966735
X0478378Y0905853
X0478378Y0976347
X0480229Y0973143
X0476529Y0902649
X0478378Y0982756
X0480229Y0979552
X0496878Y0886627
X0489478Y0886627
X0482078Y0905853
X0482078Y0886627
X0474678Y0886627
X0533879Y0886627
X0519078Y0886627
X0526479Y0886627
X0504278Y0886627
X0511678Y0886627
X0473851Y0942246
X0473904Y0971100
X0476285Y0971526
X0476285Y0973826
X0478378Y0957122
X0480229Y0953917
X0478378Y0950713
X0480229Y0947509
X0478378Y0899445
X0480228Y0909057
X0472829Y0902649
X0507978Y0886627
X0500578Y0886627
X0493178Y0886627
X0485778Y0886627
X0478378Y0886627
X0530179Y0886627
X0522778Y0886627
X0515378Y0886627
X0472828Y0915466
X0472829Y0921875
X0478379Y0969939
X0530178Y0893036
X0482078Y0982756
X0480228Y0960326
X0480229Y0915466
X0507978Y0963530
X0483929Y0953917
X0495029Y0896240
X0504278Y0905853
X0491329Y0915466
X0491329Y0934691
X0491329Y0953917
X0487629Y0896240
X0496878Y0905853
X0483929Y0915466
X0483929Y0934691
X0487629Y0953917
X0491329Y0896240
X0507978Y0905853
X0495029Y0915466
X0495029Y0934691
X0495029Y0953917
X0483929Y0896240
X0500578Y0905853
X0487629Y0915466
X0487629Y0934691
X0485778Y0918670
X0487629Y0921875
X0487629Y0928283
X0493178Y0931488
X0491329Y0928283
X0485778Y0931488
X0493178Y0937896
X0485778Y0893036
X0496878Y0893036
X0491329Y0941100
X0482078Y0893036
X0493178Y0893036
X0493178Y0899445
X0491329Y0902649
X0485778Y0899445
X0487629Y0902649
X0504278Y0899445
X0506129Y0902649
X0500578Y0899445
X0498729Y0902649
X0485778Y0937896
X0506129Y0909057
X0504278Y0912262
X0498729Y0909057
X0500578Y0912262
X0491329Y0909057
X0493178Y0912262
X0487629Y0909057
X0485778Y0912262
X0493178Y0918670
X0491329Y0921875
X0487629Y0941100
X0506129Y0960326
X0498729Y0960326
X0504278Y0957122
X0500578Y0957122
X0485778Y0957122
X0487629Y0960326
X0493178Y0957122
X0491329Y0960326
X0491329Y0947509
X0493178Y0950713
X0487629Y0947509
X0485778Y0950713
X0496878Y0963530
X0506129Y0966735
X0498729Y0966735
X0504278Y0969939
X0500578Y0969939
X0493178Y0969939
X0491329Y0966735
X0487629Y0966735
X0485778Y0969939
X0483929Y0973143
X0491329Y0973143
X0487629Y0973143
X0495029Y0973143
X0520929Y0973143
X0509829Y0953917
X0517229Y0915466
X0507978Y0925079
X0504278Y0944304
X0517229Y0953917
X0509829Y0915466
X0500578Y0925079
X0500578Y0944304
X0513529Y0953917
X0520929Y0915466
X0504278Y0925079
X0507978Y0944304
X0520929Y0953917
X0513529Y0915466
X0496878Y0925079
X0496878Y0944304
X0498729Y0928283
X0504278Y0931488
X0504278Y0937896
X0506129Y0941100
X0500578Y0937896
X0498729Y0941100
X0506129Y0947509
X0504278Y0950713
X0517229Y0909057
X0519078Y0912262
X0513529Y0909057
X0511678Y0912262
X0498729Y0947509
X0519078Y0918670
X0517229Y0921875
X0511678Y0918670
X0513529Y0921875
X0504278Y0918670
X0506129Y0921875
X0500578Y0918670
X0498729Y0921875
X0506129Y0928283
X0500578Y0931488
X0500578Y0950713
X0513529Y0966735
X0511678Y0969939
X0517229Y0966735
X0519078Y0969939
X0519078Y0957122
X0517229Y0960326
X0511678Y0957122
X0513529Y0960326
X0517229Y0947509
X0519078Y0950713
X0513529Y0947509
X0511678Y0950713
X0509829Y0973143
X0519078Y0976347
X0511678Y0976347
X0517229Y0979552
X0513529Y0979552
X0506129Y0979552
X0504278Y0976347
X0500578Y0976347
X0498729Y0979552
X0496878Y0982756
X0504278Y0982756
X0500578Y0982756
X0507978Y0982756
X0533879Y0963530
X0522778Y0944304
X0520929Y0896240
X0530179Y0905853
X0517229Y0934691
X0530178Y0944304
X0513529Y0896240
X0522778Y0905853
X0509829Y0934691
X0526479Y0944304
X0517229Y0896240
X0533879Y0905853
X0520929Y0934691
X0533879Y0944304
X0509829Y0896240
X0526479Y0905853
X0513529Y0934691
X0524629Y0909057
X0526479Y0912262
X0517229Y0928283
X0519078Y0931488
X0513529Y0928283
X0511678Y0931488
X0519078Y0937896
X0507978Y0893036
X0522778Y0893036
X0517229Y0941100
X0511678Y0893036
X0519078Y0893036
X0519078Y0899445
X0517229Y0902649
X0511678Y0899445
X0513529Y0902649
X0511678Y0937896
X0530178Y0899445
X0532029Y0902649
X0526479Y0899445
X0524629Y0902649
X0532029Y0909057
X0530179Y0912262
X0513529Y0941100
X0526479Y0957122
X0524629Y0960326
X0530178Y0957122
X0532029Y0960326
X0532029Y0947509
X0530178Y0950713
X0524629Y0947509
X0526479Y0950713
X0530179Y0937896
X0532029Y0941100
X0526479Y0937896
X0524629Y0941100
X0522778Y0963530
X0532029Y0966735
X0524629Y0966735
X0530179Y0969939
X0526479Y0969939
X0493178Y0976347
X0491329Y0979552
X0530179Y0925079
X0522778Y0925079
X0533879Y0925079
X0526479Y0925079
X0530179Y0918670
X0532029Y0921875
X0526479Y0918670
X0524629Y0921875
X0532029Y0928283
X0530179Y0931488
X0524629Y0928283
X0526479Y0931488
X0485778Y0976347
X0487629Y0979552
X0472829Y0896240
X0474678Y0893036
X0478378Y0963530
X0550701Y0972608
X0551429Y0979057
X0535729Y0973143
X0539429Y0973143
X0541279Y0969939
X0537579Y0982756
X0539429Y0979552
X0532029Y0973143
X0533879Y0969939
X0533901Y0980606
X0519079Y0982756
X0533879Y0976347
X0520929Y0979552
X0524628Y0973143
X0522778Y0969939
X0522779Y0976347
X0528329Y0973143
X0528329Y0979552
X0515378Y0982756
X0511678Y0982756
X0517228Y0973143
X0515378Y0969939
X0515379Y0976347
X0506129Y0973143
X0509828Y0979552
X0513529Y0973143
X0502429Y0973143
X0502429Y0979552
X0507979Y0969939
X0507978Y0976347
X0485778Y0982756
X0489478Y0982756
X0493179Y0982756
X0498728Y0973143
X0495029Y0979552
X0489478Y0969939
X0489478Y0976347
X0496878Y0969939
X0496879Y0976347
X0482078Y0976347
X0483928Y0979552
X0482079Y0969939
X0476335Y0980737
X0476192Y0977670
X0548146Y0965640
X0537579Y0963530
X0535729Y0966735
X0535729Y0960326
X0537579Y0950713
X0537579Y0957122
X0549719Y0962436
X0528329Y0966735
X0530178Y0963530
X0533879Y0950713
X0532029Y0953917
X0533879Y0957122
X0519079Y0963530
X0526479Y0963530
X0520928Y0966735
X0522778Y0950713
X0520929Y0960326
X0522779Y0957122
X0524629Y0953917
X0528329Y0953917
X0528329Y0960326
X0515378Y0963530
X0504278Y0963530
X0511678Y0963530
X0502428Y0966735
X0509829Y0966735
X0515378Y0950713
X0515378Y0957122
X0507979Y0950713
X0502429Y0953917
X0502429Y0960326
X0506129Y0953917
X0507978Y0957122
X0509828Y0960326
X0500579Y0963530
X0489478Y0963530
X0485778Y0963530
X0493179Y0963530
X0495028Y0966735
X0498729Y0953917
X0496878Y0950713
X0489478Y0950713
X0489478Y0957122
X0495029Y0960326
X0496879Y0957122
X0483929Y0966735
X0482079Y0950713
X0482078Y0957122
X0483928Y0960326
X0549278Y0949619
X0535729Y0947509
X0539429Y0947509
X0548678Y0944304
X0535729Y0941100
X0537578Y0944304
X0537579Y0937896
X0528329Y0947509
X0533879Y0937896
X0532029Y0934691
X0520928Y0947509
X0519079Y0944304
X0520929Y0941100
X0522779Y0937896
X0524628Y0934691
X0528329Y0934691
X0528329Y0941100
X0502429Y0947509
X0509829Y0947509
X0515378Y0937896
X0515378Y0944304
X0502429Y0934691
X0502429Y0941100
X0506129Y0934691
X0507978Y0937896
X0509828Y0941100
X0511678Y0944304
X0495028Y0947509
X0498729Y0934691
X0485778Y0944304
X0489478Y0937896
X0489478Y0944304
X0493179Y0944304
X0495029Y0941100
X0496879Y0937896
X0483928Y0947509
X0482078Y0937896
X0482079Y0944304
X0483928Y0941100
X0480229Y0934691
X0478378Y0944304
X0476180Y0947655
X0476180Y0945355
X0476285Y0964626
X0476285Y0960026
X0476285Y0962326
X0476285Y0966926
X0548678Y0931488
X0537578Y0931488
X0548678Y0925079
X0535729Y0921875
X0535729Y0928283
X0537578Y0925079
X0537579Y0918670
X0539429Y0928283
X0543129Y0928283
X0533878Y0931488
X0533879Y0918670
X0528329Y0928283
X0522778Y0931488
X0520929Y0921875
X0522779Y0918670
X0519079Y0925079
X0520928Y0928283
X0528329Y0921875
X0515378Y0931488
X0507979Y0931488
X0515378Y0918670
X0515378Y0925079
X0507978Y0918670
X0509828Y0921875
X0502429Y0921875
X0502429Y0928283
X0509829Y0928283
X0511678Y0925079
X0489478Y0931488
X0496878Y0931488
X0495029Y0921875
X0496879Y0918670
X0485778Y0925079
X0489478Y0918670
X0489478Y0925079
X0493179Y0925079
X0495028Y0928283
X0482079Y0931488
X0483928Y0921875
X0482078Y0918670
X0483929Y0928283
X0474678Y0918670
X0476528Y0921875
X0480229Y0921875
X0476285Y0930126
X0476285Y0934726
X0548679Y0905853
X0535729Y0902649
X0543129Y0909057
X0535729Y0909057
X0537579Y0905853
X0539429Y0909057
X0537579Y0912262
X0548679Y0912262
X0533879Y0912262
X0528329Y0909057
X0532029Y0915466
X0524628Y0915466
X0528329Y0915466
X0520929Y0902649
X0519079Y0905853
X0520928Y0909057
X0522778Y0912262
X0528329Y0902649
X0506129Y0915466
X0502429Y0915466
X0515378Y0905853
X0515378Y0912262
X0509828Y0902649
X0502429Y0902649
X0502429Y0909057
X0507979Y0912262
X0509829Y0909057
X0511678Y0905853
X0498728Y0915466
X0485778Y0905853
X0493179Y0905853
X0495029Y0902649
X0489478Y0905853
X0489478Y0912262
X0495029Y0909057
X0496878Y0912262
X0483928Y0902649
X0482079Y0912262
X0483929Y0909057
X0474678Y0905853
X0474678Y0912262
X0537579Y0899445
X0550529Y0889832
X0535729Y0889832
X0537579Y0886627
X0544979Y0886627
X0541279Y0886627
X0537579Y0893036
X0533879Y0899445
X0522779Y0899445
X0533879Y0893036
X0532029Y0896240
X0532029Y0889832
X0520929Y0889832
X0524629Y0896240
X0526479Y0893036
X0524629Y0889832
X0528329Y0889832
X0528329Y0896240
X0515378Y0899445
X0507978Y0899445
X0517229Y0889832
X0515379Y0893036
X0504279Y0893036
X0506128Y0896240
X0509829Y0889832
X0513529Y0889832
X0502429Y0889832
X0502428Y0896240
X0506129Y0889832
X0489478Y0899445
X0496879Y0899445
X0498729Y0896240
X0500579Y0893036
X0498729Y0889832
X0487629Y0889832
X0491329Y0889832
X0495029Y0889832
X0489479Y0893036
X0482078Y0899445
X0474678Y0899445
X0483929Y0889832
X0472829Y0889832
X0476529Y0889832
X0478379Y0893036
X0480229Y0889832
X0480228Y0896240
X0480229Y0902649
X0478379Y0918670
X0478380Y0912262
X0476529Y0915466
X0480229Y0941100
X0478378Y0937896
X0482078Y0925079
X0478378Y0925079
X0478378Y0931488
X0480229Y0928283
X0476961Y1082994
X0482511Y1073383
X0475111Y1073383
X0480662Y1025318
X0476961Y1050952
X0478812Y1054157
X0476962Y1057361
X0476962Y1063770
X0478812Y1060565
X0480661Y1057361
X0480662Y1063770
X0482511Y1054157
X0473262Y1050952
X0473262Y1063770
X0475112Y1054157
X0473261Y1057361
X0478811Y1047749
X0476962Y1044544
X0476325Y1029495
X0476325Y1027195
X0476325Y1031795
X0478811Y1015705
X0478811Y1028523
X0478811Y1022114
X0480661Y1018910
X0473262Y1044544
X0480662Y1044544
X0478811Y1041340
X0480662Y1038136
X0473262Y1076587
X0482511Y1015705
X0476962Y1070178
X0480662Y1070178
X0480662Y1076587
X0476962Y1076587
X0480662Y1031727
X0478811Y1034931
X0475111Y1047749
X0525062Y0999684
X0526911Y1002888
X0532461Y0999684
X0530611Y1002888
X0491762Y1025318
X0491762Y1044544
X0491762Y1063770
X0491762Y1082995
X0484362Y1025318
X0484362Y1044544
X0484362Y1063770
X0488062Y1082995
X0495462Y1025318
X0495462Y1044544
X0495462Y1063770
X0495462Y1082995
X0488062Y1025318
X0488062Y1044544
X0488062Y1063770
X0484362Y1082995
X0491762Y1038136
X0493611Y1041340
X0488062Y1038136
X0486211Y1041340
X0493611Y1047749
X0491762Y1050952
X0486211Y1047749
X0488062Y1050952
X0491762Y1057361
X0493611Y1060565
X0488062Y1057361
X0486211Y1060565
X0493611Y1066974
X0491762Y1070178
X0486211Y1066974
X0488062Y1070178
X0491762Y1076587
X0493611Y1079791
X0488062Y1076587
X0486211Y1079791
X0486211Y1009297
X0488062Y1012501
X0493611Y1009297
X0491761Y1012501
X0491762Y1018910
X0493611Y1022114
X0488062Y1018910
X0486211Y1022114
X0493611Y1028523
X0491762Y1031727
X0486211Y1028523
X0488062Y1031727
X0491762Y0999684
X0488062Y0999684
X0493611Y1002888
X0486211Y1002888
X0495462Y1006093
X0484362Y1006093
X0480662Y1012501
X0513962Y0999684
X0512111Y1002888
X0517661Y0999684
X0519513Y1002888
X0504711Y1034931
X0504711Y1054157
X0517662Y1044544
X0504711Y1073383
X0517662Y1082995
X0497311Y1034931
X0497311Y1054157
X0513962Y1044544
X0501011Y1073383
X0510262Y1082995
X0508411Y1034931
X0508411Y1054157
X0521362Y1044544
X0508411Y1073383
X0521362Y1082995
X0501011Y1034931
X0501011Y1054157
X0510262Y1044544
X0497311Y1073383
X0513962Y1082995
X0499162Y1076587
X0501011Y1079791
X0517662Y1076587
X0519511Y1079791
X0513962Y1076587
X0512111Y1079791
X0504711Y1047749
X0506562Y1050952
X0501011Y1047749
X0499162Y1050952
X0506562Y1057361
X0504711Y1060565
X0499162Y1057361
X0501011Y1060565
X0517662Y1038136
X0519511Y1041340
X0513962Y1038136
X0512111Y1041340
X0519511Y1047749
X0517662Y1050952
X0512111Y1047749
X0513962Y1050952
X0504711Y1066974
X0506562Y1070178
X0501011Y1066974
X0499162Y1070178
X0506562Y1076587
X0504711Y1079791
X0499162Y1018910
X0501011Y1022114
X0506562Y1018910
X0504711Y1022114
X0504711Y1028523
X0506562Y1031727
X0501011Y1028523
X0499162Y1031727
X0506562Y1038136
X0504711Y1041340
X0499162Y1038136
X0501011Y1041340
X0504711Y1009297
X0501011Y1009297
X0506562Y1012501
X0499162Y1012501
X0508411Y1015705
X0497311Y1015705
X0478811Y1009297
X0499162Y0999684
X0501011Y1002888
X0512111Y1009297
X0513962Y1012501
X0506561Y0999684
X0504711Y1002888
X0519511Y1009297
X0530611Y1034931
X0517662Y1025318
X0530611Y1054157
X0517662Y1063770
X0523211Y1034931
X0510262Y1025318
X0526911Y1054157
X0513962Y1063770
X0534311Y1034931
X0521362Y1025318
X0534311Y1054157
X0521362Y1063770
X0526911Y1034931
X0513962Y1025318
X0523211Y1054157
X0510262Y1063770
X0512111Y1066974
X0513962Y1070178
X0517662Y1018910
X0519511Y1022114
X0513962Y1018910
X0512111Y1022114
X0519511Y1028523
X0517662Y1031727
X0512111Y1028523
X0513962Y1031727
X0530611Y1047749
X0532462Y1050953
X0526911Y1047749
X0525061Y1050952
X0532462Y1057361
X0530611Y1060565
X0525062Y1057361
X0526911Y1060565
X0517662Y1057361
X0519511Y1060565
X0513962Y1057361
X0512111Y1060565
X0519511Y1066974
X0517662Y1070178
X0525062Y1018910
X0526911Y1022114
X0532461Y1018910
X0530611Y1022114
X0530611Y1028523
X0532461Y1031727
X0526911Y1028523
X0525062Y1031727
X0532461Y1038136
X0530611Y1041340
X0525062Y1038136
X0526911Y1041340
X0517662Y1012501
X0530611Y1009297
X0526911Y1009297
X0532461Y1012501
X0525062Y1012501
X0534311Y1015705
X0523211Y1015705
X0510262Y1006093
X0521362Y1006093
X0513962Y1006093
X0517662Y1006093
X0478811Y1002888
X0502862Y1006093
X0530611Y1073383
X0526911Y1073383
X0534311Y1073383
X0523211Y1073383
X0525062Y1076587
X0526911Y1079791
X0530611Y1066974
X0532462Y1070178
X0526911Y1066974
X0525062Y1070178
X0532462Y1076587
X0530611Y1079791
X0480662Y0999684
X0547262Y1082996
X0536162Y1082996
X0532462Y1082996
X0525061Y1082995
X0528762Y1082995
X0502862Y1082995
X0506562Y1082995
X0499161Y1082995
X0473262Y1082995
X0480662Y1082995
X0547262Y1070178
X0538011Y1073383
X0536162Y1070178
X0536161Y1076587
X0539861Y1076587
X0545411Y1066974
X0541711Y1073383
X0538011Y1066974
X0549422Y1064850
X0534311Y1079791
X0534311Y1066974
X0523212Y1079791
X0523211Y1066974
X0519512Y1073383
X0521361Y1070178
X0521362Y1076587
X0528762Y1070178
X0528762Y1076587
X0515811Y1079791
X0508411Y1079791
X0515811Y1066974
X0515811Y1073383
X0508411Y1066974
X0512111Y1073383
X0502862Y1070178
X0502862Y1076587
X0510262Y1070178
X0510262Y1076587
X0489911Y1079791
X0497312Y1079791
X0489911Y1073383
X0495461Y1070178
X0497311Y1066974
X0486211Y1073383
X0489911Y1066974
X0493612Y1073383
X0495462Y1076587
X0482511Y1079791
X0475111Y1079791
X0478812Y1079791
X0482512Y1066974
X0484362Y1070178
X0484361Y1076587
X0478811Y1073383
X0473262Y1070178
X0475111Y1066974
X0536161Y1050952
X0538011Y1060565
X0545411Y1054157
X0536161Y1057361
X0538011Y1054157
X0541711Y1054157
X0532462Y1063770
X0534311Y1060565
X0525061Y1063770
X0528762Y1063770
X0519512Y1054157
X0521361Y1050952
X0521362Y1057361
X0523212Y1060565
X0528762Y1050952
X0528762Y1057361
X0506562Y1063770
X0502862Y1063770
X0515811Y1060565
X0515811Y1054157
X0510262Y1050952
X0512111Y1054157
X0502862Y1050952
X0502862Y1057361
X0508411Y1060565
X0510262Y1057361
X0499162Y1063770
X0486211Y1054157
X0493611Y1054157
X0495461Y1050952
X0489911Y1054157
X0489911Y1060565
X0495462Y1057361
X0497311Y1060565
X0484362Y1050952
X0482511Y1060565
X0484361Y1057361
X0475111Y1060565
X0480662Y1050952
X0549112Y1034931
X0536161Y1038136
X0538011Y1034931
X0541711Y1034931
X0539861Y1038136
X0539862Y1044544
X0545412Y1034931
X0534311Y1047749
X0534311Y1041340
X0528762Y1038136
X0523211Y1047749
X0532462Y1044544
X0519512Y1034931
X0521362Y1038136
X0523212Y1041340
X0525061Y1044544
X0528762Y1044544
X0515811Y1047749
X0508411Y1047749
X0515811Y1041340
X0515811Y1034931
X0506562Y1044544
X0508411Y1041340
X0510261Y1038136
X0512111Y1034931
X0502862Y1038136
X0502862Y1044544
X0497311Y1047749
X0489911Y1047749
X0499161Y1044544
X0486211Y1034931
X0493612Y1034931
X0495462Y1038136
X0489911Y1034931
X0489911Y1041340
X0497312Y1041340
X0482511Y1047749
X0484361Y1038136
X0482512Y1034931
X0482511Y1041340
X0475111Y1041340
X0473507Y1035928
X0550961Y1031727
X0536161Y1031727
X0549112Y1015705
X0536161Y1018910
X0538012Y1015705
X0545412Y1015705
X0541712Y1015705
X0539861Y1018910
X0536161Y1025318
X0532461Y1025318
X0534310Y1022114
X0534311Y1028523
X0530611Y1015705
X0528762Y1018910
X0526912Y1015705
X0523211Y1022114
X0521362Y1018910
X0519512Y1015705
X0521361Y1031727
X0528762Y1031727
X0525061Y1025318
X0523211Y1028523
X0528762Y1025318
X0512111Y1015705
X0515811Y1015705
X0502862Y1031727
X0510262Y1031727
X0515811Y1022114
X0515811Y1028523
X0504711Y1015705
X0506562Y1025318
X0508411Y1022114
X0510261Y1018910
X0502862Y1018910
X0502862Y1025318
X0508411Y1028523
X0495461Y1031727
X0499161Y1025318
X0501012Y1015705
X0486211Y1015705
X0493612Y1015705
X0495462Y1018910
X0497311Y1022114
X0489911Y1015705
X0489911Y1022114
X0489911Y1028523
X0497311Y1028523
X0484361Y1031727
X0484361Y1018910
X0482511Y1022114
X0482511Y1028523
X0536161Y1012501
X0549254Y1000648
X0543563Y1006092
X0536161Y1006093
X0536161Y0999684
X0539861Y0999684
X0539862Y1006092
X0528761Y1012501
X0532461Y1006093
X0534311Y1002888
X0534311Y1009297
X0523212Y1002888
X0523211Y1009297
X0525061Y1006093
X0528762Y0999684
X0528762Y1006093
X0521361Y0999684
X0521361Y1012501
X0515811Y1002888
X0515811Y1009297
X0510262Y1012501
X0508412Y1009297
X0502861Y1012501
X0502862Y0999684
X0506562Y1006093
X0508411Y1002888
X0510261Y0999684
X0495461Y1012501
X0499161Y1006093
X0488062Y1006093
X0491761Y1006093
X0489912Y1002888
X0489911Y1009297
X0495462Y0999684
X0497312Y1002888
X0497311Y1009297
X0484362Y1012501
X0482511Y1002888
X0482512Y1009297
X0484361Y0999684
X0543729Y0984866
X0476285Y0987626
X0476285Y0989926
X0476285Y0994526
X0476285Y0996826
X0476285Y1003726
X0476285Y1006026
X0476285Y1012926
X0476295Y1010500
X0476285Y1017526
X0476275Y1022636
X0478811Y1066974
X0506561Y1115038
X0508412Y1105426
X0512112Y1111833
X0510261Y1108630
X0538012Y1131059
X0532461Y1127855
X0543561Y1127855
X0478812Y1086199
X0541711Y1124650
X0475112Y1086199
X0476961Y1095812
X0482512Y1092607
X0504712Y1105426
X0501012Y1111833
X0539861Y1121446
X0536161Y1121446
X0504712Y1111833
X0506561Y1102220
X0508412Y1111833
X0512112Y1105426
X0536161Y1127855
X0534311Y1124650
X0539861Y1127855
X0543561Y1121446
X0473261Y1089403
X0475112Y1092607
X0478812Y1092607
X0501012Y1105426
X0502861Y1108629
X0538010Y1118242
X0532461Y1121446
X0532461Y1140973
X0528761Y1140973
X0541711Y1118243
X0525062Y1134264
X0534311Y1118243
X0525062Y1121447
X0526911Y1118243
X0530611Y1105426
X0523212Y1099017
X0525062Y1102221
X0528762Y1102221
X0517662Y1134264
X0502862Y1134264
X0510262Y1134264
X0517662Y1121447
X0502862Y1121447
X0510262Y1121447
X0502862Y1115039
X0510262Y1102221
X0488062Y1134264
X0495462Y1134264
X0488062Y1121447
X0488062Y1115039
X0488062Y1095813
X0480662Y1134264
X0480662Y1121447
X0473262Y1121447
X0480662Y1102221
X0480662Y1089404
X0473262Y1095813
X0493611Y1124651
X0497311Y1124651
X0501011Y1124651
X0504711Y1124651
X0508411Y1124651
X0512111Y1124651
X0515811Y1124651
X0519511Y1124651
X0523211Y1124651
X0475111Y1124651
X0478811Y1124651
X0482511Y1124651
X0486211Y1124651
X0489911Y1124651
X0525062Y1127856
X0491762Y1121447
X0495462Y1127856
X0499162Y1121447
X0502862Y1127856
X0506562Y1121447
X0510262Y1127856
X0513962Y1121447
X0517662Y1127856
X0521362Y1121447
X0473262Y1127856
X0476962Y1121447
X0480662Y1127856
X0484362Y1121447
X0488062Y1127856
X0526911Y1124651
X0497312Y1137469
X0499162Y1134264
X0502861Y1140973
X0508412Y1137469
X0510261Y1140973
X0515812Y1137469
X0519512Y1137469
X0521362Y1134264
X0526912Y1137469
X0473261Y1140973
X0478812Y1137469
X0480661Y1140973
X0486212Y1137469
X0489912Y1137469
X0491762Y1134264
X0534312Y1137469
X0495461Y1140973
X0501012Y1137469
X0504712Y1137469
X0506562Y1134264
X0512112Y1137469
X0513962Y1134264
X0517661Y1140973
X0523212Y1137469
X0525061Y1140973
X0475112Y1137469
X0476962Y1134264
X0482512Y1137469
X0484362Y1134264
X0488061Y1140973
X0493612Y1137469
X0532462Y1134264
X0504711Y1092608
X0501011Y1092608
X0508411Y1092608
X0497311Y1092608
X0486211Y1086200
X0488062Y1089404
X0504711Y1086200
X0506562Y1089404
X0501011Y1086200
X0499162Y1089404
X0506561Y1095813
X0515811Y1099017
X0510262Y1095813
X0493611Y1086200
X0491762Y1089404
X0517662Y1102221
X0519511Y1086200
X0517662Y1089404
X0512111Y1086200
X0513962Y1089404
X0530611Y1092608
X0523211Y1092608
X0534310Y1092608
X0526911Y1092608
X0530611Y1086200
X0532462Y1089404
X0526911Y1086200
X0525062Y1089404
X0530611Y1099017
X0525062Y1095813
X0532461Y1095813
X0521362Y1095813
X0536162Y1134264
X0541711Y1131060
X0534311Y1131060
X0521361Y1140973
X0528761Y1134264
X0519511Y1131060
X0523211Y1131060
X0526912Y1131060
X0530612Y1131060
X0530612Y1137469
X0515811Y1131060
X0506561Y1140973
X0504711Y1131060
X0508411Y1131060
X0512111Y1131060
X0513961Y1140973
X0499161Y1140973
X0501011Y1131060
X0491761Y1140973
X0486211Y1131060
X0489911Y1131060
X0493611Y1131060
X0497311Y1131060
X0484361Y1140973
X0482511Y1131060
X0473261Y1134264
X0475111Y1131060
X0476961Y1140973
X0478811Y1131060
X0536161Y1115039
X0538011Y1124651
X0539862Y1115039
X0543562Y1115039
X0545411Y1118243
X0545411Y1124651
X0528762Y1115039
X0525062Y1115039
X0521361Y1127856
X0528761Y1127856
X0532461Y1115039
X0519511Y1118243
X0521361Y1115039
X0523211Y1118243
X0528762Y1121447
X0530611Y1118243
X0530611Y1124651
X0517662Y1115039
X0506561Y1127856
X0513961Y1127856
X0515811Y1118243
X0510261Y1115039
X0504711Y1118243
X0508411Y1118243
X0512111Y1118243
X0513961Y1115039
X0495462Y1115039
X0491762Y1115039
X0499161Y1127856
X0491761Y1127856
X0499161Y1115039
X0501011Y1118243
X0486211Y1118243
X0489911Y1118243
X0493612Y1118243
X0495462Y1121447
X0497311Y1118243
X0473262Y1115039
X0484362Y1115039
X0484361Y1127856
X0476961Y1127856
X0482511Y1118243
X0475111Y1118243
X0476961Y1115039
X0478811Y1118243
X0480661Y1115039
X0543561Y1108630
X0538011Y1111834
X0536161Y1108630
X0538011Y1105426
X0545411Y1111834
X0541711Y1111834
X0536161Y1102221
X0539861Y1102221
X0539861Y1108630
X0541711Y1105426
X0545412Y1105426
X0526911Y1111834
X0519511Y1111834
X0528762Y1108630
X0534311Y1105426
X0523211Y1105426
X0534311Y1111834
X0525062Y1108630
X0521362Y1108630
X0532460Y1102221
X0534311Y1099017
X0526911Y1099017
X0523211Y1111834
X0530612Y1111834
X0532461Y1108630
X0519512Y1099017
X0519511Y1105426
X0521361Y1102221
X0526911Y1105426
X0517662Y1108630
X0515811Y1111834
X0515811Y1105426
X0502862Y1102221
X0504711Y1099017
X0506562Y1108630
X0508411Y1099017
X0512112Y1099017
X0513962Y1102221
X0513962Y1108630
X0488062Y1108630
X0491762Y1108630
X0493611Y1111834
X0486211Y1111834
X0489911Y1105426
X0495462Y1108630
X0497311Y1099017
X0493611Y1099017
X0501011Y1099017
X0495462Y1102221
X0489911Y1099017
X0489911Y1111834
X0497312Y1111834
X0499161Y1102221
X0499161Y1108630
X0486212Y1099017
X0486211Y1105426
X0488061Y1102221
X0491762Y1102221
X0493611Y1105426
X0497312Y1105426
X0484362Y1102221
X0475111Y1105426
X0476962Y1108630
X0478811Y1111834
X0482511Y1099017
X0473262Y1102221
X0478811Y1105426
X0475111Y1111834
X0484362Y1108630
X0482511Y1111834
X0482511Y1105426
X0475112Y1099017
X0476962Y1102221
X0473262Y1108630
X0478811Y1099017
X0480662Y1108630
X0547261Y1095813
X0536161Y1095813
X0543561Y1095813
X0545411Y1092608
X0536161Y1089404
X0538011Y1092608
X0528761Y1095813
X0534311Y1086200
X0528762Y1089404
X0519511Y1092608
X0521361Y1089404
X0523211Y1086200
X0517662Y1095813
X0502862Y1095813
X0513961Y1095813
X0515811Y1086200
X0515812Y1092608
X0502862Y1089404
X0508412Y1086200
X0510262Y1089404
X0512112Y1092608
X0491762Y1095813
X0499162Y1095813
X0495462Y1095813
X0495461Y1089404
X0486211Y1092608
X0489911Y1086200
X0489911Y1092608
X0493612Y1092608
X0497311Y1086200
X0484362Y1095813
X0480661Y1095813
X0484362Y1089404
X0482512Y1086200
X0476962Y1089404
X0567331Y1578182
X0551011Y1578182
X0563071Y1578182
X0555271Y1578182
X0538951Y1578182
X0543211Y1578182
X0526891Y1578182
X0519091Y1578182
X0531151Y1578182
X0502771Y1578182
X0514831Y1578182
X0507031Y1578182
X0490711Y1578182
X0494971Y1578182
X0478651Y1578182
X0482911Y1578182
X0564370Y1679920
X0564370Y1675383
X0552559Y1679320
X0536811Y1679320
X0544685Y1679920
X0544685Y1675383
X0521063Y1679320
X0528937Y1679920
X0528937Y1675383
X0505315Y1679320
X0513189Y1679920
X0513189Y1675383
X0497441Y1679920
X0497441Y1675383
X0568371Y1614292
X0568371Y1602380
X0556311Y1602380
X0556311Y1614292
X0560571Y1602380
X0560571Y1614292
X0544251Y1614292
X0544251Y1602380
X0536451Y1614292
X0536451Y1602380
X0548511Y1602380
X0548511Y1614292
X0520131Y1614292
X0520131Y1602380
X0524391Y1602380
X0524391Y1614292
X0532191Y1602380
X0532191Y1614292
X0508071Y1602380
X0508071Y1614292
X0512331Y1602380
X0512331Y1614292
X0496011Y1614292
X0496011Y1602380
X0488211Y1602380
X0488211Y1614292
X0500271Y1602380
X0500271Y1614292
X0476151Y1614292
X0476151Y1602380
X0483951Y1602380
X0483951Y1614292
X0567331Y1590094
X0551011Y1590094
X0563071Y1590094
X0555271Y1590094
X0538951Y1590094
X0543211Y1590094
X0526891Y1590094
X0519091Y1590094
X0531151Y1590094
X0502771Y1590094
X0514831Y1590094
X0507031Y1590094
X0490711Y1590094
X0494971Y1590094
X0478651Y1590094
X0482911Y1590094
X0564370Y1717903
X0564370Y1722440
X0564370Y1726974
X0552559Y1716737
X0552559Y1721840
X0552559Y1726377
X0552559Y1730911
X0536811Y1716737
X0536811Y1721840
X0536811Y1726377
X0536811Y1730911
X0544685Y1717903
X0544685Y1722440
X0544685Y1726974
X0521063Y1716737
X0521063Y1721840
X0521063Y1726377
X0521063Y1730911
X0528937Y1717903
X0528937Y1722440
X0528937Y1726974
X0505315Y1716737
X0505315Y1721840
X0505315Y1726377
X0505315Y1730911
X0513189Y1717903
X0513189Y1722440
X0513189Y1726974
X0497441Y1717903
X0497441Y1722440
X0497441Y1726974
X0564370Y1712800
X0564370Y1708266
X0564370Y1703729
X0552559Y1702564
X0552559Y1712203
X0552559Y1707666
X0536811Y1702564
X0536811Y1712203
X0536811Y1707666
X0544685Y1712800
X0544685Y1708266
X0544685Y1703729
X0521063Y1702564
X0521063Y1712203
X0521063Y1707666
X0528937Y1712800
X0528937Y1708266
X0528937Y1703729
X0505315Y1702564
X0505315Y1712203
X0505315Y1707666
X0513189Y1712800
X0513189Y1708266
X0513189Y1703729
X0497441Y1712800
X0497441Y1708266
X0497441Y1703729
X0564370Y1698627
X0564370Y1694093
X0564370Y1689556
X0564370Y1684454
X0552559Y1683857
X0552559Y1698030
X0552559Y1693493
X0552559Y1688391
X0536811Y1683857
X0536811Y1698030
X0536811Y1693493
X0536811Y1688391
X0544685Y1698627
X0544685Y1694093
X0544685Y1689556
X0544685Y1684454
X0521063Y1683857
X0521063Y1698030
X0521063Y1693493
X0521063Y1688391
X0528937Y1698627
X0528937Y1694093
X0528937Y1689556
X0528937Y1684454
X0505315Y1683857
X0505315Y1698030
X0505315Y1693493
X0505315Y1688391
X0513189Y1698627
X0513189Y1694093
X0513189Y1689556
X0513189Y1684454
X0497441Y1698627
X0497441Y1694093
X0497441Y1689556
X0497441Y1684454
X0619488Y1716737
X0619488Y1721840
X0619488Y1726377
X0619488Y1730911
X0603740Y1716737
X0603740Y1721840
X0603740Y1726377
X0603740Y1730911
X0611614Y1717903
X0611614Y1722440
X0611614Y1726974
X0587992Y1716737
X0587992Y1721840
X0587992Y1726377
X0587992Y1730911
X0595866Y1717903
X0595866Y1722440
X0595866Y1726974
X0572244Y1716737
X0572244Y1721840
X0572244Y1726377
X0572244Y1730911
X0580118Y1717903
X0580118Y1722440
X0580118Y1726974
X0619488Y1702564
X0619488Y1712203
X0619488Y1707666
X0603740Y1702564
X0603740Y1712203
X0603740Y1707666
X0611614Y1712800
X0611614Y1708266
X0611614Y1703729
X0587992Y1702564
X0587992Y1712203
X0587992Y1707666
X0595866Y1712800
X0595866Y1708266
X0595866Y1703729
X0572244Y1702564
X0572244Y1712203
X0572244Y1707666
X0580118Y1712800
X0580118Y1708266
X0580118Y1703729
X0619488Y1683857
X0619488Y1698030
X0619488Y1693493
X0619488Y1688391
X0603740Y1683857
X0603740Y1698030
X0603740Y1693493
X0603740Y1688391
X0611614Y1698627
X0611614Y1694093
X0611614Y1689556
X0611614Y1684454
X0587992Y1683857
X0587992Y1698030
X0587992Y1693493
X0587992Y1688391
X0595866Y1698627
X0595866Y1694093
X0595866Y1689556
X0595866Y1684454
X0572244Y1683857
X0572244Y1698030
X0572244Y1693493
X0572244Y1688391
X0580118Y1698627
X0580118Y1694093
X0580118Y1689556
X0580118Y1684454
X0619488Y1679320
X0603740Y1679320
X0611614Y1679920
X0611614Y1675383
X0587992Y1679320
X0595866Y1679920
X0595866Y1675383
X0572244Y1679320
X0580118Y1679920
X0580118Y1675383
X0664851Y1614292
X0664851Y1602380
X0652791Y1614292
X0652791Y1602286
X0657051Y1614292
X0657051Y1602380
X0640731Y1602380
X0640731Y1614292
X0632931Y1614292
X0632931Y1602380
X0644991Y1602380
X0644991Y1614292
X0616611Y1602380
X0616611Y1614292
X0620871Y1602380
X0620871Y1614292
X0628671Y1614292
X0628671Y1602380
X0604551Y1614292
X0604551Y1602380
X0608811Y1614292
X0608811Y1602380
X0592491Y1614292
X0592491Y1602380
X0584691Y1614292
X0584691Y1602380
X0596751Y1602380
X0596751Y1614292
X0572631Y1602380
X0580431Y1602380
X0572631Y1614292
X0580431Y1614292
X0659551Y1590094
X0651751Y1590094
X0635431Y1590094
X0639691Y1590094
X0647491Y1590094
X0623371Y1590094
X0627631Y1590094
X0611311Y1590094
X0603511Y1590094
X0615571Y1590094
X0587191Y1590094
X0591451Y1590094
X0599251Y1590094
X0575131Y1590094
X0579391Y1590094
X0659551Y1578182
X0651751Y1578182
X0635431Y1578182
X0639691Y1578182
X0647491Y1578088
X0623371Y1578182
X0627631Y1578182
X0611311Y1578182
X0603511Y1578182
X0615571Y1578182
X0587191Y1578182
X0591451Y1578182
X0599251Y1578182
X0575131Y1578182
X0579391Y1578182
X0647877Y1254076
X0629699Y1255381
X0645897Y1248785
X0637041Y1252034
X0632080Y1262074
X0666741Y1252034
X0661400Y1263522
X0647690Y1260812
X0664630Y1259442
X0636946Y1258414
X0629931Y1258727
X0650599Y1258727
X0666646Y1264464
X0666741Y1262074
X0649587Y1266766
X0636877Y1261235
X0631270Y1264942
X0636941Y1188451
X0620799Y1195144
X0636941Y1191798
X0620799Y1191798
X0620799Y1201837
X0620799Y1208530
X0620799Y1185105
X0636941Y1198491
X0636941Y1205184
X0627646Y1273164
X0625246Y1273164
X0620899Y1188452
X0630623Y1188452
X0629599Y1198491
X0620899Y1198491
X0620899Y1205184
X0629599Y1205184
X0620899Y1211877
X0629599Y1211877
X0620899Y1218570
X0629599Y1218570
X0629599Y1225263
X0620899Y1225263
X0620036Y1235302
X0630922Y1235302
X0620899Y1241995
X0629599Y1241995
X0629599Y1248688
X0620899Y1248688
X0645741Y1185105
X0637041Y1185105
X0645741Y1195144
X0637041Y1195144
X0637041Y1201837
X0645741Y1201837
X0637041Y1208530
X0645741Y1208530
X0637041Y1215223
X0645741Y1215223
X0646570Y1221916
X0636005Y1221916
X0646539Y1231955
X0635995Y1231862
X0637041Y1238648
X0645741Y1238648
X0634213Y1258679
X0637041Y1245341
X0645741Y1245341
X0639946Y1273364
X0642746Y1273364
X0659299Y1188452
X0650599Y1188452
X0659299Y1198491
X0650599Y1198491
X0659299Y1205184
X0650599Y1205184
X0650599Y1211877
X0659299Y1211877
X0650599Y1218570
X0659299Y1218570
X0649913Y1225263
X0660070Y1225263
X0649701Y1235302
X0660234Y1235302
X0650599Y1241995
X0659299Y1241995
X0659546Y1257664
X0659299Y1248688
X0650599Y1248688
X0653646Y1273364
X0656446Y1273364
X0666741Y1185105
X0666741Y1195144
X0666741Y1201837
X0666741Y1208530
X0666741Y1215223
X0665651Y1221916
X0665912Y1231955
X0666741Y1238648
X0666741Y1245341
X0669646Y1273364
X0636941Y1175066
X0636941Y1181759
X0620799Y1178412
X0620899Y1094751
X0629599Y1094751
X0629599Y1088058
X0620899Y1088058
X0620899Y1101444
X0629599Y1101444
X0629599Y1108137
X0620899Y1108137
X0620099Y1114829
X0630399Y1114829
X0620369Y1124969
X0630363Y1124674
X0620899Y1138255
X0629599Y1138255
X0620899Y1144948
X0629599Y1144948
X0629599Y1131562
X0620899Y1131562
X0620899Y1151641
X0629599Y1151641
X0629833Y1161581
X0620511Y1161680
X0620899Y1168373
X0629599Y1168373
X0620899Y1175066
X0629599Y1175066
X0620899Y1181759
X0629599Y1181759
X0636241Y1084711
X0645741Y1084711
X0645741Y1091404
X0637041Y1091404
X0637041Y1104790
X0645741Y1104790
X0637041Y1098097
X0645741Y1098097
X0637041Y1111483
X0645741Y1111483
X0645741Y1128215
X0637041Y1128915
X0645741Y1121522
X0637041Y1121522
X0637041Y1141601
X0645741Y1141601
X0635744Y1134908
X0646584Y1135108
X0637041Y1158333
X0645741Y1158333
X0637041Y1148294
X0645741Y1148294
X0637041Y1165026
X0645741Y1165026
X0645741Y1171719
X0637041Y1171719
X0637041Y1178412
X0645741Y1178412
X0649799Y1088058
X0660099Y1088058
X0650599Y1094751
X0659299Y1094751
X0659299Y1101444
X0650599Y1101444
X0659299Y1108137
X0650599Y1108137
X0650599Y1114829
X0659299Y1114829
X0649932Y1124640
X0660199Y1124869
X0650599Y1144948
X0659299Y1144948
X0650599Y1138255
X0659299Y1138255
X0650599Y1130762
X0659299Y1130762
X0659299Y1161680
X0650599Y1161680
X0650599Y1151641
X0659299Y1151641
X0659299Y1168373
X0650599Y1168373
X0659299Y1175066
X0650599Y1175066
X0659299Y1181759
X0650599Y1181759
X0665941Y1084711
X0666741Y1091404
X0666741Y1098097
X0666741Y1104790
X0666741Y1111483
X0666741Y1121522
X0666741Y1128215
X0666741Y1134908
X0666741Y1141601
X0665941Y1158333
X0665602Y1148294
X0666741Y1171719
X0666741Y1165026
X0666741Y1178412
X0644257Y1000325
X0650107Y1002825
X0647397Y1000135
X0647447Y1002865
X0640467Y1000735
X0640327Y1003135
X0644347Y1003135
X0625780Y1000198
X0623347Y0999665
X0620899Y1061286
X0620899Y0984318
X0629599Y0984318
X0629599Y0991011
X0620899Y0991011
X0629599Y1024475
X0620899Y1024475
X0629599Y1017782
X0620899Y1017782
X0629599Y1031168
X0620899Y1031168
X0629599Y1037861
X0620899Y1037861
X0629599Y1044554
X0620899Y1044554
X0620899Y1051247
X0629599Y1051247
X0629599Y1057940
X0620899Y1057940
X0629599Y1064633
X0620899Y1064633
X0619999Y1071326
X0630399Y1071326
X0629599Y1078018
X0620899Y1078018
X0645741Y0987664
X0637041Y0987664
X0637041Y1017782
X0645741Y1017782
X0645741Y1027822
X0637041Y1027822
X0645741Y1034515
X0637041Y1034515
X0645741Y1041207
X0637041Y1041207
X0637041Y1047900
X0645741Y1047900
X0637041Y1054593
X0645741Y1054593
X0645741Y1061286
X0637041Y1061286
X0636841Y1067979
X0645741Y1067979
X0646541Y1074672
X0636141Y1074672
X0650599Y0984318
X0659299Y0984318
X0650599Y0991011
X0659299Y0991011
X0650599Y1024475
X0659299Y1024475
X0650599Y1017782
X0659299Y1017782
X0650599Y1031168
X0659299Y1031168
X0650599Y1037861
X0659299Y1037861
X0650599Y1044554
X0659299Y1044554
X0659299Y1057940
X0650599Y1057940
X0650599Y1051247
X0659299Y1051247
X0650599Y1064633
X0659299Y1064633
X0650599Y1071326
X0659299Y1071326
X0649799Y1078018
X0660099Y1078018
X0666741Y0987664
X0666741Y1017782
X0666741Y1027822
X0666741Y1034515
X0666741Y1041207
X0666741Y1047900
X0666741Y1061286
X0666741Y1054593
X0666741Y1067979
X0665841Y1074672
X0636941Y0954200
X0636941Y0957546
X0666641Y0954200
X0666641Y0957546
X0620799Y0957546
X0650499Y0957546
X0636941Y0893963
X0620799Y0900656
X0636941Y0897310
X0620799Y0897310
X0636941Y0887270
X0620799Y0883924
X0620799Y0890617
X0636941Y0904003
X0636941Y0910696
X0620799Y0907349
X0620799Y0914042
X0620799Y0960892
X0650499Y0960892
X0620899Y0887270
X0629599Y0887270
X0620899Y0893963
X0630756Y0893963
X0620899Y0904003
X0629599Y0904003
X0620899Y0917389
X0629599Y0917389
X0629599Y0910696
X0620899Y0910696
X0629599Y0924081
X0620899Y0924081
X0619905Y0930774
X0630399Y0930697
X0630777Y0940814
X0619964Y0940814
X0620899Y0947507
X0629599Y0947507
X0620899Y0954200
X0629599Y0954200
X0620899Y0964239
X0629599Y0964239
X0620899Y0970932
X0629599Y0970932
X0629599Y0977625
X0620899Y0977625
X0637041Y0883924
X0645741Y0883924
X0645741Y0890617
X0637041Y0890617
X0645741Y0900656
X0637041Y0900656
X0637041Y0907349
X0645741Y0907349
X0645741Y0914042
X0637041Y0914042
X0637041Y0920735
X0645741Y0920735
X0636026Y0927428
X0646393Y0927526
X0646703Y0937467
X0636170Y0937467
X0637041Y0944160
X0645741Y0944160
X0645741Y0950853
X0637041Y0950853
X0637041Y0960892
X0645741Y0960892
X0645741Y0967585
X0637041Y0967585
X0645741Y0974278
X0637041Y0974278
X0645741Y0980971
X0637041Y0980971
X0659299Y0887270
X0650599Y0887270
X0659299Y0893963
X0650599Y0893963
X0659299Y0904003
X0650599Y0904003
X0650599Y0910696
X0659299Y0910696
X0650599Y0917389
X0659299Y0917389
X0649661Y0930774
X0660174Y0930774
X0650599Y0924081
X0660504Y0924081
X0650599Y0940814
X0659299Y0940814
X0650599Y0947507
X0659299Y0947507
X0659299Y0954200
X0650599Y0954200
X0650599Y0964239
X0659299Y0964239
X0650599Y0970932
X0659299Y0970932
X0650599Y0977625
X0659299Y0977625
X0666741Y0883924
X0666741Y0890617
X0666741Y0900656
X0666741Y0907349
X0666741Y0914042
X0666741Y0920735
X0665896Y0927428
X0665923Y0937467
X0666741Y0944160
X0666741Y0950853
X0666741Y0960892
X0666741Y0967585
X0666741Y0974278
X0666741Y0980971
X0636941Y0880577
X0620899Y0793570
X0629599Y0793570
X0629599Y0800263
X0620846Y0800263
X0630792Y0806955
X0619632Y0806955
X0630593Y0813648
X0620076Y0813648
X0629599Y0820341
X0620899Y0820341
X0629599Y0830381
X0620899Y0830381
X0620899Y0837074
X0629599Y0837074
X0629599Y0843766
X0620899Y0843766
X0630754Y0850459
X0620005Y0850459
X0630481Y0857152
X0620058Y0857152
X0629599Y0867192
X0620899Y0867192
X0629599Y0873885
X0620899Y0873885
X0629599Y0880577
X0620899Y0880577
X0637041Y0790223
X0645741Y0790223
X0645741Y0796916
X0637041Y0796916
X0645741Y0803609
X0637041Y0803609
X0637041Y0816995
X0646774Y0816995
X0646844Y0810302
X0636221Y0810302
X0645741Y0827034
X0637041Y0827034
X0637041Y0833727
X0645741Y0833727
X0645741Y0840420
X0637041Y0840420
X0645801Y0847113
X0637041Y0847113
X0636266Y0863845
X0645918Y0863845
X0636332Y0853955
X0646819Y0853806
X0645741Y0870538
X0637041Y0870538
X0645741Y0877231
X0637041Y0877231
X0659299Y0793570
X0650599Y0793570
X0650599Y0800263
X0659299Y0800263
X0650599Y0820341
X0660199Y0820341
X0650599Y0813648
X0660432Y0813648
X0650599Y0806955
X0659299Y0806955
X0650599Y0830381
X0659299Y0830381
X0659299Y0837074
X0650599Y0837074
X0650599Y0843766
X0659299Y0843766
X0650599Y0850459
X0659299Y0850459
X0660299Y0867192
X0649563Y0867192
X0650599Y0857152
X0659299Y0857152
X0659299Y0880577
X0650599Y0880577
X0650599Y0873885
X0659299Y0873885
X0666741Y0790223
X0666741Y0796916
X0666741Y0803609
X0666741Y0810302
X0665803Y0816995
X0665876Y0827034
X0666741Y0833727
X0666741Y0840420
X0666741Y0847113
X0665916Y0863845
X0665890Y0853806
X0666741Y0870538
X0666741Y0877231
X0629658Y0766478
X0650599Y0766798
X0620899Y0770144
X0629599Y0770144
X0620899Y0776837
X0629599Y0776837
X0620899Y0783530
X0629599Y0783530
X0645741Y0766798
X0637041Y0766798
X0637041Y0780184
X0645741Y0780184
X0637041Y0773491
X0645741Y0773491
X0659299Y0770144
X0650599Y0770144
X0659299Y0776837
X0650599Y0776837
X0659299Y0783530
X0650599Y0783530
X0666741Y0766798
X0666741Y0780184
X0666741Y0773491
X0739699Y0766798
X0769399Y0766798
X0680299Y0766798
X0709899Y0766798
X0755841Y0783530
X0755841Y0770144
X0755841Y0776837
X0739699Y0773491
X0739699Y0780184
X0696441Y0783530
X0696441Y0770144
X0696441Y0776837
X0680299Y0773491
X0680299Y0780184
X0675441Y0766798
X0680299Y0770144
X0675441Y0780184
X0675441Y0773491
X0680299Y0776837
X0680299Y0783530
X0688999Y0770144
X0696441Y0766798
X0688999Y0776837
X0688999Y0783530
X0696441Y0780184
X0696441Y0773491
X0705141Y0766798
X0709999Y0770144
X0705141Y0780184
X0705141Y0773491
X0709999Y0776837
X0709999Y0783530
X0718699Y0770144
X0726141Y0766798
X0718699Y0776837
X0718699Y0783530
X0726141Y0780184
X0726141Y0773491
X0734841Y0766798
X0739699Y0770144
X0734841Y0780184
X0734841Y0773491
X0739699Y0776837
X0739699Y0783530
X0748399Y0770144
X0755841Y0766798
X0748399Y0776837
X0748399Y0783530
X0755841Y0773491
X0755841Y0780184
X0764541Y0766798
X0769399Y0770144
X0764541Y0773491
X0764541Y0780184
X0769399Y0776837
X0769399Y0783530
X0755841Y0820341
X0755841Y0857152
X0739699Y0790223
X0739699Y0827034
X0739699Y0863845
X0755841Y0786877
X0755841Y0823688
X0755841Y0860499
X0739699Y0786877
X0739699Y0823688
X0739699Y0860499
X0739699Y0870538
X0739699Y0877231
X0755841Y0880577
X0755841Y0793570
X0755841Y0800263
X0739699Y0796916
X0739699Y0803609
X0755841Y0806955
X0755841Y0813648
X0739699Y0810302
X0739699Y0816995
X0755841Y0830381
X0755841Y0837074
X0739699Y0833727
X0739699Y0840420
X0755841Y0843766
X0755841Y0850459
X0739699Y0847113
X0739699Y0853806
X0755841Y0867192
X0755841Y0873885
X0696441Y0820341
X0696441Y0857152
X0680299Y0790223
X0680299Y0827034
X0680299Y0863845
X0696441Y0786877
X0696441Y0823688
X0696441Y0860499
X0680299Y0786877
X0680299Y0823688
X0680299Y0860499
X0680299Y0870538
X0680299Y0877231
X0696441Y0880577
X0696441Y0793570
X0696441Y0800263
X0680299Y0796916
X0680299Y0803609
X0696441Y0806955
X0696441Y0813648
X0680299Y0810302
X0680299Y0816995
X0696441Y0830381
X0696441Y0837074
X0680299Y0833727
X0680299Y0840420
X0696441Y0843766
X0696441Y0850459
X0680299Y0847113
X0680299Y0853806
X0696441Y0867192
X0696441Y0873885
X0675441Y0790223
X0675441Y0796916
X0680299Y0793570
X0680299Y0800263
X0675441Y0803609
X0680299Y0806955
X0680299Y0813648
X0680299Y0820341
X0675441Y0810302
X0676403Y0816995
X0680299Y0830381
X0676625Y0827034
X0675441Y0833727
X0675441Y0840420
X0680299Y0837074
X0680299Y0843766
X0680299Y0850459
X0675441Y0847113
X0676600Y0863845
X0680299Y0857152
X0680299Y0867192
X0676417Y0853806
X0680299Y0873885
X0680299Y0880577
X0675441Y0870538
X0675441Y0877231
X0688999Y0793570
X0688999Y0800263
X0696441Y0790223
X0696441Y0796916
X0696441Y0803609
X0688999Y0806955
X0688999Y0813648
X0689888Y0820341
X0696441Y0810302
X0696441Y0816995
X0688999Y0830381
X0696441Y0827034
X0696441Y0833727
X0688999Y0837074
X0688999Y0843766
X0696441Y0840420
X0688999Y0850459
X0696441Y0847113
X0689896Y0857152
X0688999Y0867192
X0696441Y0853806
X0696441Y0863845
X0688999Y0873885
X0688999Y0880577
X0696441Y0870538
X0696441Y0877231
X0705141Y0790223
X0705141Y0796916
X0705141Y0803609
X0709999Y0793570
X0709999Y0800263
X0705141Y0810302
X0705141Y0816995
X0709999Y0806955
X0709999Y0813648
X0709999Y0820341
X0705141Y0827034
X0705141Y0833727
X0709999Y0830381
X0705141Y0840420
X0709999Y0837074
X0709999Y0843766
X0709999Y0850459
X0705141Y0847113
X0709999Y0857152
X0709999Y0867192
X0705141Y0853806
X0705141Y0863845
X0709999Y0873885
X0709999Y0880577
X0705141Y0870538
X0705141Y0877231
X0718699Y0793570
X0718699Y0800263
X0726141Y0790223
X0726141Y0796916
X0726141Y0803609
X0718699Y0806955
X0718699Y0813648
X0718699Y0820341
X0726141Y0810302
X0726141Y0816995
X0718699Y0830381
X0726141Y0827034
X0726141Y0833727
X0718699Y0837074
X0718699Y0843766
X0718699Y0850459
X0726141Y0840420
X0726141Y0847113
X0718699Y0857152
X0718699Y0867192
X0726141Y0853806
X0726141Y0863845
X0718699Y0873885
X0718699Y0880577
X0726141Y0870538
X0726141Y0877231
X0734841Y0790223
X0734841Y0796916
X0734841Y0803609
X0739699Y0793570
X0739699Y0800263
X0734841Y0810302
X0734841Y0816995
X0739699Y0806955
X0739699Y0813648
X0739699Y0820341
X0734841Y0827034
X0734841Y0833727
X0739699Y0830381
X0734841Y0840420
X0734841Y0847113
X0739699Y0837074
X0739699Y0843766
X0739699Y0850459
X0734841Y0853806
X0734841Y0863845
X0739699Y0857152
X0739699Y0867192
X0734841Y0870538
X0734841Y0877231
X0739699Y0873885
X0739699Y0880577
X0748399Y0793570
X0748399Y0800263
X0755841Y0790223
X0755841Y0796916
X0755841Y0803609
X0748399Y0806955
X0748399Y0813648
X0748399Y0820341
X0755841Y0810302
X0755841Y0816995
X0748399Y0830381
X0755841Y0827034
X0755841Y0833727
X0748399Y0837074
X0748399Y0843766
X0748399Y0850459
X0755841Y0840420
X0755841Y0847113
X0748399Y0857152
X0748399Y0867192
X0755841Y0853806
X0755841Y0863845
X0748399Y0873885
X0748399Y0880577
X0755841Y0870538
X0755841Y0877231
X0764541Y0790223
X0764541Y0796916
X0764541Y0803609
X0769399Y0793570
X0769399Y0800263
X0764541Y0810302
X0764541Y0816995
X0769399Y0806955
X0769399Y0813648
X0769399Y0820341
X0764541Y0827034
X0764541Y0833727
X0769399Y0830381
X0764541Y0840420
X0764541Y0847113
X0769399Y0837074
X0769399Y0843766
X0769399Y0850459
X0764541Y0853806
X0764541Y0863845
X0769399Y0857152
X0769399Y0867192
X0764541Y0870538
X0764541Y0877231
X0769399Y0873885
X0769399Y0880577
X0755841Y0954200
X0755841Y0957546
X0696441Y0954200
X0696441Y0957546
X0726041Y0954200
X0726041Y0957546
X0739699Y0957546
X0769399Y0957546
X0755741Y0970932
X0739699Y0937467
X0755841Y0893963
X0755841Y0930774
X0739699Y0900656
X0739699Y0934121
X0755841Y0897310
X0755841Y0934121
X0739699Y0897310
X0755841Y0887270
X0739699Y0883924
X0739699Y0890617
X0755841Y0904003
X0755841Y0910696
X0739699Y0907349
X0739699Y0914042
X0755841Y0964239
X0739699Y0967585
X0769399Y0967585
X0755841Y0940814
X0755841Y0947507
X0739699Y0944160
X0739699Y0950853
X0755841Y0917389
X0755841Y0924081
X0739699Y0920735
X0739699Y0927428
X0739699Y0974278
X0755841Y0977625
X0739699Y0980971
X0739699Y0960892
X0769399Y0960892
X0680299Y0957546
X0709899Y0957546
X0696441Y0970932
X0680299Y0937467
X0696441Y0893963
X0696441Y0930774
X0680299Y0900656
X0680299Y0934121
X0696441Y0897310
X0696441Y0934121
X0680299Y0897310
X0696441Y0887270
X0680299Y0883924
X0680299Y0890617
X0696441Y0904003
X0696441Y0910696
X0680299Y0907349
X0680299Y0914042
X0696441Y0964239
X0680299Y0967585
X0726141Y0964239
X0709999Y0967585
X0696441Y0940814
X0696441Y0947507
X0680299Y0944160
X0680299Y0950853
X0696441Y0917389
X0696441Y0924081
X0680299Y0920735
X0680299Y0927428
X0680299Y0974278
X0696441Y0977625
X0680299Y0980971
X0680299Y0960892
X0709899Y0960892
X0675441Y0883924
X0675441Y0890617
X0680299Y0887270
X0680299Y0893963
X0675441Y0900656
X0675441Y0907349
X0680299Y0904003
X0680299Y0910696
X0680299Y0917389
X0675441Y0914042
X0680299Y0924081
X0680299Y0930774
X0675441Y0920735
X0676488Y0927428
X0680299Y0940814
X0680299Y0947507
X0676359Y0937467
X0675441Y0944160
X0675441Y0950853
X0680299Y0954200
X0675441Y0960892
X0680299Y0964239
X0680299Y0977625
X0675441Y0967585
X0675441Y0974278
X0680299Y0970932
X0675441Y0980971
X0696441Y0883924
X0688999Y0887270
X0688999Y0893963
X0696441Y0890617
X0696441Y0900656
X0688999Y0904003
X0688999Y0910696
X0688999Y0917389
X0696441Y0907349
X0696441Y0914042
X0688999Y0924081
X0690104Y0930774
X0696441Y0920735
X0696441Y0927428
X0688999Y0940814
X0688999Y0947507
X0696441Y0937467
X0696441Y0944160
X0688999Y0954200
X0688999Y0964239
X0696441Y0950853
X0696441Y0960892
X0688999Y0977625
X0688999Y0970932
X0696441Y0967585
X0696441Y0974278
X0696441Y0980971
X0705141Y0883924
X0709999Y0887270
X0709999Y0893963
X0705141Y0890617
X0705141Y0900656
X0709999Y0904003
X0709999Y0910696
X0709999Y0917389
X0705141Y0907349
X0705141Y0914042
X0709999Y0924081
X0709999Y0930774
X0705141Y0920735
X0705141Y0927428
X0709999Y0940814
X0709999Y0947507
X0705141Y0937467
X0705141Y0944160
X0709999Y0954200
X0709999Y0964239
X0705141Y0950853
X0705141Y0960892
X0709999Y0970932
X0709999Y0977625
X0705141Y0967585
X0705141Y0974278
X0705141Y0980971
X0726141Y0883924
X0718699Y0887270
X0718699Y0893963
X0726141Y0890617
X0726141Y0900656
X0718699Y0904003
X0718699Y0910696
X0718699Y0917389
X0726141Y0907349
X0726141Y0914042
X0718699Y0924081
X0718699Y0930774
X0726141Y0920735
X0726141Y0927428
X0718699Y0940814
X0718699Y0947507
X0726141Y0937467
X0726141Y0944160
X0718699Y0954200
X0718699Y0964239
X0726141Y0950853
X0726141Y0960892
X0718699Y0970932
X0718699Y0977625
X0726141Y0967585
X0726141Y0974278
X0726141Y0980971
X0734841Y0883924
X0734841Y0890617
X0734841Y0900656
X0739699Y0887270
X0739699Y0893963
X0734841Y0907349
X0734841Y0914042
X0739699Y0904003
X0739699Y0910696
X0739699Y0917389
X0734841Y0920735
X0734841Y0927428
X0739699Y0924081
X0739699Y0930774
X0734841Y0937467
X0734841Y0944160
X0739699Y0940814
X0739699Y0947507
X0734841Y0950853
X0734841Y0960892
X0739699Y0954200
X0739699Y0964239
X0734841Y0967585
X0734841Y0974278
X0734841Y0980971
X0739699Y0970932
X0739699Y0977625
X0755841Y0883924
X0748399Y0887270
X0748399Y0893963
X0755841Y0890617
X0755841Y0900656
X0748399Y0904003
X0748399Y0910696
X0748399Y0917389
X0755841Y0907349
X0755841Y0914042
X0748399Y0924081
X0748399Y0930774
X0755841Y0920735
X0755841Y0927428
X0748399Y0940814
X0748399Y0947507
X0755841Y0937467
X0755841Y0944160
X0748399Y0954200
X0748399Y0964239
X0755841Y0950853
X0755841Y0960892
X0748399Y0970932
X0748399Y0977625
X0755841Y0967585
X0755841Y0974278
X0755841Y0980971
X0764541Y0883924
X0764541Y0890617
X0764541Y0900656
X0769399Y0887270
X0769399Y0893963
X0764541Y0907349
X0764541Y0914042
X0769399Y0904003
X0769399Y0910696
X0769399Y0917389
X0764541Y0920735
X0764541Y0927428
X0769399Y0924081
X0769399Y0930774
X0764541Y0937467
X0764541Y0944160
X0769399Y0940814
X0769399Y0947507
X0764541Y0950853
X0764541Y0960892
X0769399Y0954200
X0769399Y0964239
X0764541Y0967585
X0764541Y0974278
X0764541Y0980971
X0769399Y0970932
X0769399Y0977625
X0755841Y0994357
X0696441Y0994357
X0726041Y0994357
X0672063Y0998632
X0755541Y1057940
X0726141Y1057940
X0755841Y0984318
X0739699Y0987664
X0755841Y0991011
X0739699Y0994357
X0739699Y1021129
X0755841Y1078018
X0755841Y1081365
X0739699Y1081365
X0755841Y1051247
X0739699Y1054593
X0769399Y1054593
X0755741Y1064633
X0755676Y1071326
X0739699Y1067979
X0739699Y1074672
X0739699Y1027822
X0755841Y1031168
X0739699Y1034514
X0755541Y1037861
X0739699Y1041207
X0755541Y1044554
X0739699Y1047900
X0755841Y1024475
X0755841Y1021129
X0739699Y1061286
X0696441Y0984318
X0680299Y0987664
X0696441Y0991011
X0680299Y0994357
X0680299Y1021129
X0696441Y1078018
X0696441Y1081365
X0680299Y1081365
X0696441Y1051247
X0679999Y1054593
X0726141Y1051247
X0709999Y1054593
X0696441Y1064633
X0696441Y1071325
X0680299Y1067979
X0680299Y1074672
X0679999Y1027822
X0696441Y1031168
X0679999Y1034514
X0696141Y1037861
X0679999Y1041207
X0696141Y1044554
X0679999Y1047900
X0696441Y1024475
X0726141Y1024475
X0696441Y1021129
X0726141Y1021129
X0680299Y1061286
X0680299Y0984318
X0680299Y0991011
X0675441Y0987664
X0680299Y1017782
X0675441Y1017782
X0675441Y1027822
X0680299Y1024475
X0680299Y1031168
X0680299Y1044554
X0675441Y1034515
X0675441Y1041207
X0680299Y1037861
X0675441Y1047900
X0675441Y1061286
X0675441Y1054593
X0680299Y1051247
X0680299Y1057940
X0680299Y1064633
X0680299Y1071326
X0680299Y1078018
X0675441Y1067979
X0676341Y1074672
X0688999Y0984318
X0688999Y0991011
X0696441Y0987664
X0688999Y1017782
X0688999Y1024475
X0688999Y1031168
X0696441Y1017782
X0696441Y1027822
X0688999Y1044554
X0688999Y1037861
X0696441Y1034515
X0696441Y1041207
X0696441Y1047900
X0688999Y1051247
X0688999Y1057940
X0696441Y1061286
X0696441Y1054593
X0688999Y1064633
X0688999Y1071326
X0688999Y1077118
X0696441Y1067979
X0696441Y1074672
X0709999Y0984318
X0709999Y0991011
X0705141Y0987664
X0709999Y1017782
X0709999Y1024475
X0709999Y1031168
X0705141Y1017782
X0705141Y1027822
X0709999Y1037861
X0709999Y1044554
X0705141Y1034515
X0705141Y1041207
X0705141Y1047900
X0709999Y1051247
X0709999Y1057940
X0705141Y1061286
X0705141Y1054593
X0709999Y1064633
X0709999Y1071326
X0709999Y1078018
X0705141Y1067979
X0705141Y1074672
X0718699Y0984318
X0718699Y0991011
X0726141Y0987664
X0718699Y1017782
X0718699Y1024475
X0718699Y1031168
X0726141Y1017782
X0726141Y1027822
X0718699Y1037861
X0718699Y1044554
X0726141Y1034515
X0726141Y1041207
X0726141Y1047900
X0718699Y1051247
X0718699Y1057940
X0726141Y1054593
X0726141Y1061286
X0718699Y1064633
X0718699Y1071326
X0718699Y1078018
X0726141Y1067979
X0726141Y1074672
X0734841Y0987664
X0739699Y0984318
X0739699Y0991011
X0734841Y1017782
X0734841Y1027822
X0739699Y1017782
X0739699Y1024475
X0739699Y1031168
X0734841Y1034515
X0734841Y1041207
X0734841Y1047900
X0739699Y1037861
X0739699Y1044554
X0734841Y1054593
X0734841Y1061286
X0739699Y1051247
X0739699Y1057940
X0734841Y1067979
X0734841Y1074672
X0739699Y1064633
X0739699Y1071326
X0739699Y1078018
X0748399Y0984318
X0748399Y0991011
X0755841Y0987664
X0748399Y1017782
X0748399Y1024475
X0748399Y1031168
X0755841Y1017782
X0755841Y1027822
X0748399Y1037861
X0748399Y1044554
X0755841Y1034515
X0755841Y1041207
X0755841Y1047900
X0748399Y1051247
X0748399Y1057940
X0755841Y1061286
X0755841Y1054593
X0748399Y1064633
X0748399Y1071326
X0748399Y1078018
X0755841Y1074672
X0755841Y1067979
X0764541Y0987664
X0769399Y0984318
X0769399Y0991011
X0764541Y1017782
X0764541Y1027822
X0769399Y1017782
X0769399Y1024475
X0769399Y1031168
X0764541Y1034515
X0764541Y1041207
X0764541Y1047900
X0769399Y1037861
X0769399Y1044554
X0764541Y1061286
X0764541Y1054593
X0769399Y1051247
X0769399Y1057940
X0764541Y1074672
X0764541Y1067979
X0769399Y1064633
X0769399Y1071326
X0769399Y1078018
X0755841Y1114829
X0755841Y1151640
X0739699Y1084711
X0739699Y1121522
X0739699Y1158333
X0755841Y1118176
X0755841Y1154987
X0739699Y1118176
X0739699Y1154987
X0755841Y1101444
X0755676Y1108137
X0739699Y1104790
X0739699Y1111483
X0755841Y1124869
X0755841Y1131562
X0739699Y1128215
X0739699Y1134908
X0755841Y1138255
X0755841Y1144947
X0739699Y1141601
X0739699Y1148294
X0755841Y1161680
X0755841Y1168373
X0739699Y1165026
X0739699Y1171719
X0755841Y1175066
X0755676Y1181759
X0739699Y1178412
X0755841Y1088058
X0755841Y1094751
X0739699Y1091404
X0739699Y1098097
X0696441Y1114829
X0696441Y1151640
X0680299Y1084711
X0680299Y1121522
X0680299Y1158333
X0696441Y1118176
X0696441Y1154987
X0680299Y1118176
X0680299Y1154987
X0696441Y1101444
X0696441Y1108136
X0680299Y1104790
X0680299Y1111483
X0696441Y1124869
X0696441Y1131562
X0680299Y1128215
X0680299Y1134908
X0696441Y1138255
X0696441Y1144947
X0680299Y1141601
X0680299Y1148294
X0696441Y1161680
X0696441Y1168373
X0680299Y1165026
X0680299Y1171719
X0696441Y1175066
X0696441Y1181758
X0680299Y1178412
X0696441Y1088058
X0696441Y1094751
X0680299Y1091404
X0680299Y1098097
X0680299Y1088058
X0680299Y1094751
X0676241Y1084711
X0675441Y1091404
X0675441Y1098097
X0675441Y1104790
X0680299Y1101444
X0680299Y1108137
X0675441Y1111483
X0675441Y1121522
X0680299Y1114829
X0680299Y1124869
X0675441Y1128215
X0675441Y1134908
X0675441Y1141601
X0680299Y1131562
X0680299Y1138255
X0680299Y1144948
X0680299Y1151641
X0680299Y1161680
X0676241Y1158333
X0676652Y1148294
X0675441Y1171719
X0680299Y1168373
X0680299Y1175066
X0675441Y1165026
X0675441Y1178412
X0680299Y1181759
X0688999Y1088058
X0688999Y1094751
X0696441Y1084711
X0696441Y1091404
X0688999Y1101444
X0688999Y1108137
X0696441Y1098097
X0696441Y1104790
X0696441Y1111483
X0688999Y1114829
X0688999Y1124869
X0696441Y1121522
X0696441Y1128215
X0688999Y1131562
X0688999Y1138255
X0688999Y1144948
X0696441Y1134908
X0696441Y1141601
X0689999Y1151641
X0688999Y1161680
X0696441Y1148294
X0696441Y1158333
X0688999Y1168373
X0688999Y1175066
X0696441Y1165026
X0696441Y1171719
X0688999Y1181759
X0696441Y1178412
X0709999Y1088058
X0709999Y1094751
X0705141Y1084711
X0705141Y1091404
X0709999Y1101444
X0709999Y1108137
X0705141Y1098097
X0705141Y1104790
X0705141Y1111483
X0709999Y1114829
X0709999Y1124869
X0705141Y1121522
X0705141Y1128215
X0709999Y1131562
X0709999Y1138255
X0709999Y1144948
X0705141Y1134908
X0705141Y1141601
X0709999Y1151641
X0709999Y1161680
X0705141Y1148294
X0705141Y1158333
X0709999Y1168373
X0709999Y1175066
X0705141Y1165026
X0705141Y1171719
X0709999Y1181759
X0705141Y1178412
X0718699Y1088058
X0718699Y1094751
X0726141Y1084711
X0726141Y1091404
X0718699Y1101444
X0718699Y1108137
X0726141Y1098097
X0726141Y1104790
X0726141Y1111483
X0718699Y1114829
X0718699Y1124869
X0726141Y1121522
X0726141Y1128215
X0718699Y1131562
X0718699Y1138255
X0718699Y1144948
X0726141Y1134908
X0726141Y1141601
X0718699Y1151641
X0718699Y1161680
X0726141Y1148294
X0726141Y1158333
X0718699Y1168373
X0718699Y1175066
X0726141Y1165026
X0726141Y1171719
X0718699Y1181759
X0726141Y1178412
X0734841Y1084711
X0734841Y1091404
X0739699Y1088058
X0739699Y1094751
X0734841Y1098097
X0734841Y1104790
X0734841Y1111483
X0739699Y1101444
X0739699Y1108137
X0734841Y1121522
X0734841Y1128215
X0739699Y1114829
X0739699Y1124869
X0734841Y1134908
X0734841Y1141601
X0739699Y1131562
X0739699Y1138255
X0739699Y1144948
X0734841Y1148294
X0734841Y1158333
X0739699Y1151641
X0739699Y1161680
X0734841Y1165026
X0734841Y1171719
X0739699Y1168373
X0739699Y1175066
X0734841Y1178412
X0739699Y1181759
X0748399Y1088058
X0748399Y1094751
X0755841Y1091404
X0755841Y1084711
X0748399Y1101444
X0748399Y1108137
X0755841Y1098097
X0755841Y1104790
X0755841Y1111483
X0748399Y1114829
X0748399Y1124869
X0755841Y1121522
X0755841Y1128215
X0748399Y1131562
X0748399Y1138255
X0748399Y1144948
X0755841Y1134908
X0755841Y1141601
X0748399Y1151641
X0748399Y1161680
X0755841Y1148294
X0755841Y1158333
X0748399Y1168373
X0748399Y1175066
X0755841Y1165026
X0755841Y1171719
X0748399Y1181759
X0755841Y1178412
X0764541Y1091404
X0764541Y1084711
X0769399Y1088058
X0769399Y1094751
X0764541Y1098097
X0764541Y1104790
X0764541Y1111483
X0769399Y1101444
X0769399Y1108137
X0764541Y1121522
X0764541Y1128215
X0769399Y1114829
X0769399Y1124869
X0764541Y1134908
X0764541Y1141601
X0769399Y1131562
X0769399Y1138255
X0769399Y1144948
X0764541Y1148294
X0764541Y1158333
X0769399Y1151641
X0769399Y1161680
X0764541Y1165026
X0764541Y1171719
X0769399Y1168373
X0769399Y1175066
X0764541Y1178412
X0769399Y1181759
X0750040Y1254179
X0766148Y1255882
X0692233Y1252480
X0706493Y1256563
X0755841Y1248688
X0755841Y1252034
X0737580Y1262074
X0767080Y1262074
X0696441Y1248688
X0705037Y1252034
X0677980Y1262074
X0726141Y1248688
X0734967Y1252034
X0708090Y1262074
X0675537Y1248885
X0753000Y1261352
X0694100Y1261562
X0723700Y1258727
X0755890Y1255381
X0696441Y1255381
X0680299Y1258727
X0709999Y1258727
X0739699Y1258727
X0769399Y1258727
X0769399Y1265420
X0755797Y1265420
X0755841Y1262074
X0739697Y1265420
X0726107Y1265420
X0726141Y1262074
X0709977Y1264985
X0705167Y1262074
X0696046Y1263764
X0680046Y1264964
X0755676Y1188452
X0755841Y1225262
X0739699Y1195144
X0739699Y1231955
X0755841Y1191798
X0755841Y1228609
X0739699Y1191798
X0739699Y1228609
X0739699Y1201837
X0739699Y1208530
X0755841Y1211877
X0755841Y1218569
X0739699Y1215223
X0739699Y1221916
X0755841Y1235302
X0755841Y1241995
X0739699Y1238648
X0739699Y1185105
X0755841Y1198491
X0755841Y1205184
X0739699Y1245341
X0696441Y1188451
X0696441Y1225262
X0680299Y1195144
X0680299Y1231955
X0696441Y1191798
X0696441Y1228609
X0680299Y1191798
X0680299Y1228609
X0680299Y1201837
X0680299Y1208530
X0696441Y1211877
X0696441Y1218569
X0680299Y1215223
X0680299Y1221916
X0696441Y1235302
X0696441Y1241995
X0680299Y1238648
X0680299Y1185105
X0696441Y1198491
X0696441Y1205184
X0680299Y1245341
X0750890Y1248500
X0675441Y1185105
X0680299Y1188452
X0675441Y1195144
X0675441Y1201837
X0675441Y1208530
X0680299Y1198491
X0680299Y1205184
X0680299Y1211877
X0675441Y1215223
X0676448Y1221916
X0680299Y1225263
X0680299Y1218570
X0680299Y1235302
X0680299Y1241995
X0676462Y1231955
X0675441Y1238648
X0680299Y1248688
X0676046Y1257964
X0675441Y1245341
X0672446Y1273364
X0688999Y1188452
X0696441Y1185105
X0688999Y1198491
X0688999Y1205184
X0696441Y1195144
X0696441Y1201837
X0696441Y1208530
X0688999Y1211877
X0689799Y1225263
X0688999Y1218570
X0696441Y1215223
X0696441Y1221916
X0688999Y1235302
X0688999Y1241995
X0696441Y1231955
X0696441Y1238648
X0688999Y1248688
X0696441Y1245341
X0688916Y1256964
X0683346Y1273364
X0686146Y1273364
X0709999Y1188452
X0705141Y1185105
X0709999Y1198491
X0709999Y1205184
X0705141Y1195144
X0705141Y1201837
X0705141Y1208530
X0709999Y1211877
X0709999Y1218570
X0709999Y1225263
X0705141Y1215223
X0705141Y1221916
X0709999Y1235302
X0709999Y1241995
X0705141Y1231955
X0705141Y1238648
X0709999Y1248688
X0705141Y1245341
X0699346Y1273364
X0702146Y1273364
X0713046Y1273364
X0718699Y1188452
X0726141Y1185105
X0718699Y1198491
X0718699Y1205184
X0726141Y1195144
X0726141Y1201837
X0726141Y1208530
X0718699Y1211877
X0718699Y1218570
X0718699Y1225263
X0726141Y1215223
X0726141Y1221916
X0718699Y1235302
X0718699Y1241995
X0726141Y1231955
X0726141Y1238648
X0718699Y1248688
X0719046Y1257064
X0726141Y1245341
X0715846Y1273364
X0729046Y1273364
X0734841Y1185105
X0739699Y1188452
X0734841Y1195144
X0734841Y1201837
X0734841Y1208530
X0739699Y1198491
X0739699Y1205184
X0734841Y1215223
X0734841Y1221916
X0739699Y1211877
X0739699Y1218570
X0739699Y1225263
X0734841Y1231955
X0734841Y1238648
X0739699Y1235302
X0739699Y1241995
X0734841Y1245341
X0739699Y1248688
X0731372Y1273464
X0742746Y1273364
X0745546Y1273364
X0748399Y1188452
X0755841Y1185105
X0748399Y1198491
X0748399Y1205184
X0755841Y1195144
X0755841Y1201837
X0755841Y1208530
X0748399Y1211877
X0748399Y1218570
X0748399Y1225263
X0755841Y1215223
X0755841Y1221916
X0748399Y1235302
X0748399Y1241995
X0755841Y1231955
X0755841Y1238648
X0748399Y1248688
X0748283Y1256964
X0755841Y1245341
X0761546Y1273364
X0758746Y1273364
X0764541Y1185105
X0769399Y1188452
X0764541Y1195144
X0764541Y1201837
X0764541Y1208530
X0769399Y1198491
X0769399Y1205184
X0764541Y1215223
X0764541Y1221916
X0769399Y1211877
X0769399Y1218570
X0769399Y1225263
X0764541Y1231955
X0764541Y1238648
X0769399Y1235302
X0769399Y1241995
X0764541Y1245341
X0769399Y1248688
X0796280Y1254402
X0826501Y1254553
X0815241Y1248688
X0823877Y1252034
X0796880Y1262074
X0844997Y1248155
X0844941Y1252034
X0826750Y1262074
X0785541Y1248688
X0794157Y1252034
X0812440Y1258727
X0844941Y1258727
X0783130Y1259372
X0842630Y1256912
X0799099Y1258727
X0828799Y1258727
X0844941Y1262074
X0844941Y1265420
X0828799Y1265420
X0815241Y1262074
X0815241Y1265420
X0799099Y1265420
X0785541Y1262074
X0785541Y1265420
X0815241Y1188451
X0815241Y1225263
X0799099Y1195144
X0799099Y1231955
X0815241Y1191798
X0815241Y1228609
X0799099Y1191798
X0799099Y1228609
X0799099Y1201837
X0799099Y1208530
X0815241Y1211877
X0815241Y1218570
X0799099Y1215223
X0799099Y1221916
X0815241Y1235302
X0815241Y1241995
X0799099Y1238648
X0799099Y1185105
X0815241Y1198491
X0815241Y1205184
X0799099Y1245341
X0778099Y1188452
X0778099Y1198491
X0778099Y1205184
X0778099Y1211877
X0778099Y1218570
X0778099Y1225263
X0778099Y1235302
X0778099Y1241995
X0778099Y1248688
X0778346Y1257264
X0775246Y1273364
X0772446Y1273364
X0794241Y1185105
X0785541Y1185105
X0794241Y1201837
X0785541Y1201837
X0794241Y1195144
X0785541Y1195144
X0794241Y1208530
X0785541Y1208530
X0794241Y1215223
X0785541Y1215223
X0794241Y1221916
X0785541Y1221916
X0794241Y1231955
X0785541Y1231955
X0794241Y1238648
X0785541Y1238648
X0794241Y1245341
X0785541Y1245341
X0791246Y1273364
X0788446Y1273364
X0807799Y1188452
X0799099Y1188452
X0807799Y1198491
X0799099Y1198491
X0807799Y1205184
X0799099Y1205184
X0807799Y1218570
X0799099Y1218570
X0807799Y1211877
X0799099Y1211877
X0807799Y1225263
X0799099Y1225263
X0807799Y1235302
X0799099Y1235302
X0807799Y1241995
X0799099Y1241995
X0808046Y1257664
X0807799Y1248688
X0799099Y1248688
X0802146Y1273364
X0804946Y1273364
X0823941Y1185105
X0815241Y1185105
X0823941Y1201837
X0815241Y1201837
X0823941Y1195144
X0815241Y1195144
X0823941Y1208530
X0815241Y1208530
X0823941Y1215223
X0815241Y1215223
X0823941Y1221916
X0815241Y1221916
X0823941Y1231955
X0815241Y1231955
X0823941Y1238648
X0815241Y1238648
X0823941Y1245341
X0815241Y1245341
X0818146Y1273364
X0820946Y1273364
X0837499Y1188452
X0828799Y1188452
X0828799Y1198491
X0837499Y1198491
X0828799Y1205184
X0837499Y1205184
X0828799Y1211877
X0837499Y1211877
X0828799Y1218570
X0837499Y1218570
X0828799Y1225263
X0837499Y1225263
X0828799Y1235302
X0837499Y1235302
X0828799Y1241995
X0837499Y1241995
X0837846Y1256964
X0828799Y1248688
X0837499Y1248688
X0834646Y1273364
X0831846Y1273364
X0842046Y1273064
X0839246Y1273064
X0853641Y1185105
X0844941Y1185105
X0853641Y1195144
X0844941Y1195144
X0853641Y1201837
X0844941Y1201837
X0853641Y1208530
X0844941Y1208530
X0853641Y1215223
X0844941Y1215223
X0853641Y1221916
X0844941Y1221916
X0853641Y1231955
X0844941Y1231955
X0853641Y1238648
X0844941Y1238648
X0853641Y1245341
X0844941Y1245341
X0815241Y1114829
X0815241Y1151640
X0799099Y1084711
X0799099Y1121522
X0799099Y1158333
X0815241Y1118176
X0815241Y1154987
X0799099Y1118176
X0799099Y1154987
X0815241Y1101444
X0815241Y1108136
X0799099Y1104790
X0799099Y1111483
X0815241Y1124869
X0815241Y1131562
X0799099Y1128215
X0799099Y1134908
X0815241Y1138255
X0815241Y1144947
X0799099Y1141601
X0799099Y1148294
X0815241Y1161680
X0815241Y1168373
X0799099Y1165026
X0799099Y1171719
X0815241Y1175066
X0815241Y1181758
X0799099Y1178412
X0815241Y1088058
X0815241Y1094751
X0799099Y1091404
X0799099Y1098097
X0778099Y1088058
X0778099Y1094751
X0778099Y1101444
X0778099Y1108137
X0778099Y1114829
X0778099Y1124869
X0778099Y1131562
X0778099Y1138255
X0778099Y1144948
X0778099Y1151641
X0778099Y1161680
X0778099Y1168373
X0778099Y1175066
X0778099Y1181759
X0794241Y1084711
X0785541Y1084711
X0794241Y1091404
X0785541Y1091404
X0794241Y1098097
X0785541Y1098097
X0794241Y1104790
X0785541Y1104790
X0794241Y1111483
X0785541Y1111483
X0794241Y1121522
X0785541Y1121522
X0794241Y1128215
X0785541Y1128215
X0794241Y1134908
X0785541Y1134908
X0794241Y1141601
X0785541Y1141601
X0794241Y1148294
X0785541Y1148294
X0794241Y1158333
X0785541Y1158333
X0794241Y1165026
X0785541Y1165026
X0794241Y1171719
X0785541Y1171719
X0794241Y1178412
X0785541Y1178412
X0807799Y1088058
X0799099Y1088058
X0807799Y1094751
X0799099Y1094751
X0807799Y1101444
X0799099Y1101444
X0807799Y1108137
X0799099Y1108137
X0807799Y1114829
X0799099Y1114829
X0807799Y1124869
X0799099Y1124869
X0807799Y1131562
X0799099Y1131562
X0807799Y1138255
X0799099Y1138255
X0807799Y1144948
X0799099Y1144948
X0807799Y1151641
X0799099Y1151641
X0807799Y1161680
X0799099Y1161680
X0807799Y1168373
X0799099Y1168373
X0807799Y1175066
X0799099Y1175066
X0807799Y1181759
X0799099Y1181759
X0823941Y1084711
X0815241Y1084711
X0823941Y1091404
X0815241Y1091404
X0823941Y1098097
X0815241Y1098097
X0823941Y1104790
X0815241Y1104790
X0823941Y1111483
X0815241Y1111483
X0823941Y1121522
X0815241Y1121522
X0823941Y1128215
X0815241Y1128215
X0823941Y1134908
X0815241Y1134908
X0823941Y1141601
X0815241Y1141601
X0823941Y1148294
X0815241Y1148294
X0823941Y1158333
X0815241Y1158333
X0823941Y1165026
X0815241Y1165026
X0823941Y1171719
X0815241Y1171719
X0823941Y1178412
X0815241Y1178412
X0828799Y1088058
X0837499Y1088058
X0837499Y1094751
X0828799Y1094751
X0837499Y1101444
X0828799Y1101444
X0828799Y1108137
X0837499Y1108137
X0828799Y1114829
X0837499Y1114829
X0828799Y1124869
X0837499Y1124869
X0828799Y1131562
X0837499Y1131562
X0828799Y1138255
X0837499Y1138255
X0828799Y1144948
X0837499Y1144948
X0828799Y1151641
X0837499Y1151641
X0828799Y1161680
X0837499Y1161680
X0828799Y1168373
X0837499Y1168373
X0828799Y1175066
X0837499Y1175066
X0828799Y1181759
X0837499Y1181759
X0853641Y1084711
X0844941Y1084711
X0853641Y1091404
X0844941Y1091404
X0853641Y1098097
X0844941Y1098097
X0853641Y1104790
X0844941Y1104790
X0853641Y1111483
X0844941Y1111483
X0853641Y1121522
X0844941Y1121522
X0853641Y1128215
X0844941Y1128215
X0853641Y1134908
X0844941Y1134908
X0853641Y1141601
X0844941Y1141601
X0853641Y1148294
X0844941Y1148294
X0853641Y1158333
X0844941Y1158333
X0853641Y1165026
X0844941Y1165026
X0853641Y1171719
X0844941Y1171719
X0853641Y1178412
X0844941Y1178412
X0815241Y0994357
X0844841Y0994357
X0785541Y0994357
X0815241Y0984318
X0799099Y0987664
X0815241Y0991011
X0799099Y0994357
X0799099Y1021129
X0815241Y1078018
X0815241Y1081365
X0799099Y1081365
X0814941Y1051247
X0799099Y1054593
X0844941Y1051247
X0828799Y1054593
X0815241Y1064633
X0815241Y1071325
X0799099Y1067979
X0799099Y1074672
X0799099Y1027822
X0815241Y1031168
X0799099Y1034515
X0815241Y1037861
X0799099Y1041207
X0815241Y1044554
X0799099Y1047900
X0815241Y1024475
X0844941Y1024475
X0815241Y1021129
X0844941Y1021129
X0799099Y1061286
X0785541Y1051247
X0785541Y1024475
X0785541Y1021129
X0778099Y0984318
X0778099Y0991011
X0778099Y1017782
X0778099Y1024475
X0778099Y1031168
X0778099Y1037861
X0778099Y1044554
X0778099Y1051247
X0778099Y1057940
X0778099Y1064633
X0778099Y1071326
X0778099Y1078018
X0794241Y0987664
X0785541Y0987664
X0794241Y1017782
X0785541Y1017782
X0794241Y1027822
X0785541Y1027822
X0794241Y1034515
X0785541Y1034515
X0794241Y1041207
X0785541Y1041207
X0794241Y1047900
X0785541Y1047900
X0794241Y1061286
X0785541Y1061286
X0794241Y1054593
X0785541Y1054593
X0794241Y1067979
X0785541Y1067979
X0794241Y1074672
X0785541Y1074672
X0807799Y0984318
X0799099Y0984318
X0807799Y0991011
X0799099Y0991011
X0807799Y1017782
X0799099Y1017782
X0807799Y1024475
X0799099Y1024475
X0807799Y1031168
X0799099Y1031168
X0807799Y1044554
X0799099Y1044554
X0807799Y1037861
X0799099Y1037861
X0807799Y1051247
X0799099Y1051247
X0807799Y1057940
X0799099Y1057940
X0807799Y1064633
X0799099Y1064633
X0807799Y1071326
X0799099Y1071326
X0807799Y1078018
X0799099Y1078018
X0823941Y0987664
X0815241Y0987664
X0823941Y1017782
X0815241Y1017782
X0823941Y1027822
X0815241Y1027822
X0823941Y1034515
X0815241Y1034515
X0823941Y1041207
X0815241Y1041207
X0823941Y1047900
X0815241Y1047900
X0823941Y1061286
X0815241Y1061286
X0823941Y1054593
X0815241Y1054593
X0823941Y1067979
X0815241Y1067979
X0823941Y1074672
X0815241Y1074672
X0837499Y0984318
X0828799Y0984318
X0837499Y0991011
X0828799Y0991011
X0837499Y1017782
X0828799Y1017782
X0837499Y1024475
X0828799Y1024475
X0837499Y1031168
X0828799Y1031168
X0837499Y1037861
X0828799Y1037861
X0837499Y1044554
X0828799Y1044554
X0837499Y1051247
X0828799Y1051247
X0837499Y1057940
X0828799Y1057940
X0837499Y1064633
X0828799Y1064633
X0837499Y1071326
X0828799Y1071326
X0837499Y1078018
X0828799Y1078018
X0853641Y0987664
X0844941Y0987664
X0853641Y1017782
X0844941Y1017782
X0853641Y1027822
X0844941Y1027822
X0853641Y1034515
X0844941Y1034515
X0853641Y1041207
X0844941Y1041207
X0853641Y1047900
X0844941Y1047900
X0853641Y1054593
X0844941Y1054593
X0853641Y1061286
X0844941Y1061286
X0853641Y1067979
X0844941Y1067979
X0853641Y1074672
X0844941Y1074672
X0815241Y0954200
X0815241Y0957546
X0844841Y0954200
X0844841Y0957546
X0785541Y0954200
X0785541Y0957546
X0799099Y0957546
X0828799Y0957546
X0815241Y0970932
X0799099Y0937467
X0815241Y0893963
X0815241Y0930774
X0799099Y0900656
X0799099Y0934121
X0815241Y0897310
X0815241Y0934121
X0799099Y0897310
X0815241Y0887270
X0799099Y0883924
X0799099Y0890617
X0815241Y0904003
X0815241Y0910696
X0799099Y0907349
X0799099Y0914042
X0815241Y0964239
X0799099Y0967585
X0844941Y0964239
X0828799Y0967585
X0815241Y0940814
X0815241Y0947507
X0799099Y0944160
X0799099Y0950853
X0815241Y0917389
X0815241Y0924081
X0799099Y0920735
X0799099Y0927428
X0799099Y0974278
X0815241Y0977625
X0799099Y0980971
X0799099Y0960892
X0828799Y0960892
X0785541Y0964239
X0778099Y0887270
X0778099Y0893963
X0778099Y0904003
X0778099Y0910696
X0778099Y0917389
X0778099Y0924081
X0778099Y0930774
X0778099Y0940814
X0778099Y0947507
X0778099Y0954200
X0778099Y0964239
X0778099Y0970932
X0778099Y0977625
X0794241Y0883924
X0785541Y0883924
X0794241Y0890617
X0785541Y0890617
X0794241Y0900656
X0785541Y0900656
X0794241Y0914042
X0785541Y0914042
X0794241Y0907349
X0785541Y0907349
X0794241Y0927428
X0785541Y0927428
X0794241Y0920735
X0785541Y0920735
X0794241Y0944160
X0785541Y0944160
X0794241Y0937467
X0785541Y0937467
X0794241Y0950853
X0785541Y0950853
X0794241Y0960892
X0785541Y0960892
X0794241Y0967585
X0785541Y0967585
X0794241Y0974278
X0785541Y0974278
X0794241Y0980971
X0785541Y0980971
X0807799Y0893963
X0799099Y0893963
X0807799Y0887270
X0799099Y0887270
X0807799Y0910696
X0799099Y0910696
X0807799Y0904003
X0799099Y0904003
X0807799Y0917389
X0799099Y0917389
X0807799Y0924081
X0799099Y0924081
X0807799Y0930774
X0799099Y0930774
X0807799Y0940814
X0799099Y0940814
X0807799Y0947507
X0799099Y0947507
X0807799Y0954200
X0799099Y0954200
X0807799Y0964239
X0799099Y0964239
X0807799Y0977625
X0799099Y0977625
X0807799Y0970932
X0799099Y0970932
X0823941Y0883924
X0815241Y0883924
X0823941Y0890617
X0815241Y0890617
X0823941Y0900656
X0815241Y0900656
X0823941Y0914042
X0815241Y0914042
X0823941Y0907349
X0815241Y0907349
X0823941Y0927428
X0815241Y0927428
X0823941Y0920735
X0815241Y0920735
X0823941Y0944160
X0815241Y0944160
X0823941Y0937467
X0815241Y0937467
X0823941Y0950853
X0815241Y0950853
X0823941Y0960892
X0815241Y0960892
X0823941Y0967585
X0815241Y0967585
X0823941Y0974278
X0815241Y0974278
X0823941Y0980971
X0815241Y0980971
X0837499Y0887270
X0828799Y0887270
X0837499Y0893963
X0828799Y0893963
X0828799Y0910696
X0837499Y0910696
X0828799Y0904003
X0837499Y0904003
X0837499Y0917389
X0828799Y0917389
X0837499Y0924081
X0828799Y0924081
X0837499Y0930774
X0828799Y0930774
X0837499Y0940814
X0828799Y0940814
X0837499Y0947507
X0828799Y0947507
X0837499Y0954200
X0828799Y0954200
X0837499Y0964239
X0828799Y0964239
X0837499Y0970932
X0828799Y0970932
X0837499Y0977625
X0828799Y0977625
X0853641Y0883924
X0844941Y0883924
X0853641Y0890617
X0844941Y0890617
X0853641Y0900656
X0844941Y0900656
X0853641Y0907349
X0844941Y0907349
X0853641Y0914042
X0844941Y0914042
X0853641Y0920735
X0844941Y0920735
X0853641Y0927428
X0844941Y0927428
X0853641Y0937467
X0844941Y0937467
X0853641Y0944160
X0844941Y0944160
X0853641Y0950853
X0844941Y0950853
X0853641Y0960892
X0844941Y0960892
X0853641Y0967585
X0844941Y0967585
X0853641Y0974278
X0844941Y0974278
X0853641Y0980971
X0844941Y0980971
X0815241Y0820341
X0815241Y0857152
X0799099Y0790223
X0799099Y0827034
X0799099Y0863845
X0815241Y0786877
X0815241Y0823688
X0815241Y0860499
X0799099Y0786877
X0799099Y0823688
X0799099Y0860499
X0799099Y0870538
X0799099Y0877231
X0815241Y0880577
X0815241Y0793570
X0815241Y0800263
X0799099Y0796916
X0799099Y0803609
X0815241Y0806955
X0815241Y0813648
X0799099Y0810302
X0799099Y0816995
X0815241Y0830381
X0815241Y0837074
X0799099Y0833727
X0799099Y0840420
X0815241Y0843766
X0815241Y0850459
X0799099Y0847113
X0799099Y0853806
X0815241Y0867192
X0815241Y0873885
X0778099Y0793570
X0778099Y0800263
X0778099Y0806955
X0778099Y0813648
X0778099Y0820341
X0778099Y0830381
X0778099Y0837074
X0778099Y0843766
X0778099Y0850459
X0778099Y0857152
X0778099Y0867192
X0778099Y0873885
X0778099Y0880577
X0794241Y0796916
X0785541Y0796916
X0794241Y0790223
X0785541Y0790223
X0794241Y0803609
X0785541Y0803609
X0794241Y0810302
X0785541Y0810302
X0794241Y0816995
X0785541Y0816995
X0794241Y0827034
X0785541Y0827034
X0794241Y0833727
X0785541Y0833727
X0794241Y0847113
X0785541Y0847113
X0794241Y0840420
X0785541Y0840420
X0794241Y0863845
X0785541Y0863845
X0794241Y0853806
X0785541Y0853806
X0794241Y0877231
X0785541Y0877231
X0794241Y0870538
X0785541Y0870538
X0807799Y0793570
X0799099Y0793570
X0807799Y0800263
X0799099Y0800263
X0807799Y0813648
X0799099Y0813648
X0807799Y0806955
X0799099Y0806955
X0807799Y0820341
X0799099Y0820341
X0807799Y0830381
X0799099Y0830381
X0807799Y0843766
X0799099Y0843766
X0807799Y0837074
X0799099Y0837074
X0807799Y0850459
X0799099Y0850459
X0807799Y0857152
X0799099Y0857152
X0807799Y0867192
X0799099Y0867192
X0807799Y0880577
X0799099Y0880577
X0807799Y0873885
X0799099Y0873885
X0823941Y0796916
X0815241Y0796916
X0823941Y0790223
X0815241Y0790223
X0823941Y0803609
X0815241Y0803609
X0823941Y0810302
X0815241Y0810302
X0823941Y0816995
X0815241Y0816995
X0823941Y0827034
X0815241Y0827034
X0823941Y0833727
X0815241Y0833727
X0823941Y0847113
X0815241Y0847113
X0823941Y0840420
X0815241Y0840420
X0823941Y0863845
X0815241Y0863845
X0823941Y0853806
X0815241Y0853806
X0823941Y0877231
X0815241Y0877231
X0823941Y0870538
X0815241Y0870538
X0828799Y0793570
X0837499Y0793570
X0828799Y0800263
X0837499Y0800263
X0837499Y0806955
X0828799Y0806955
X0837499Y0813648
X0828799Y0813648
X0837499Y0820341
X0828799Y0820341
X0837499Y0830381
X0828799Y0830381
X0837499Y0837074
X0828799Y0837074
X0837499Y0843766
X0828799Y0843766
X0837499Y0850459
X0828799Y0850459
X0837499Y0857152
X0828799Y0857152
X0837499Y0867192
X0828799Y0867192
X0837499Y0873885
X0828799Y0873885
X0837499Y0880577
X0828799Y0880577
X0853641Y0790223
X0844941Y0790223
X0853641Y0796916
X0844941Y0796916
X0853641Y0803609
X0844941Y0803609
X0853641Y0810302
X0844941Y0810302
X0853641Y0816995
X0844941Y0816995
X0853641Y0827034
X0844941Y0827034
X0853641Y0833727
X0844941Y0833727
X0853641Y0840420
X0844941Y0840420
X0853641Y0847113
X0844941Y0847113
X0853641Y0853806
X0844941Y0853806
X0853641Y0863845
X0844941Y0863845
X0853641Y0870538
X0844941Y0870538
X0853641Y0877231
X0844941Y0877231
X0797417Y0767345
X0828699Y0766798
X0815241Y0783530
X0815241Y0770144
X0815241Y0776837
X0799099Y0773491
X0799099Y0780184
X0778099Y0770144
X0778099Y0776837
X0778099Y0783530
X0794241Y0766798
X0785541Y0766798
X0794241Y0780184
X0785541Y0780184
X0794241Y0773491
X0785541Y0773491
X0807799Y0770144
X0799099Y0770144
X0807799Y0776837
X0799099Y0776837
X0807799Y0783530
X0799099Y0783530
X0823941Y0766798
X0815241Y0766798
X0823941Y0780184
X0815241Y0780184
X0823941Y0773491
X0815241Y0773491
X0837499Y0770144
X0828799Y0770144
X0837499Y0776837
X0828799Y0776837
X0837499Y0783530
X0828799Y0783530
X0853641Y0766798
X0844941Y0766798
X0853641Y0773491
X0844941Y0773491
X0853641Y0780184
X0844941Y0780184
X0918264Y0506011
X1030270Y1256042
X1002070Y1256942
X1059410Y1252272
X1058383Y1248688
X1044930Y1263492
X1030780Y1266532
X1019983Y1248688
X1019983Y1252034
X1003841Y1262074
X1061330Y1262074
X1049683Y1258727
X1030830Y1261302
X1047010Y1259222
X1019983Y1255381
X1033541Y1258727
X1063241Y1258727
X1003831Y1259077
X1063241Y1265420
X1049683Y1262074
X1049683Y1265420
X1033541Y1265420
X1019983Y1265420
X1019983Y1262074
X1003841Y1265420
X1058383Y1188452
X1058383Y1225263
X1042241Y1195144
X1042241Y1231955
X1058383Y1191798
X1058383Y1228609
X1042241Y1191798
X1042241Y1228609
X1042241Y1201837
X1042241Y1208530
X1058383Y1211877
X1058383Y1218570
X1042241Y1215223
X1042241Y1221916
X1058383Y1235302
X1058383Y1241995
X1042241Y1238648
X1042241Y1185105
X1058383Y1198491
X1058383Y1205184
X1042241Y1245341
X1001970Y1251522
X1017900Y1247632
X1003841Y1188452
X1003841Y1198491
X1003841Y1205184
X1003841Y1211877
X1003841Y1218570
X1003841Y1225263
X1003841Y1235302
X1003841Y1241995
X1003841Y1248688
X1012541Y1188452
X1019983Y1185105
X1012541Y1198491
X1012541Y1205184
X1019983Y1195144
X1019983Y1201837
X1019983Y1208530
X1012541Y1211877
X1012541Y1218570
X1012541Y1225263
X1019983Y1215223
X1019983Y1221916
X1012541Y1235302
X1012541Y1241995
X1019983Y1231955
X1019983Y1238648
X1012541Y1248688
X1019983Y1245341
X1012543Y1257198
X1014111Y1273299
X1017111Y1273299
X1028683Y1185105
X1033541Y1188452
X1028683Y1195144
X1028683Y1201837
X1028683Y1208530
X1033541Y1198491
X1033541Y1205184
X1028683Y1215223
X1028683Y1221916
X1033541Y1211877
X1033541Y1218570
X1033541Y1225263
X1028683Y1231955
X1028683Y1238648
X1033541Y1235302
X1033541Y1241995
X1028683Y1245341
X1033541Y1248688
X1025688Y1273344
X1022888Y1273344
X1036588Y1273344
X1042241Y1188452
X1049683Y1185105
X1042241Y1198491
X1042241Y1205184
X1049683Y1195144
X1049683Y1201837
X1049683Y1208530
X1042241Y1211877
X1042241Y1218570
X1042241Y1225263
X1049683Y1221916
X1049683Y1215223
X1042241Y1235302
X1042241Y1241995
X1049683Y1231955
X1049683Y1238648
X1042241Y1248688
X1049683Y1245341
X1042331Y1257488
X1039388Y1273344
X1052588Y1273344
X1058383Y1185105
X1063241Y1188452
X1058383Y1195144
X1058383Y1201837
X1058383Y1208530
X1063241Y1198491
X1063241Y1205184
X1058383Y1221916
X1058383Y1215223
X1063241Y1211877
X1063241Y1218570
X1063241Y1225263
X1058383Y1231955
X1058383Y1238648
X1063241Y1235302
X1063241Y1241995
X1058383Y1245341
X1063241Y1248688
X1055388Y1273344
X1066288Y1273344
X1069088Y1273344
X1058383Y1114829
X1058383Y1151641
X1042241Y1084711
X1042241Y1121522
X1042241Y1158333
X1058383Y1118176
X1058383Y1154987
X1042241Y1118176
X1042241Y1154987
X1058383Y1101444
X1058383Y1108137
X1042241Y1104790
X1042241Y1111483
X1058383Y1124869
X1058383Y1131562
X1042241Y1128215
X1042241Y1134908
X1058383Y1138255
X1058383Y1144948
X1042241Y1141601
X1042241Y1148294
X1058383Y1161680
X1058383Y1168373
X1042241Y1165026
X1042241Y1171719
X1058383Y1175066
X1058383Y1181759
X1042241Y1178412
X1058383Y1088058
X1058383Y1094751
X1042241Y1091404
X1042241Y1098097
X1003841Y1088058
X1003841Y1094751
X1003841Y1101444
X1003841Y1108137
X1003841Y1114829
X1003841Y1124869
X1003841Y1131562
X1003841Y1138255
X1003841Y1144948
X1003841Y1151641
X1003841Y1161680
X1003841Y1168373
X1003841Y1175066
X1003841Y1181759
X1012541Y1088058
X1012541Y1094751
X1019983Y1084711
X1019983Y1091404
X1012541Y1101444
X1012541Y1108137
X1019983Y1098097
X1019983Y1104790
X1019983Y1111483
X1012541Y1114829
X1012541Y1124869
X1019983Y1121522
X1019983Y1128215
X1012541Y1131562
X1012541Y1138255
X1012541Y1144948
X1019983Y1134908
X1019983Y1141601
X1012541Y1151641
X1012541Y1161680
X1019983Y1148294
X1019983Y1158333
X1012541Y1168373
X1012541Y1175066
X1019983Y1165026
X1019983Y1171719
X1012541Y1181759
X1019983Y1178412
X1028683Y1084711
X1028683Y1091404
X1033541Y1088058
X1033541Y1094751
X1028683Y1098097
X1028683Y1104790
X1028683Y1111483
X1033541Y1101444
X1033541Y1108137
X1028683Y1121522
X1028683Y1128215
X1033541Y1124869
X1033541Y1114829
X1028683Y1134908
X1028683Y1141601
X1033541Y1131562
X1033541Y1138255
X1033541Y1144948
X1028683Y1148294
X1028683Y1158333
X1033541Y1151641
X1033541Y1161680
X1028683Y1165026
X1028683Y1171719
X1033541Y1168373
X1033541Y1175066
X1028683Y1178412
X1033541Y1181759
X1042241Y1088058
X1042241Y1094751
X1049683Y1084711
X1049683Y1091404
X1042241Y1101444
X1042241Y1108137
X1049683Y1098097
X1049683Y1104790
X1049683Y1111483
X1042241Y1124869
X1049683Y1121522
X1049683Y1128215
X1042241Y1114829
X1042241Y1131562
X1042241Y1138255
X1042241Y1144948
X1049683Y1134908
X1049683Y1141601
X1042241Y1151641
X1049683Y1148294
X1049683Y1158333
X1042241Y1161680
X1042241Y1168373
X1042241Y1175066
X1049683Y1165026
X1049683Y1171719
X1042241Y1181759
X1049683Y1178412
X1058383Y1084711
X1058383Y1091404
X1063241Y1088058
X1063241Y1094751
X1058383Y1098097
X1058383Y1104790
X1058383Y1111483
X1063241Y1101444
X1063241Y1108137
X1058383Y1121522
X1058383Y1128215
X1063241Y1114829
X1063241Y1124869
X1058383Y1134908
X1058383Y1141601
X1063241Y1131562
X1063241Y1138255
X1063241Y1144948
X1058383Y1148294
X1058383Y1158333
X1063241Y1151641
X1063241Y1161680
X1058383Y1165026
X1058383Y1171719
X1063241Y1168373
X1063241Y1175066
X1058383Y1178412
X1063241Y1181759
X1058383Y0994357
X1019983Y0994357
X1058383Y0984318
X1042241Y0987664
X1058383Y0991011
X1042241Y0994357
X1042241Y1021129
X1058383Y1078018
X1058383Y1081365
X1042241Y1081365
X1058383Y1051247
X1042241Y1054593
X1028683Y1051247
X1012541Y1054593
X1058383Y1064633
X1058383Y1071326
X1042241Y1067979
X1042241Y1074672
X1042241Y1027822
X1058383Y1031168
X1042241Y1034515
X1058383Y1037861
X1042241Y1041207
X1058383Y1044554
X1042241Y1047900
X1058383Y1024475
X1028683Y1024475
X1058383Y1021129
X1028683Y1021129
X1042241Y1061286
X1003841Y0984318
X1003841Y0991011
X1003841Y1017782
X1003841Y1024475
X1003841Y1031168
X1003841Y1037861
X1003841Y1044554
X1003841Y1051247
X1003841Y1057940
X1003841Y1064633
X1003841Y1071326
X1003841Y1078018
X1012541Y0984318
X1012541Y0991011
X1019983Y0987664
X1012541Y1017782
X1012541Y1024475
X1012541Y1031168
X1019983Y1017782
X1019983Y1027822
X1012541Y1037861
X1012541Y1044554
X1019983Y1034515
X1019983Y1041207
X1019983Y1047900
X1012541Y1051247
X1012541Y1057940
X1019983Y1054593
X1019983Y1061286
X1012541Y1064633
X1012541Y1071326
X1012541Y1078018
X1019983Y1074672
X1019983Y1067979
X1028683Y0987664
X1033541Y0984318
X1033541Y0991011
X1028683Y1017782
X1028683Y1027822
X1033541Y1024475
X1033541Y1017782
X1033541Y1031168
X1028683Y1034515
X1028683Y1041207
X1028683Y1047900
X1033541Y1037861
X1033541Y1044554
X1028683Y1054593
X1028683Y1061286
X1033541Y1051247
X1033541Y1057940
X1028683Y1074672
X1028683Y1067979
X1033541Y1064633
X1033541Y1071326
X1033541Y1078018
X1042241Y0984318
X1042241Y0991011
X1049683Y0987664
X1042241Y1024475
X1042241Y1017782
X1042241Y1031168
X1049683Y1017782
X1049683Y1027822
X1042241Y1037861
X1042241Y1044554
X1049683Y1034515
X1049683Y1041207
X1049683Y1047900
X1042241Y1051247
X1042241Y1057940
X1049683Y1054593
X1049683Y1061286
X1042241Y1064633
X1042241Y1071326
X1042241Y1078018
X1049683Y1067979
X1049683Y1074672
X1058383Y0987664
X1063241Y0984318
X1063241Y0991011
X1058383Y1017782
X1058383Y1027822
X1063241Y1017782
X1063241Y1024475
X1063241Y1031168
X1058383Y1034515
X1058383Y1041207
X1058383Y1047900
X1063241Y1037861
X1063241Y1044554
X1058383Y1054593
X1058383Y1061286
X1063241Y1051247
X1063241Y1057940
X1058383Y1067979
X1058383Y1074672
X1063241Y1064633
X1063241Y1071326
X1063241Y1078018
X1058383Y0954200
X1058383Y0957546
X1028683Y0954200
X1028683Y0957546
X1042241Y0957546
X1012541Y0957546
X1058383Y0970932
X1042241Y0937467
X1058383Y0893963
X1058383Y0930774
X1042241Y0900656
X1042241Y0934121
X1058383Y0897310
X1058383Y0934121
X1042241Y0897310
X1058383Y0887270
X1042241Y0883924
X1042241Y0890617
X1058383Y0904003
X1058383Y0910696
X1042241Y0907349
X1042241Y0914042
X1058383Y0964239
X1042241Y0967585
X1028683Y0964239
X1012541Y0967585
X1058383Y0940814
X1058383Y0947507
X1042241Y0944160
X1042241Y0950853
X1058383Y0917389
X1058383Y0924081
X1042241Y0920735
X1042241Y0927428
X1042241Y0974278
X1058383Y0977625
X1042241Y0980971
X1042241Y0960892
X1012541Y0960892
X1003841Y0887270
X1003841Y0893963
X1003841Y0904003
X1003841Y0910696
X1003841Y0917389
X1003841Y0924081
X1003841Y0930774
X1003841Y0940814
X1003841Y0947507
X1003841Y0954200
X1003841Y0964239
X1003841Y0970932
X1003841Y0977625
X1019983Y0883924
X1012541Y0887270
X1012541Y0893963
X1019983Y0890617
X1019983Y0900656
X1012541Y0904003
X1012541Y0910696
X1012541Y0917389
X1019983Y0907349
X1019983Y0914042
X1012541Y0924081
X1012541Y0930774
X1019983Y0920735
X1019983Y0927428
X1012541Y0940814
X1012541Y0947507
X1019983Y0937467
X1019983Y0944160
X1012541Y0954200
X1012541Y0964239
X1019983Y0950853
X1019983Y0960892
X1012541Y0970932
X1012541Y0977625
X1019983Y0967585
X1019983Y0974278
X1019983Y0980971
X1028683Y0883924
X1028683Y0890617
X1028683Y0900656
X1033541Y0887270
X1033541Y0893963
X1028683Y0907349
X1028683Y0914042
X1033541Y0904003
X1033541Y0910696
X1033541Y0917389
X1028683Y0920735
X1028683Y0927428
X1033541Y0924081
X1033541Y0930774
X1028683Y0937467
X1028683Y0944160
X1033541Y0940814
X1033541Y0947507
X1028683Y0950853
X1028683Y0960892
X1033541Y0954200
X1033541Y0964239
X1028683Y0967585
X1028683Y0974278
X1028683Y0980971
X1033541Y0970932
X1033541Y0977625
X1049683Y0883924
X1042241Y0887270
X1042241Y0893963
X1049683Y0890617
X1049683Y0900656
X1042241Y0904003
X1042241Y0910696
X1042241Y0917389
X1049683Y0907349
X1049683Y0914042
X1042241Y0924081
X1042241Y0930774
X1049683Y0920735
X1049683Y0927428
X1042241Y0940814
X1042241Y0947507
X1049683Y0937467
X1049683Y0944160
X1042241Y0954200
X1042241Y0964239
X1049683Y0950853
X1049683Y0960892
X1042241Y0970932
X1042241Y0977625
X1049683Y0967585
X1049683Y0974278
X1049683Y0980971
X1058383Y0883924
X1058383Y0890617
X1058383Y0900656
X1063241Y0887270
X1063241Y0893963
X1058383Y0907349
X1058383Y0914042
X1063241Y0904003
X1063241Y0910696
X1063241Y0917389
X1058383Y0920735
X1058383Y0927428
X1063241Y0924081
X1063241Y0930774
X1058383Y0937467
X1058383Y0944160
X1063241Y0940814
X1063241Y0947507
X1058383Y0950853
X1058383Y0960892
X1063241Y0954200
X1063241Y0964239
X1058383Y0967585
X1058383Y0974278
X1058383Y0980971
X1063241Y0970932
X1063241Y0977625
X1058383Y0820341
X1058383Y0857152
X1042241Y0790223
X1042241Y0827034
X1042241Y0863845
X1058383Y0786877
X1058383Y0823688
X1058383Y0860499
X1042241Y0786877
X1042241Y0823688
X1042241Y0860499
X1042241Y0870538
X1042241Y0877231
X1058383Y0880577
X1058383Y0793570
X1058383Y0800263
X1042241Y0796916
X1042241Y0803609
X1058383Y0806955
X1058383Y0813648
X1042241Y0810302
X1042241Y0816995
X1058383Y0830381
X1058383Y0837074
X1042241Y0833727
X1042241Y0840420
X1058383Y0843766
X1058383Y0850459
X1042241Y0847113
X1042241Y0853806
X1058383Y0867192
X1058383Y0873885
X1003841Y0793570
X1003841Y0800263
X1003841Y0806955
X1003841Y0813648
X1003841Y0820341
X1003841Y0830381
X1003841Y0837074
X1003841Y0843766
X1003841Y0850459
X1003841Y0857152
X1003841Y0867192
X1003841Y0873885
X1003841Y0880577
X1012541Y0793570
X1012541Y0800263
X1019983Y0790223
X1019983Y0796916
X1019983Y0803609
X1012541Y0806955
X1012541Y0813648
X1012541Y0820341
X1019983Y0810302
X1019983Y0816995
X1012541Y0830381
X1019983Y0827034
X1019983Y0833727
X1012541Y0837074
X1012541Y0843766
X1012541Y0850459
X1019983Y0840420
X1019983Y0847113
X1012541Y0857152
X1012541Y0867192
X1019983Y0853806
X1019983Y0863845
X1012541Y0873885
X1012541Y0880577
X1019983Y0870538
X1019983Y0877231
X1028683Y0790223
X1028683Y0796916
X1028683Y0803609
X1033541Y0793570
X1033541Y0800263
X1028683Y0810302
X1028683Y0816995
X1033541Y0806955
X1033541Y0813648
X1033541Y0820341
X1028683Y0827034
X1028683Y0833727
X1033541Y0830381
X1028683Y0840420
X1028683Y0847113
X1033541Y0837074
X1033541Y0843766
X1033541Y0850459
X1028683Y0853806
X1028683Y0863845
X1033541Y0857152
X1033541Y0867192
X1028683Y0870538
X1028683Y0877231
X1033541Y0873885
X1033541Y0880577
X1042241Y0793570
X1042241Y0800263
X1049683Y0790223
X1049683Y0796916
X1049683Y0803609
X1042241Y0806955
X1042241Y0813648
X1042241Y0820341
X1049683Y0810302
X1049683Y0816995
X1042241Y0830381
X1049683Y0827034
X1049683Y0833727
X1042241Y0837074
X1042241Y0843766
X1042241Y0850459
X1049683Y0840420
X1049683Y0847113
X1042241Y0857152
X1042241Y0867192
X1049683Y0853806
X1049683Y0863845
X1042241Y0873885
X1042241Y0880577
X1049683Y0870538
X1049683Y0877231
X1058383Y0790223
X1058383Y0796916
X1058383Y0803609
X1063241Y0793570
X1063241Y0800263
X1058383Y0810302
X1058383Y0816995
X1063241Y0806955
X1063241Y0813648
X1063241Y0820341
X1058383Y0827034
X1058383Y0833727
X1063241Y0830381
X1058383Y0840420
X1058383Y0847113
X1063241Y0837074
X1063241Y0843766
X1063241Y0850459
X1058383Y0853806
X1058383Y0863845
X1063241Y0857152
X1063241Y0867192
X1058383Y0870538
X1058383Y0877231
X1063241Y0873885
X1063241Y0880577
X1033441Y0766798
X1012769Y0766798
X1063141Y0766798
X1058383Y0783530
X1058383Y0770144
X1058383Y0776837
X1042241Y0773491
X1042241Y0780184
X1003841Y0770144
X1003841Y0776837
X1003841Y0783530
X1012541Y0770144
X1019983Y0766798
X1012541Y0776837
X1012541Y0783530
X1019983Y0773491
X1019983Y0780184
X1028683Y0766798
X1033541Y0770144
X1028683Y0773491
X1028683Y0780184
X1033541Y0776837
X1033541Y0783530
X1042241Y0770144
X1049683Y0766798
X1042241Y0776837
X1042241Y0783530
X1049683Y0773491
X1049683Y0780184
X1058383Y0766798
X1063241Y0770144
X1058383Y0773491
X1058383Y0780184
X1063241Y0776837
X1063241Y0783530
X1092709Y0766775
X1152241Y0766798
X1122541Y0766798
X1117783Y0783530
X1117783Y0770144
X1117783Y0776837
X1101641Y0773491
X1101641Y0780184
X1161041Y0773491
X1161041Y0780184
X1071941Y0770144
X1079383Y0766798
X1071941Y0776837
X1071941Y0783530
X1079383Y0773491
X1079383Y0780184
X1088083Y0766798
X1101641Y0770144
X1092941Y0770144
X1088083Y0773491
X1088083Y0780184
X1101641Y0776837
X1092941Y0776837
X1101641Y0783530
X1092941Y0783530
X1117783Y0766798
X1109083Y0766798
X1109083Y0773491
X1117783Y0773491
X1109083Y0780184
X1117783Y0780184
X1122641Y0770144
X1131341Y0770144
X1122641Y0776837
X1131341Y0776837
X1122641Y0783530
X1131341Y0783530
X1138783Y0766798
X1147483Y0766798
X1152341Y0770144
X1147483Y0773491
X1138783Y0773491
X1138783Y0780184
X1147483Y0780184
X1152341Y0776837
X1152341Y0783530
X1161041Y0770144
X1168483Y0766798
X1161041Y0776837
X1161041Y0783530
X1168483Y0773491
X1168483Y0780184
X1117783Y0820341
X1117783Y0857152
X1101641Y0790223
X1101641Y0827034
X1101641Y0863845
X1117783Y0786877
X1117783Y0823688
X1117783Y0860499
X1101641Y0786877
X1101641Y0823688
X1101641Y0860499
X1101641Y0870538
X1101641Y0877231
X1117783Y0880577
X1117783Y0793570
X1117783Y0800263
X1101641Y0796916
X1101641Y0803609
X1117783Y0806955
X1117783Y0813648
X1101641Y0810302
X1101641Y0816995
X1117783Y0830381
X1117783Y0837074
X1101641Y0833727
X1101641Y0840420
X1117783Y0843766
X1117783Y0850459
X1101641Y0847113
X1101641Y0853806
X1117783Y0867192
X1117783Y0873885
X1161041Y0790223
X1161041Y0827034
X1161041Y0863845
X1161041Y0786877
X1161041Y0823688
X1161041Y0860499
X1161041Y0870538
X1161041Y0877231
X1161041Y0796916
X1161041Y0803609
X1161041Y0810302
X1161041Y0816995
X1161041Y0833727
X1161041Y0840420
X1161041Y0847113
X1161041Y0853806
X1071941Y0793570
X1071941Y0800263
X1079383Y0790223
X1079383Y0796916
X1079383Y0803609
X1071941Y0806955
X1071941Y0813648
X1071941Y0820341
X1079383Y0810302
X1079383Y0816995
X1071941Y0830381
X1079383Y0827034
X1079383Y0833727
X1071941Y0837074
X1071941Y0843766
X1071941Y0850459
X1079383Y0840420
X1079383Y0847113
X1071941Y0857152
X1071941Y0867192
X1079383Y0853806
X1079383Y0863845
X1071941Y0873885
X1071941Y0880577
X1079383Y0870538
X1079383Y0877231
X1088083Y0790223
X1088083Y0796916
X1088083Y0803609
X1092941Y0793570
X1101641Y0793570
X1092941Y0800263
X1101641Y0800263
X1088083Y0810302
X1088083Y0816995
X1092941Y0806955
X1101641Y0806955
X1092941Y0813648
X1101641Y0813648
X1092941Y0820341
X1101641Y0820341
X1088083Y0827034
X1088083Y0833727
X1092941Y0830381
X1101641Y0830381
X1088083Y0840420
X1088083Y0847113
X1092941Y0837074
X1101641Y0837074
X1092941Y0843766
X1101641Y0843766
X1092941Y0850459
X1101641Y0850459
X1088083Y0853806
X1088083Y0863845
X1092941Y0857152
X1101641Y0857152
X1092941Y0867192
X1101641Y0867192
X1088083Y0870538
X1088083Y0877231
X1092941Y0873885
X1101641Y0873885
X1092941Y0880577
X1101641Y0880577
X1117783Y0790223
X1109083Y0790223
X1109083Y0796916
X1117783Y0796916
X1109083Y0803609
X1117783Y0803609
X1109083Y0810302
X1117783Y0810302
X1109083Y0816995
X1117783Y0816995
X1109083Y0827034
X1117783Y0827034
X1109083Y0833727
X1117783Y0833727
X1109083Y0840420
X1117783Y0840420
X1109083Y0847113
X1117783Y0847113
X1109083Y0853806
X1117783Y0853806
X1109083Y0863845
X1117783Y0863845
X1109083Y0870538
X1117783Y0870538
X1109083Y0877231
X1117783Y0877231
X1122641Y0793570
X1131341Y0793570
X1122641Y0800263
X1131341Y0800263
X1122641Y0806955
X1131341Y0806955
X1122641Y0813648
X1131341Y0813648
X1122641Y0820341
X1131341Y0820341
X1122641Y0830381
X1131341Y0830381
X1122641Y0837074
X1131341Y0837074
X1122641Y0843766
X1131341Y0843766
X1122641Y0850459
X1131341Y0850459
X1122641Y0857152
X1131341Y0857152
X1122641Y0867192
X1131341Y0867192
X1122641Y0873885
X1131341Y0873885
X1122641Y0880577
X1131341Y0880577
X1138783Y0790223
X1147483Y0790223
X1138783Y0796916
X1147483Y0796916
X1152341Y0793570
X1138783Y0803609
X1147483Y0803609
X1152341Y0800263
X1138783Y0810302
X1147483Y0810302
X1152341Y0806955
X1152341Y0813648
X1138783Y0816995
X1147483Y0816995
X1152341Y0820341
X1138783Y0827034
X1147483Y0827034
X1152341Y0830381
X1138783Y0833727
X1147483Y0833727
X1138783Y0840420
X1147483Y0840420
X1138783Y0847113
X1147483Y0847113
X1152341Y0837074
X1152341Y0843766
X1152341Y0850459
X1138783Y0853806
X1147483Y0853806
X1138783Y0863845
X1147483Y0863845
X1152341Y0857152
X1152341Y0867192
X1138783Y0870538
X1147483Y0870538
X1138783Y0877231
X1147483Y0877231
X1152341Y0873885
X1152341Y0880577
X1161041Y0793570
X1161041Y0800263
X1168483Y0790223
X1168483Y0796916
X1168483Y0803609
X1161041Y0806955
X1161041Y0813648
X1161041Y0820341
X1168483Y0810302
X1168483Y0816995
X1161041Y0830381
X1167633Y0827034
X1168483Y0833727
X1161041Y0837074
X1161041Y0843766
X1161041Y0850459
X1168483Y0840420
X1168483Y0847113
X1161041Y0857152
X1168483Y0853806
X1161041Y0867192
X1167633Y0863845
X1161041Y0873885
X1161041Y0880577
X1168483Y0870538
X1168483Y0877231
X1117783Y0954200
X1117783Y0957546
X1088083Y0954200
X1088083Y0957546
X1147483Y0954200
X1147483Y0957546
X1101641Y0957546
X1071941Y0957546
X1117783Y0970932
X1101641Y0937467
X1117783Y0893963
X1117783Y0930774
X1101641Y0900656
X1101641Y0934121
X1117783Y0897310
X1117783Y0934121
X1101641Y0897310
X1117783Y0887270
X1101641Y0883924
X1101641Y0890617
X1117783Y0904003
X1117783Y0910696
X1101641Y0907349
X1101641Y0914042
X1117783Y0964239
X1101641Y0967585
X1088083Y0964239
X1071941Y0967585
X1117783Y0940814
X1117783Y0947507
X1101641Y0944160
X1101641Y0950853
X1117783Y0917389
X1117783Y0924081
X1101641Y0920735
X1101641Y0927428
X1101641Y0974278
X1117783Y0977625
X1101641Y0980971
X1101641Y0960892
X1071941Y0960892
X1161041Y0957546
X1131341Y0957546
X1161041Y0937467
X1161041Y0900656
X1161041Y0934121
X1161041Y0897310
X1161041Y0883924
X1161041Y0890617
X1161041Y0907349
X1161041Y0914042
X1161041Y0967585
X1147483Y0964239
X1131341Y0967585
X1161041Y0944160
X1161041Y0950853
X1161041Y0920735
X1161041Y0927428
X1161041Y0974278
X1161041Y0980971
X1161041Y0960892
X1131341Y0960892
X1079383Y0883924
X1071941Y0887270
X1071941Y0893963
X1079383Y0890617
X1079383Y0900656
X1071941Y0904003
X1071941Y0910696
X1071941Y0917389
X1079383Y0907349
X1079383Y0914042
X1071941Y0924081
X1071941Y0930774
X1079383Y0920735
X1079383Y0927428
X1071941Y0940814
X1071941Y0947507
X1079383Y0937467
X1079383Y0944160
X1071941Y0954200
X1071941Y0964239
X1079383Y0950853
X1079383Y0960892
X1071941Y0970932
X1071941Y0977625
X1079383Y0967585
X1079383Y0974278
X1079383Y0980971
X1088083Y0883924
X1088083Y0890617
X1088083Y0900656
X1092941Y0887270
X1101641Y0887270
X1092941Y0893963
X1101641Y0893963
X1088083Y0907349
X1088083Y0914042
X1092941Y0904003
X1101641Y0904003
X1092941Y0910696
X1101641Y0910696
X1092941Y0917389
X1101641Y0917389
X1088083Y0920735
X1088083Y0927428
X1092941Y0924081
X1101641Y0924081
X1092941Y0930774
X1101641Y0930774
X1088083Y0937467
X1088083Y0944160
X1092941Y0940814
X1101641Y0940814
X1092941Y0947507
X1101641Y0947507
X1088083Y0950853
X1088083Y0960892
X1092941Y0954200
X1101641Y0954200
X1092941Y0964239
X1101641Y0964239
X1088083Y0967585
X1088083Y0974278
X1088083Y0980971
X1092941Y0970932
X1101641Y0970932
X1092941Y0977625
X1101641Y0977625
X1109083Y0883924
X1117783Y0883924
X1109083Y0890617
X1117783Y0890617
X1109083Y0900656
X1117783Y0900656
X1109083Y0907349
X1117783Y0907349
X1109083Y0914042
X1117783Y0914042
X1109083Y0920735
X1117783Y0920735
X1109083Y0927428
X1117783Y0927428
X1109083Y0937467
X1117783Y0937467
X1109083Y0944160
X1117783Y0944160
X1109083Y0950853
X1117783Y0950853
X1109083Y0960892
X1117783Y0960892
X1109083Y0967585
X1117783Y0967585
X1109083Y0974278
X1117783Y0974278
X1109083Y0980971
X1117783Y0980971
X1122641Y0887270
X1131341Y0887270
X1122641Y0893963
X1131341Y0893963
X1122641Y0904003
X1131341Y0904003
X1122641Y0910696
X1131341Y0910696
X1122641Y0917389
X1131341Y0917389
X1122641Y0924081
X1131341Y0924081
X1122641Y0930774
X1131341Y0930774
X1122641Y0940814
X1131341Y0940814
X1131341Y0947507
X1122641Y0947507
X1122641Y0954200
X1131341Y0954200
X1122641Y0964239
X1131341Y0964239
X1122641Y0970932
X1131341Y0970932
X1122641Y0977625
X1131341Y0977625
X1138783Y0883924
X1147483Y0883924
X1147483Y0890617
X1138783Y0890617
X1147483Y0900656
X1138783Y0900656
X1152341Y0887270
X1152341Y0893963
X1138783Y0907349
X1147483Y0907349
X1138783Y0914042
X1147483Y0914042
X1152341Y0904003
X1152341Y0910696
X1152341Y0917389
X1138783Y0920735
X1147483Y0920735
X1138783Y0927428
X1147483Y0927428
X1152341Y0924081
X1152341Y0930774
X1138783Y0937467
X1147483Y0937467
X1138783Y0944160
X1147483Y0944160
X1152341Y0940814
X1152341Y0947507
X1138783Y0950853
X1147483Y0950853
X1138783Y0960892
X1147483Y0960892
X1152341Y0954200
X1152341Y0964239
X1138783Y0967585
X1147483Y0967585
X1138783Y0974278
X1147483Y0974278
X1138783Y0980971
X1147483Y0980971
X1152341Y0970932
X1152341Y0977625
X1168483Y0883924
X1161041Y0887270
X1161041Y0893963
X1168483Y0890617
X1168483Y0900656
X1161041Y0904003
X1161041Y0910696
X1161041Y0917389
X1168483Y0907349
X1168483Y0914042
X1161041Y0924081
X1161041Y0930774
X1168483Y0920735
X1167633Y0927428
X1161041Y0940814
X1161041Y0947507
X1168483Y0944160
X1168483Y0937467
X1161041Y0954200
X1161041Y0964239
X1168483Y0950853
X1168483Y0960892
X1161041Y0970932
X1161041Y0977625
X1168483Y0967585
X1168483Y0980971
X1168483Y0974278
X1117783Y0994357
X1079383Y0994357
X1138783Y0994357
X1117783Y1057940
X1117783Y0984318
X1101641Y0987664
X1117783Y0991011
X1101641Y0994357
X1101641Y1021129
X1117783Y1078018
X1117783Y1081365
X1101641Y1081365
X1117783Y1051247
X1101641Y1054593
X1088083Y1051247
X1071941Y1054593
X1117783Y1064633
X1117783Y1071326
X1101641Y1067979
X1101641Y1074672
X1101641Y1027822
X1117783Y1031168
X1101641Y1034515
X1117783Y1037861
X1101641Y1041207
X1117783Y1044554
X1101641Y1047900
X1117783Y1024475
X1088083Y1024475
X1117783Y1021129
X1088083Y1021129
X1101641Y1061286
X1161041Y0987664
X1161041Y0994357
X1161041Y1021129
X1161041Y1081365
X1161041Y1054593
X1147483Y1051247
X1131341Y1054593
X1161041Y1067979
X1161041Y1074672
X1161041Y1027822
X1161041Y1034515
X1161041Y1041207
X1161041Y1047900
X1147483Y1024475
X1147483Y1021129
X1161041Y1061286
X1071941Y0984318
X1071941Y0991011
X1079383Y0987664
X1071941Y1017782
X1071941Y1024475
X1071941Y1031168
X1079383Y1017782
X1079383Y1027822
X1071941Y1037861
X1071941Y1044554
X1079383Y1034515
X1079383Y1041207
X1079383Y1047900
X1071941Y1051247
X1071941Y1057940
X1079383Y1054593
X1079383Y1061286
X1071941Y1064633
X1071941Y1071326
X1071941Y1078018
X1079383Y1067979
X1079383Y1074672
X1088083Y0987664
X1092941Y0984318
X1101641Y0984318
X1092941Y0991011
X1101641Y0991011
X1088083Y1017782
X1088083Y1027822
X1092941Y1017782
X1101641Y1017782
X1092941Y1024475
X1101641Y1024475
X1092941Y1031168
X1101641Y1031168
X1088083Y1034515
X1088083Y1041207
X1088083Y1047900
X1092941Y1037861
X1101641Y1037861
X1092941Y1044554
X1101641Y1044554
X1088083Y1054593
X1088083Y1061286
X1092941Y1051247
X1101641Y1051247
X1092941Y1057940
X1101641Y1057940
X1088083Y1067979
X1088083Y1074672
X1092941Y1064633
X1101641Y1064633
X1092941Y1071326
X1101641Y1071326
X1092941Y1078018
X1101641Y1078018
X1109083Y0987664
X1117783Y0987664
X1109083Y1017782
X1117783Y1017782
X1109083Y1027822
X1117783Y1027822
X1109083Y1034515
X1117783Y1034515
X1109083Y1041207
X1117783Y1041207
X1109083Y1047900
X1117783Y1047900
X1109083Y1054593
X1117783Y1054593
X1109083Y1061286
X1117783Y1061286
X1109083Y1067979
X1117783Y1067979
X1109083Y1074672
X1117783Y1074672
X1122641Y0984318
X1131341Y0984318
X1122641Y0991011
X1131341Y0991011
X1122641Y1017782
X1131341Y1017782
X1122641Y1024475
X1131341Y1024475
X1122641Y1031168
X1131341Y1031168
X1122641Y1037861
X1131341Y1037861
X1122641Y1044554
X1131341Y1044554
X1122641Y1051247
X1131341Y1051247
X1122641Y1057940
X1131341Y1057940
X1122641Y1064633
X1131341Y1064633
X1122641Y1071326
X1131341Y1071326
X1122641Y1078018
X1131341Y1078018
X1138783Y0987664
X1147483Y0987664
X1152341Y0984318
X1152341Y0991011
X1138783Y1017782
X1147483Y1017782
X1138783Y1027822
X1147483Y1027822
X1152341Y1017782
X1152341Y1024475
X1152341Y1031168
X1138783Y1034515
X1147483Y1034515
X1138783Y1041207
X1147483Y1041207
X1147483Y1047900
X1138783Y1047900
X1152341Y1037861
X1152341Y1044554
X1138783Y1054593
X1147483Y1054593
X1138783Y1061286
X1147483Y1061286
X1152341Y1051247
X1152341Y1057940
X1138783Y1067979
X1147483Y1067979
X1138783Y1074672
X1147483Y1074672
X1152341Y1064633
X1152341Y1071326
X1152341Y1078018
X1161041Y0984318
X1161041Y0991011
X1168483Y0987664
X1161041Y1017782
X1161041Y1024475
X1161041Y1031168
X1168483Y1017782
X1168483Y1027822
X1161041Y1037861
X1161041Y1044554
X1168483Y1034515
X1168483Y1041207
X1168483Y1047900
X1161041Y1051247
X1161041Y1057940
X1168483Y1061286
X1168483Y1054593
X1161041Y1064633
X1161041Y1071326
X1161041Y1078018
X1168483Y1067979
X1168483Y1074672
X1117783Y1114829
X1117783Y1151641
X1101641Y1084711
X1101641Y1121522
X1101641Y1158333
X1117783Y1118176
X1117783Y1154987
X1101641Y1118176
X1101641Y1154987
X1117783Y1101444
X1117783Y1108137
X1101641Y1104790
X1101641Y1111483
X1117783Y1124869
X1117783Y1131562
X1101641Y1128215
X1101641Y1134908
X1117783Y1138255
X1117783Y1144948
X1101641Y1141601
X1101641Y1148294
X1117783Y1161680
X1117783Y1168373
X1101641Y1165026
X1101641Y1171719
X1117783Y1175066
X1117783Y1181759
X1101641Y1178412
X1117783Y1088058
X1117783Y1094751
X1101641Y1091404
X1101641Y1098097
X1161041Y1084711
X1161041Y1121522
X1161041Y1158333
X1161041Y1118176
X1161041Y1154987
X1161041Y1104790
X1161041Y1111483
X1161041Y1128215
X1161041Y1134908
X1161041Y1141601
X1161041Y1148294
X1161041Y1165026
X1161041Y1171719
X1161041Y1178412
X1161041Y1091404
X1161041Y1098097
X1071941Y1088058
X1071941Y1094751
X1079383Y1084711
X1079383Y1091404
X1071941Y1101444
X1071941Y1108137
X1079383Y1098097
X1079383Y1104790
X1079383Y1111483
X1071941Y1114829
X1071941Y1124869
X1079383Y1121522
X1079383Y1128215
X1071941Y1131562
X1071941Y1138255
X1071941Y1144948
X1079383Y1134908
X1079383Y1141601
X1071941Y1151641
X1071941Y1161680
X1079383Y1148294
X1079383Y1158333
X1071941Y1168373
X1071941Y1175066
X1079383Y1165026
X1079383Y1171719
X1071941Y1181759
X1079383Y1178412
X1088083Y1084711
X1088083Y1091404
X1092941Y1088058
X1101641Y1088058
X1092941Y1094751
X1101641Y1094751
X1088083Y1098097
X1088083Y1104790
X1088083Y1111483
X1092941Y1101444
X1101641Y1101444
X1092941Y1108137
X1101641Y1108137
X1088083Y1121522
X1088083Y1128215
X1092941Y1114829
X1101641Y1114829
X1092941Y1124869
X1101641Y1124869
X1088083Y1134908
X1088083Y1141601
X1092941Y1131562
X1101641Y1131562
X1092941Y1138255
X1101641Y1138255
X1092941Y1144948
X1101641Y1144948
X1088083Y1148294
X1088083Y1158333
X1092941Y1151641
X1101641Y1151641
X1101641Y1161680
X1092941Y1161680
X1088083Y1165026
X1088083Y1171719
X1092941Y1168373
X1101641Y1168373
X1092941Y1175066
X1101641Y1175066
X1088083Y1178412
X1092941Y1181759
X1101641Y1181759
X1109083Y1084711
X1117783Y1084711
X1109083Y1091404
X1117783Y1091404
X1109083Y1098097
X1117783Y1098097
X1109083Y1104790
X1117783Y1104790
X1109083Y1111483
X1117783Y1111483
X1109083Y1121522
X1117783Y1121522
X1109083Y1128215
X1117783Y1128215
X1109083Y1134908
X1117783Y1134908
X1109083Y1141601
X1117783Y1141601
X1109083Y1148294
X1117783Y1148294
X1109083Y1158333
X1117783Y1158333
X1109083Y1165026
X1117783Y1165026
X1109083Y1171719
X1117783Y1171719
X1109083Y1178412
X1117783Y1178412
X1122641Y1088058
X1131341Y1088058
X1122641Y1094751
X1131341Y1094751
X1122641Y1101444
X1131341Y1101444
X1122641Y1108137
X1131341Y1108137
X1122641Y1114829
X1131341Y1114829
X1122641Y1124869
X1131341Y1124869
X1122641Y1131562
X1131341Y1131562
X1122641Y1138255
X1131341Y1138255
X1122641Y1144948
X1131341Y1144948
X1122641Y1151641
X1131341Y1151641
X1122641Y1161680
X1131341Y1161680
X1122641Y1168373
X1131341Y1168373
X1122641Y1175066
X1131341Y1175066
X1122641Y1181759
X1131341Y1181759
X1138783Y1084711
X1147483Y1084711
X1138783Y1091404
X1147483Y1091404
X1152341Y1088058
X1152341Y1094751
X1138783Y1098097
X1147483Y1098097
X1138783Y1104790
X1147483Y1104790
X1138783Y1111483
X1147483Y1111483
X1152341Y1101444
X1152341Y1108137
X1138783Y1121522
X1147483Y1121522
X1138783Y1128215
X1147483Y1128215
X1152341Y1114829
X1152341Y1124869
X1138783Y1134908
X1147483Y1134908
X1138783Y1141601
X1147483Y1141601
X1152341Y1131562
X1152341Y1138255
X1152341Y1144948
X1147483Y1148294
X1138783Y1148294
X1138783Y1158333
X1147483Y1158333
X1152341Y1151641
X1152341Y1161680
X1138783Y1165026
X1147483Y1165026
X1138783Y1171719
X1147483Y1171719
X1152341Y1168373
X1152341Y1175066
X1138783Y1178412
X1147483Y1178412
X1152341Y1181759
X1161041Y1088058
X1161041Y1094751
X1167633Y1084711
X1168483Y1091404
X1161041Y1101444
X1161041Y1108137
X1168483Y1098097
X1168483Y1104790
X1168483Y1111483
X1161041Y1114829
X1161041Y1124869
X1168483Y1121522
X1168483Y1128215
X1161041Y1131562
X1161041Y1138255
X1161041Y1144948
X1168483Y1134908
X1168483Y1141601
X1161041Y1151641
X1161041Y1161680
X1168483Y1148294
X1167633Y1158333
X1161041Y1168373
X1161041Y1175066
X1168483Y1165026
X1168483Y1171719
X1161041Y1181759
X1168483Y1178412
X1148563Y1257097
X1117783Y1248688
X1106200Y1250162
X1091000Y1262074
X1088083Y1248688
X1074480Y1263742
X1168483Y1252034
X1150400Y1262074
X1147483Y1248688
X1138783Y1252034
X1120800Y1262074
X1106740Y1267902
X1079383Y1258727
X1168483Y1258727
X1138783Y1258727
X1103530Y1263602
X1076520Y1259072
X1092941Y1258727
X1122641Y1258727
X1152341Y1258727
X1168483Y1262074
X1168483Y1265420
X1137980Y1264212
X1138783Y1262027
X1152341Y1265420
X1122620Y1264622
X1109050Y1262972
X1109083Y1265420
X1092941Y1265420
X1079383Y1262074
X1079383Y1265420
X1117783Y1188452
X1117783Y1225263
X1101641Y1195144
X1101641Y1231955
X1117783Y1191798
X1117783Y1228609
X1101641Y1191798
X1101641Y1228609
X1101641Y1201837
X1101641Y1208530
X1117783Y1211877
X1117783Y1218570
X1101641Y1215223
X1101641Y1221916
X1117783Y1235302
X1117783Y1241995
X1101641Y1238648
X1101641Y1185105
X1117783Y1198491
X1117783Y1205184
X1101641Y1245341
X1161041Y1195144
X1161041Y1231955
X1161041Y1191798
X1161041Y1228609
X1161041Y1201837
X1161041Y1208530
X1161041Y1215223
X1161041Y1221916
X1161041Y1238648
X1161041Y1185105
X1161041Y1245341
X1090273Y1246800
X1071941Y1188452
X1079383Y1185105
X1071941Y1198491
X1071941Y1205184
X1079383Y1195144
X1079383Y1201837
X1079383Y1208530
X1071941Y1211877
X1071941Y1218570
X1071941Y1225263
X1079383Y1215223
X1079383Y1221916
X1071941Y1235302
X1071941Y1241995
X1079383Y1231955
X1079383Y1238648
X1071941Y1248688
X1079383Y1245341
X1071991Y1257262
X1082288Y1273344
X1085088Y1273344
X1088083Y1185105
X1101641Y1188452
X1092941Y1188452
X1088083Y1195144
X1088083Y1201837
X1088083Y1208530
X1101641Y1198491
X1092941Y1198491
X1101641Y1205184
X1092941Y1205184
X1088083Y1215223
X1088083Y1221916
X1101641Y1211877
X1092941Y1211877
X1092941Y1218570
X1101641Y1218570
X1092941Y1225263
X1101641Y1225263
X1088083Y1231955
X1088083Y1238648
X1092941Y1235302
X1101641Y1235302
X1092941Y1241995
X1101641Y1241995
X1088083Y1245341
X1092941Y1248688
X1101641Y1248688
X1101554Y1257102
X1095988Y1273344
X1098788Y1273344
X1109083Y1185105
X1117783Y1185105
X1109083Y1195144
X1117783Y1195144
X1109083Y1201837
X1117783Y1201837
X1109083Y1208530
X1117783Y1208530
X1109083Y1215223
X1117783Y1215223
X1109083Y1221916
X1117783Y1221916
X1109083Y1231955
X1117783Y1231955
X1109083Y1238648
X1117783Y1238648
X1109083Y1245341
X1117783Y1245341
X1114788Y1273344
X1111988Y1273344
X1122641Y1188452
X1131341Y1188452
X1122641Y1198491
X1131341Y1198491
X1122641Y1205184
X1131341Y1205184
X1122641Y1211877
X1131341Y1211877
X1122641Y1218570
X1131341Y1218570
X1122641Y1225263
X1131341Y1225263
X1122641Y1235302
X1131341Y1235302
X1122641Y1241995
X1131341Y1241995
X1131341Y1248688
X1122641Y1248688
X1131434Y1257291
X1128988Y1273344
X1126188Y1273344
X1138783Y1185105
X1147483Y1185105
X1152341Y1188452
X1138783Y1195144
X1147483Y1195144
X1138783Y1201837
X1147483Y1201837
X1138783Y1208530
X1147483Y1208530
X1152341Y1198491
X1152341Y1205184
X1138783Y1215223
X1147483Y1215223
X1138783Y1221916
X1147483Y1221916
X1152341Y1211877
X1152341Y1218570
X1152341Y1225263
X1138783Y1231955
X1147483Y1231955
X1138783Y1238648
X1147483Y1238648
X1152341Y1235302
X1152341Y1241995
X1138783Y1245341
X1147483Y1245341
X1152341Y1248688
X1138201Y1270277
X1147681Y1269684
X1152381Y1269684
X1161041Y1188452
X1168483Y1185105
X1161041Y1198491
X1161041Y1205184
X1168483Y1195144
X1168483Y1201837
X1168483Y1208530
X1161041Y1211877
X1161041Y1218570
X1161041Y1225263
X1168483Y1215223
X1168483Y1221916
X1161041Y1235302
X1161041Y1241995
X1167633Y1231955
X1168483Y1238648
X1161041Y1248688
X1168483Y1245341
X1161065Y1258871
X1161781Y1269684
X1264764Y1716737
X1264764Y1721840
X1264764Y1726377
X1264764Y1730911
X1256890Y1717903
X1256890Y1722440
X1256890Y1726974
X1249016Y1716737
X1249016Y1721840
X1249016Y1726377
X1249016Y1730911
X1241142Y1717903
X1241142Y1722440
X1241142Y1726974
X1264764Y1702564
X1264764Y1712203
X1264764Y1707666
X1256890Y1712800
X1256890Y1708266
X1256890Y1703729
X1249016Y1702564
X1249016Y1712203
X1249016Y1707666
X1241142Y1712800
X1241142Y1708266
X1241142Y1703729
X1264764Y1683857
X1264764Y1698030
X1264764Y1693493
X1264764Y1688391
X1256890Y1698627
X1256890Y1694093
X1256890Y1689556
X1256890Y1684454
X1249016Y1683857
X1249016Y1698030
X1249016Y1693493
X1249016Y1688391
X1241142Y1698627
X1241142Y1694093
X1241142Y1689556
X1241142Y1684454
X1264764Y1679320
X1256890Y1679920
X1256890Y1675383
X1249016Y1679320
X1241142Y1679920
X1241142Y1675383
X1267972Y1602380
X1267972Y1614292
X1260172Y1614292
X1260172Y1602380
X1255912Y1602380
X1255912Y1614292
X1248112Y1614292
X1248112Y1602380
X1243852Y1602380
X1243852Y1614292
X1236052Y1614292
X1236052Y1602380
X1223992Y1614292
X1223992Y1602380
X1231792Y1602380
X1231792Y1614292
X1219732Y1602380
X1219732Y1614292
X1211932Y1602380
X1211932Y1614292
X1207672Y1614292
X1207672Y1602380
X1199872Y1602380
X1199872Y1614292
X1266932Y1590094
X1254872Y1590094
X1262672Y1590094
X1250612Y1590094
X1242812Y1590094
X1238552Y1590094
X1230752Y1590094
X1226492Y1590094
X1218692Y1590094
X1206632Y1590094
X1214432Y1590094
X1202372Y1590094
X1194572Y1590094
X1266932Y1578182
X1254872Y1578182
X1262672Y1578182
X1250612Y1578182
X1242812Y1578182
X1238552Y1578182
X1230752Y1578182
X1226492Y1578182
X1218692Y1578182
X1206632Y1578182
X1214432Y1578182
X1202372Y1578182
X1194572Y1578182
X1177222Y1255567
X1207048Y1255174
X1177120Y1248688
X1236583Y1248688
X1227847Y1251715
X1208750Y1266546
X1206883Y1248688
X1198183Y1252034
X1179180Y1265872
X1226899Y1257968
X1195470Y1262802
X1193590Y1267912
X1181850Y1260192
X1208830Y1256692
X1225540Y1266402
X1227670Y1265162
X1211240Y1265502
X1196470Y1265382
X1198180Y1262112
X1182041Y1265420
X1177283Y1188452
X1177283Y1225263
X1177283Y1191799
X1177283Y1228609
X1177283Y1211877
X1177283Y1218570
X1177283Y1235302
X1177250Y1241995
X1177283Y1198491
X1177283Y1205184
X1236583Y1188452
X1220441Y1195144
X1236583Y1191798
X1220441Y1191798
X1220441Y1201837
X1220441Y1208530
X1220441Y1185105
X1236583Y1198491
X1236583Y1205184
X1231377Y1275855
X1233327Y1274515
X1220931Y1260093
X1220601Y1269684
X1202043Y1273123
X1204608Y1273119
X1191538Y1270004
X1227883Y1245341
X1236583Y1245341
X1211741Y1248688
X1220441Y1248688
X1177183Y1185105
X1182041Y1188452
X1177183Y1195144
X1177183Y1201837
X1177183Y1208530
X1182041Y1198491
X1182041Y1205184
X1177183Y1215223
X1177183Y1221916
X1182041Y1218570
X1182041Y1211877
X1181191Y1225263
X1177183Y1231955
X1177183Y1238648
X1181191Y1235302
X1182041Y1241995
X1177183Y1245341
X1182041Y1248688
X1176867Y1270029
X1190741Y1188452
X1198183Y1185105
X1190741Y1198491
X1190741Y1205184
X1198183Y1195144
X1198183Y1201837
X1198183Y1208530
X1190741Y1218570
X1190741Y1211877
X1191591Y1225263
X1198183Y1215223
X1198183Y1221916
X1191591Y1235302
X1190741Y1241995
X1197333Y1231955
X1197333Y1238648
X1190741Y1248688
X1190966Y1258711
X1198183Y1245341
X1206883Y1185105
X1211741Y1188452
X1206883Y1195144
X1206883Y1201837
X1206883Y1208530
X1211741Y1198491
X1211741Y1205184
X1206883Y1215223
X1206883Y1221916
X1211741Y1211877
X1211741Y1218570
X1210891Y1225263
X1207733Y1231955
X1207733Y1238648
X1211328Y1234977
X1211741Y1241995
X1206883Y1245341
X1220441Y1188452
X1227883Y1185105
X1220441Y1198491
X1220441Y1205184
X1227033Y1195144
X1227883Y1201837
X1227883Y1208530
X1220441Y1211877
X1220441Y1218570
X1221291Y1225263
X1227883Y1215223
X1227033Y1221916
X1221291Y1235302
X1220441Y1241995
X1227033Y1231955
X1227883Y1238648
X1236583Y1185105
X1236583Y1195144
X1236583Y1201837
X1236583Y1208530
X1236583Y1215223
X1237433Y1221916
X1237433Y1231955
X1236583Y1238648
X1177283Y1114830
X1177283Y1151641
X1177283Y1118177
X1177283Y1154988
X1177283Y1101444
X1177283Y1108137
X1177183Y1124869
X1177183Y1131562
X1177283Y1138255
X1177283Y1144948
X1177283Y1161680
X1177283Y1168373
X1177283Y1175066
X1177283Y1181759
X1177283Y1088059
X1177283Y1094752
X1236583Y1175066
X1236583Y1181759
X1220441Y1178412
X1177183Y1084711
X1177183Y1091404
X1181191Y1088058
X1182041Y1094751
X1177183Y1098097
X1177183Y1104790
X1177183Y1111483
X1182041Y1108137
X1182041Y1101444
X1177183Y1121522
X1177183Y1128215
X1182041Y1124869
X1182041Y1114829
X1177183Y1134908
X1177183Y1141601
X1182041Y1131562
X1182041Y1138255
X1182041Y1144948
X1177183Y1148294
X1177183Y1158333
X1181191Y1151641
X1181191Y1161680
X1177183Y1165026
X1177183Y1171719
X1182041Y1175066
X1182041Y1168373
X1177183Y1178412
X1182041Y1181759
X1191591Y1088058
X1190741Y1094751
X1197333Y1084711
X1198183Y1091404
X1190741Y1108137
X1190741Y1101444
X1198183Y1104790
X1198183Y1098097
X1198183Y1111483
X1190741Y1124869
X1190741Y1114829
X1198183Y1121522
X1198183Y1128215
X1190741Y1131562
X1190741Y1138255
X1190741Y1144948
X1197333Y1134908
X1198183Y1141601
X1191591Y1151641
X1191591Y1161680
X1197333Y1148294
X1198183Y1158333
X1190741Y1175066
X1190741Y1168373
X1198183Y1171719
X1198183Y1165026
X1190741Y1181759
X1198183Y1178412
X1206883Y1084711
X1206883Y1091404
X1210891Y1088058
X1211741Y1094751
X1206883Y1104790
X1206883Y1098097
X1206883Y1111483
X1211741Y1101444
X1211741Y1108137
X1206883Y1121522
X1206883Y1128215
X1211741Y1114829
X1210891Y1124869
X1207733Y1134908
X1206883Y1141601
X1210891Y1131562
X1211741Y1138255
X1211741Y1144948
X1207733Y1148294
X1206883Y1158333
X1211741Y1161680
X1211741Y1151641
X1206883Y1171719
X1206883Y1165026
X1211741Y1168373
X1211741Y1175066
X1206883Y1178412
X1211741Y1181759
X1221291Y1088058
X1220441Y1094751
X1227883Y1084711
X1227883Y1091404
X1220441Y1101444
X1220441Y1108137
X1227883Y1098097
X1227033Y1111483
X1227883Y1104790
X1220441Y1114829
X1221291Y1124869
X1227033Y1121522
X1227883Y1128215
X1221291Y1131562
X1220441Y1138255
X1220441Y1144948
X1227883Y1141601
X1227883Y1134908
X1220441Y1161680
X1220441Y1151641
X1227883Y1148294
X1227883Y1158333
X1220441Y1168373
X1220441Y1175066
X1227883Y1165026
X1227883Y1171719
X1220441Y1181759
X1227883Y1178412
X1236583Y1084711
X1236583Y1091404
X1236583Y1098097
X1237433Y1111483
X1236583Y1104790
X1237433Y1121522
X1236583Y1128215
X1236583Y1141601
X1236583Y1134908
X1236583Y1148294
X1236583Y1158333
X1236583Y1165026
X1236583Y1171719
X1236583Y1178412
X1177183Y0994357
X1227883Y0994357
X1198183Y0994357
X1236583Y1057940
X1231023Y0999650
X1233703Y0999608
X1210033Y1002557
X1207533Y1002557
X1205033Y1002557
X1212533Y1002557
X1216663Y1000395
X1213983Y1000437
X1177183Y0984318
X1177183Y0991011
X1177283Y1078018
X1177283Y1081366
X1177283Y1051247
X1177283Y1064633
X1177283Y1071326
X1177283Y1031168
X1177283Y1037861
X1177283Y1044554
X1177283Y1024475
X1177283Y1021129
X1220441Y1061286
X1177183Y0987664
X1182041Y0984318
X1182041Y0991011
X1177183Y1017782
X1177183Y1027822
X1182041Y1024475
X1182041Y1017782
X1182041Y1031168
X1177183Y1034515
X1177183Y1041207
X1177183Y1047900
X1182041Y1037861
X1182041Y1044554
X1177183Y1061286
X1177183Y1054593
X1182041Y1051247
X1182041Y1057940
X1177183Y1067979
X1177183Y1074672
X1182041Y1064633
X1182041Y1071326
X1181191Y1078018
X1190741Y0984318
X1190741Y0991011
X1198183Y0987664
X1190741Y1024475
X1190741Y1017782
X1190741Y1031168
X1198183Y1017782
X1198183Y1027822
X1190741Y1037861
X1190741Y1044554
X1198183Y1034515
X1198183Y1041207
X1198183Y1047900
X1190741Y1051247
X1190741Y1057940
X1198183Y1061286
X1198183Y1054593
X1190741Y1064633
X1190741Y1071326
X1191591Y1078018
X1198183Y1067979
X1197333Y1074672
X1211741Y0984318
X1206883Y0987664
X1211741Y0991011
X1211741Y1024475
X1211741Y1017782
X1206883Y1017782
X1206883Y1027822
X1211741Y1031168
X1206883Y1034515
X1206883Y1041207
X1206883Y1047900
X1211741Y1037861
X1211741Y1044554
X1206883Y1061286
X1206883Y1054593
X1211741Y1057940
X1211741Y1051247
X1206883Y1067979
X1207733Y1074672
X1211741Y1071326
X1211741Y1064633
X1210891Y1078018
X1220441Y0984318
X1220441Y0991011
X1227883Y0987664
X1220441Y1024475
X1220441Y1017782
X1227883Y1017782
X1220441Y1031168
X1227883Y1027822
X1220441Y1037861
X1220441Y1044554
X1227883Y1034515
X1227883Y1041207
X1227883Y1047900
X1220441Y1057940
X1220441Y1051247
X1227883Y1054593
X1227883Y1061286
X1220441Y1071326
X1220441Y1064633
X1221291Y1078018
X1227033Y1067979
X1227033Y1074672
X1236583Y0987664
X1236583Y1017782
X1236583Y1027822
X1236583Y1034515
X1236583Y1041207
X1236583Y1047900
X1236583Y1054593
X1236583Y1061286
X1237433Y1067979
X1237433Y1074672
X1177183Y0954200
X1177183Y0957546
X1227883Y0954200
X1227883Y0957546
X1198183Y0954200
X1198183Y0957546
X1177183Y0970932
X1177183Y0893963
X1177183Y0930774
X1177183Y0897310
X1177183Y0934121
X1177183Y0887270
X1177183Y0904003
X1177183Y0910696
X1177183Y0964239
X1177183Y0940814
X1177183Y0947507
X1177183Y0917389
X1177183Y0924081
X1177183Y0977625
X1220441Y0957546
X1190741Y0957546
X1236583Y0893963
X1220441Y0900656
X1236583Y0897310
X1220441Y0897310
X1236583Y0887270
X1220441Y0883924
X1220441Y0890617
X1236583Y0904003
X1236583Y0910696
X1220441Y0907349
X1220441Y0914042
X1220441Y0960892
X1190741Y0960892
X1177183Y0883924
X1177183Y0890617
X1177183Y0900656
X1182041Y0887270
X1182041Y0893963
X1177183Y0907349
X1177183Y0914042
X1182041Y0904003
X1182041Y0910696
X1182041Y0917389
X1177183Y0920735
X1177183Y0927428
X1181191Y0924081
X1181191Y0930774
X1177183Y0944160
X1177183Y0937467
X1182041Y0947507
X1182041Y0940814
X1177183Y0950853
X1177183Y0960892
X1182041Y0954200
X1182041Y0964239
X1177183Y0967585
X1177183Y0980971
X1177183Y0974278
X1182041Y0977625
X1182041Y0970932
X1198183Y0883924
X1190741Y0887270
X1190741Y0893963
X1198183Y0890617
X1198183Y0900656
X1190741Y0904003
X1190741Y0910696
X1190741Y0917389
X1198183Y0907349
X1198183Y0914042
X1191591Y0924081
X1191591Y0930774
X1198183Y0920735
X1197383Y0927428
X1190741Y0947507
X1190741Y0940814
X1197333Y0937467
X1198183Y0944160
X1190741Y0954200
X1190741Y0964239
X1198183Y0950853
X1198183Y0960892
X1190741Y0977625
X1190741Y0970932
X1198183Y0967585
X1198183Y0974278
X1198183Y0980971
X1206883Y0883924
X1206883Y0890617
X1206883Y0900656
X1211741Y0887270
X1211741Y0893963
X1206883Y0907349
X1206883Y0914042
X1211741Y0904003
X1211741Y0910696
X1211741Y0917389
X1206883Y0920735
X1207683Y0927428
X1211741Y0924081
X1211741Y0930774
X1207733Y0937467
X1206883Y0944660
X1211001Y0940814
X1211741Y0947507
X1206883Y0950853
X1206883Y0960892
X1211741Y0954200
X1211741Y0964239
X1206883Y0967585
X1206883Y0974278
X1206883Y0980971
X1211741Y0970932
X1211741Y0977625
X1227883Y0883924
X1220441Y0887270
X1220441Y0893963
X1227883Y0890617
X1227033Y0900656
X1220441Y0904003
X1220441Y0910696
X1220441Y0917389
X1227883Y0907349
X1227883Y0914042
X1220441Y0924081
X1221291Y0930774
X1227883Y0920735
X1227033Y0927428
X1221291Y0940814
X1220441Y0947507
X1227033Y0937467
X1227883Y0944160
X1220441Y0954200
X1220441Y0964239
X1227883Y0950853
X1227883Y0960892
X1227883Y0980971
X1220441Y0970932
X1220441Y0977625
X1227883Y0967585
X1227883Y0974278
X1236583Y0883924
X1236583Y0890617
X1236583Y0900656
X1236583Y0907349
X1236583Y0914042
X1236583Y0920735
X1237433Y0927428
X1237433Y0937467
X1236583Y0944160
X1236583Y0950853
X1236583Y0960892
X1236583Y0980971
X1236583Y0967585
X1236583Y0974278
X1177183Y0820341
X1177183Y0857152
X1177183Y0786877
X1177183Y0823688
X1177183Y0860499
X1177183Y0880577
X1177183Y0793570
X1177183Y0800263
X1177183Y0806955
X1177183Y0813648
X1177183Y0830381
X1177183Y0837074
X1177183Y0843766
X1177183Y0850459
X1177183Y0867192
X1177183Y0873885
X1236583Y0880577
X1177183Y0790223
X1177183Y0796916
X1177183Y0803609
X1182041Y0793570
X1182041Y0800263
X1177183Y0810302
X1177183Y0816995
X1181191Y0820341
X1182041Y0806955
X1182041Y0813648
X1177183Y0827034
X1177183Y0833727
X1181191Y0830381
X1177183Y0840420
X1177183Y0847113
X1182041Y0843766
X1182041Y0837074
X1182041Y0850459
X1177183Y0853806
X1181191Y0857152
X1177183Y0863845
X1181191Y0867192
X1177183Y0870538
X1177183Y0877231
X1182041Y0880577
X1182041Y0873885
X1190741Y0793570
X1190741Y0800263
X1198183Y0790223
X1198183Y0796916
X1198183Y0803609
X1191591Y0820341
X1190741Y0806955
X1190741Y0813648
X1198183Y0810302
X1197333Y0816995
X1191591Y0830381
X1197333Y0827034
X1198183Y0833727
X1190741Y0843766
X1190741Y0837074
X1190741Y0850459
X1198183Y0840420
X1198183Y0847113
X1191591Y0857152
X1198183Y0853806
X1191591Y0867192
X1197333Y0863845
X1190741Y0880577
X1190741Y0873885
X1197333Y0870538
X1198183Y0877231
X1206883Y0790223
X1206883Y0796916
X1206883Y0803609
X1211741Y0793570
X1211741Y0800263
X1206883Y0810302
X1207148Y0817554
X1211741Y0806955
X1210891Y0813648
X1210891Y0820341
X1207733Y0827034
X1206883Y0833727
X1211741Y0830381
X1206883Y0840420
X1206883Y0847113
X1211741Y0843766
X1211741Y0837074
X1211741Y0850459
X1206883Y0853806
X1210891Y0857152
X1207733Y0863845
X1210891Y0867492
X1207201Y0871084
X1206883Y0877231
X1211741Y0880577
X1211741Y0874185
X1220441Y0793570
X1220441Y0800263
X1227883Y0790223
X1227883Y0796916
X1227883Y0803609
X1220441Y0806955
X1221291Y0813648
X1221291Y0820341
X1227883Y0810302
X1227033Y0816995
X1220441Y0830381
X1227033Y0827034
X1227883Y0833727
X1220441Y0843766
X1220441Y0837074
X1220441Y0850459
X1227883Y0840420
X1227883Y0847113
X1221291Y0857152
X1227033Y0853806
X1221291Y0867192
X1227033Y0863845
X1220441Y0880577
X1220441Y0873885
X1227883Y0877231
X1227883Y0870538
X1236583Y0790223
X1236583Y0796916
X1236583Y0803609
X1236583Y0810302
X1237433Y0816995
X1237433Y0827034
X1236583Y0833727
X1236583Y0840420
X1236583Y0847113
X1237433Y0853806
X1237433Y0863845
X1236583Y0877231
X1236583Y0870538
X1211641Y0766798
X1181941Y0766798
X1177183Y0783530
X1177183Y0770144
X1177183Y0776837
X1177183Y0766798
X1182041Y0770144
X1177183Y0773491
X1177183Y0780184
X1182041Y0776837
X1182041Y0783530
X1190741Y0770144
X1198183Y0766798
X1190741Y0776837
X1190741Y0783530
X1198183Y0773491
X1198183Y0780184
X1206883Y0766798
X1211741Y0770144
X1206883Y0773491
X1206883Y0780184
X1211741Y0776837
X1211741Y0783530
X1220441Y0770144
X1227883Y0766798
X1220441Y0776837
X1220441Y0783530
X1227883Y0773491
X1227883Y0780184
X1236583Y0766798
X1236583Y0773491
X1236583Y0780184
X1339727Y0157449
X1352551Y0161148
X1322652Y0157449
X1348386Y0156646
X1346140Y0157449
X1335472Y0157449
X1349344Y0162999
X1342937Y0162999
X1352557Y0183348
X1355761Y0181498
X1346137Y0179649
X1355761Y0174098
X1349351Y0181498
X1352557Y0175948
X1329062Y0157449
X1313033Y0166699
X1346140Y0161149
X1346137Y0183349
X1300217Y0159299
X1300204Y0181499
X1309817Y0179649
X1306617Y0177799
X1332268Y0174099
X1296999Y0179649
X1326918Y0161161
X1335472Y0164849
X1329062Y0164849
X1303417Y0157449
X1313037Y0159299
X1309832Y0164849
X1313037Y0162999
X1306626Y0159299
X1306626Y0162999
X1309832Y0157449
X1303407Y0179649
X1303407Y0175949
X1293802Y0166699
X1294163Y0175865
X1293802Y0170399
X1339727Y0168549
X1342903Y0170399
X1313027Y0181499
X1319442Y0174099
X1315352Y0179724
X1349351Y0174098
X1355762Y0166698
X1349351Y0170398
X1342937Y0177799
X1349351Y0177798
X1352557Y0168548
X1352557Y0172248
X1346137Y0175949
X1339727Y0183349
X1334252Y0176574
X1332268Y0170399
X1324802Y0182874
X1324802Y0179724
X1325085Y0176402
X1331102Y0182874
X1331102Y0179724
X1325853Y0174099
X1322652Y0164849
X1332268Y0162999
X1316242Y0164849
X1309832Y0172249
X1355961Y0155458
X1352557Y0179648
X1355761Y0177798
X1355761Y0170398
X1358865Y0178544
X1358865Y0182484
X1335472Y0172249
X1346137Y0172249
X1342937Y0181499
X1339727Y0179649
X1339568Y0176028
X1327952Y0182874
X1331102Y0176574
X1316237Y0172249
X1329062Y0172249
X1306617Y0181499
X1306622Y0174099
X1313033Y0174099
X1303422Y0172249
X1300207Y0177799
X1293802Y0183349
X1352557Y0164848
X1349351Y0166698
X1358865Y0162793
X1358865Y0158854
X1358865Y0166732
X1358865Y0174603
X1358865Y0170671
X1355761Y0162998
X1355758Y0159298
X1349351Y0159298
X1335472Y0168549
X1339727Y0164849
X1346137Y0164849
X1332268Y0166699
X1342907Y0166699
X1346137Y0168549
X1335472Y0161149
X1342936Y0159301
X1329062Y0168549
X1319452Y0166699
X1318502Y0182874
X1318502Y0176574
X1319442Y0170399
X1316242Y0161149
X1322652Y0161149
X1303417Y0168549
X1309832Y0168549
X1303417Y0161149
X1309832Y0161149
X1297007Y0164849
X1297012Y0168549
X1297007Y0161149
X1293802Y0162999
X1300774Y0155288
X1320469Y0155288
X1344103Y0155288
X1313037Y0170399
X1316241Y0157449
X1341992Y0156897
X1293802Y0159299
X1306622Y0166699
X1319442Y0159299
X1300212Y0174099
X1296999Y0175949
X1309817Y0175949
X1297007Y0172249
X1300212Y0166699
X1316242Y0168549
X1303407Y0183349
X1296999Y0183349
X1339727Y0161149
X1319452Y0162999
X1300213Y0162999
X1306626Y0170399
X1297012Y0157449
X1352550Y0157449
X1300212Y0170399
X1293511Y0179048
X1303417Y0164849
X1322652Y0216649
X1322652Y0220349
X1303407Y0198149
X1309817Y0198149
X1300207Y0211099
X1296999Y0205549
X1322652Y0224049
X1325856Y0222199
X1346147Y0198149
X1346147Y0201849
X1352561Y0201848
X1349361Y0199998
X1349351Y0185198
X1355761Y0185198
X1355765Y0199999
X1355771Y0196298
X1355765Y0203699
X1352561Y0198148
X1346137Y0187049
X1296999Y0212949
X1316242Y0209249
X1325857Y0218499
X1329062Y0220349
X1313025Y0188899
X1306627Y0214799
X1306614Y0203699
X1303416Y0205549
X1303425Y0224049
X1296999Y0201849
X1300393Y0235762
X1300493Y0238062
X1309833Y0220349
X1313033Y0222199
X1300220Y0222199
X1300220Y0218499
X1309817Y0190749
X1339727Y0209249
X1313027Y0185199
X1313027Y0192599
X1313027Y0203699
X1315352Y0186024
X1315405Y0189227
X1322652Y0209249
X1355761Y0188898
X1352551Y0187048
X1349351Y0192598
X1342937Y0192599
X1337402Y0198624
X1339727Y0201849
X1315352Y0204924
X1318502Y0204924
X1327952Y0204924
X1324802Y0204924
X1319442Y0211099
X1332262Y0207399
X1339686Y0205478
X1337345Y0201831
X1339727Y0187049
X1337901Y0196035
X1332262Y0211099
X1325852Y0211099
X1331102Y0189174
X1321652Y0201774
X1327952Y0201774
X1321652Y0195474
X1318502Y0195474
X1327952Y0195474
X1324802Y0195474
X1324802Y0186024
X1331102Y0186024
X1309832Y0209249
X1329062Y0212949
X1360186Y0226264
X1306617Y0185199
X1293807Y0214799
X1293807Y0222199
X1293807Y0218499
X1300204Y0188899
X1296999Y0187049
X1349351Y0222198
X1332267Y0222199
X1342937Y0222199
X1329061Y0224049
X1319442Y0222199
X1306622Y0222199
X1309828Y0224049
X1301151Y0225450
X1309100Y0236477
X1321986Y0236726
X1326377Y0235784
X1332285Y0226210
X1349351Y0211098
X1352561Y0212948
X1349351Y0214798
X1355765Y0207399
X1352560Y0205549
X1332262Y0214799
X1332262Y0218499
X1337102Y0206675
X1329062Y0216649
X1319442Y0207399
X1329062Y0209249
X1300207Y0214799
X1303417Y0216649
X1303417Y0212949
X1306622Y0218499
X1313032Y0214799
X1319442Y0218499
X1325852Y0214799
X1303422Y0209249
X1355761Y0192598
X1349345Y0188898
X1352551Y0190748
X1352561Y0194448
X1346137Y0190749
X1346137Y0194449
X1346147Y0209248
X1349351Y0196298
X1321652Y0198624
X1327952Y0198624
X1331102Y0195474
X1334252Y0195474
X1327952Y0189174
X1303407Y0201849
X1300207Y0199999
X1306617Y0199999
X1313023Y0199999
X1315352Y0195474
X1306617Y0192599
X1309817Y0187049
X1300207Y0192599
X1358865Y0199180
X1358865Y0195240
X1358371Y0188778
X1358865Y0217934
X1358865Y0213994
X1358865Y0203120
X1358865Y0207060
X1342937Y0185199
X1342937Y0188899
X1339727Y0190749
X1327952Y0186024
X1300207Y0185199
X1293802Y0201849
X1293802Y0194449
X1293802Y0198149
X1293802Y0190749
X1293802Y0187049
X1296999Y0209249
X1318502Y0186024
X1318502Y0189174
X1296999Y0224049
X1303407Y0187049
X1296999Y0190749
X1303407Y0190749
X1296999Y0216649
X1303422Y0220349
X1294357Y0224688
X1293798Y0205833
X1300207Y0196299
X1306617Y0196299
X1300207Y0207399
X1300207Y0203699
X1296999Y0198149
X1303407Y0194449
X1306617Y0188899
X1296999Y0194449
X1309817Y0194449
X1293805Y0211099
X1355766Y0218498
X1352561Y0216648
X1349351Y0218498
X1346147Y0220349
X1342937Y0214799
X1342937Y0218499
X1336527Y0222199
X1336527Y0218499
X1355766Y0222198
X1355766Y0214798
X1352561Y0220348
X1346147Y0216649
X1346147Y0212949
X1339727Y0216649
X1339727Y0220349
X1336527Y0214799
X1362020Y0854584
X1358320Y0860993
X1352771Y0857789
X1350920Y0860993
X1347220Y0854584
X1343520Y0860993
X1339820Y0854584
X1336120Y0860993
X1330571Y0857789
X1371271Y0857789
X1369420Y0854584
X1363871Y0857789
X1328720Y0860993
X1360171Y0857789
X1356471Y0857789
X1354620Y0854584
X1349071Y0857789
X1345371Y0857789
X1341671Y0857789
X1337971Y0857789
X1334271Y0857789
X1332420Y0854584
X1367571Y0857789
X1365720Y0860993
X1326871Y0857789
X1358320Y0848176
X1354621Y0841467
X1350920Y0848176
X1349069Y0844971
X1343520Y0848176
X1341669Y0844971
X1336120Y0848176
X1334269Y0844971
X1328720Y0848176
X1371269Y0844971
X1365720Y0848176
X1362021Y0841467
X1325020Y0848176
X1360169Y0844971
X1356469Y0844971
X1352769Y0844971
X1347221Y0841467
X1345369Y0844971
X1339821Y0841467
X1337969Y0844971
X1332421Y0841467
X1330569Y0844971
X1369421Y0841467
X1367569Y0844971
X1363869Y0844971
X1326869Y0851380
X1325020Y0880219
X1323171Y0877014
X1369420Y0873810
X1369420Y0860993
X1362020Y0873810
X1354620Y0873810
X1354620Y0860993
X1362020Y0860993
X1347220Y0873810
X1332420Y0873810
X1339820Y0873810
X1332420Y0860993
X1347220Y0860993
X1339820Y0860993
X1325020Y0873810
X1325021Y0860993
X1369420Y0848176
X1354620Y0848176
X1362020Y0848176
X1332420Y0848176
X1339820Y0848176
X1347220Y0848176
X1360171Y0883423
X1352771Y0883423
X1345371Y0883423
X1337971Y0883423
X1367571Y0883423
X1330571Y0883423
X1363871Y0883423
X1362020Y0880219
X1356471Y0883423
X1354620Y0880219
X1349071Y0883423
X1347220Y0880219
X1341671Y0883423
X1339820Y0880219
X1334271Y0883423
X1371271Y0883423
X1369420Y0880219
X1332420Y0880219
X1360171Y0870606
X1358320Y0873810
X1352771Y0870606
X1350920Y0873810
X1345371Y0870606
X1343520Y0873810
X1339820Y0867401
X1336120Y0873810
X1332420Y0867401
X1369420Y0867401
X1365720Y0873810
X1328720Y0873810
X1362020Y0867401
X1356471Y0870606
X1354620Y0867401
X1349071Y0870606
X1347220Y0867401
X1341671Y0870606
X1337971Y0870606
X1334271Y0870606
X1330571Y0870606
X1371271Y0870606
X1367571Y0870606
X1363871Y0870606
X1326871Y0870606
X1314184Y0849978
X1321320Y0854584
X1319471Y0883423
X1312070Y0883423
X1317621Y0880219
X1313921Y0880219
X1365721Y0880219
X1367571Y0877014
X1371271Y0877014
X1363871Y0877014
X1349071Y0877014
X1350921Y0880219
X1352771Y0877014
X1356471Y0877014
X1358321Y0880219
X1360171Y0877014
X1334271Y0877014
X1336121Y0880219
X1337971Y0877014
X1341671Y0877014
X1343521Y0880219
X1345371Y0877014
X1323171Y0883423
X1326871Y0883423
X1315771Y0883423
X1319471Y0877014
X1321321Y0880219
X1317621Y0873810
X1315771Y0877014
X1321321Y0873810
X1326871Y0877014
X1323171Y0870606
X1328722Y0880219
X1330571Y0877014
X1308370Y0877014
X1310221Y0880219
X1312070Y0877014
X1365721Y0867401
X1365721Y0854584
X1367571Y0864197
X1371271Y0864197
X1350921Y0867401
X1358321Y0867401
X1363871Y0864197
X1349071Y0864197
X1350921Y0854584
X1352771Y0864197
X1356471Y0864197
X1358321Y0854584
X1360171Y0864197
X1336121Y0867401
X1343521Y0867401
X1334271Y0864197
X1336121Y0854584
X1337971Y0864197
X1341671Y0864197
X1343521Y0854584
X1345371Y0864197
X1325021Y0867401
X1328721Y0867401
X1317621Y0867401
X1319469Y0857789
X1321321Y0860993
X1325020Y0854584
X1323171Y0857789
X1323171Y0864197
X1326871Y0864197
X1330571Y0864197
X1328721Y0854584
X1315770Y0857789
X1317620Y0854584
X1312266Y0857972
X1313920Y0854584
X1367571Y0851380
X1371271Y0851380
X1365721Y0841467
X1363871Y0851380
X1349071Y0851380
X1352771Y0851380
X1356471Y0851380
X1360171Y0851380
X1350921Y0841467
X1358321Y0841467
X1334271Y0851380
X1337971Y0851380
X1341671Y0851380
X1345371Y0851380
X1336121Y0841467
X1343521Y0841467
X1319469Y0851380
X1323170Y0851380
X1330571Y0851380
X1321320Y0848176
X1323170Y0844971
X1326869Y0844971
X1307426Y0978814
X1369420Y0886627
X1362020Y0886627
X1354620Y0886627
X1339820Y0886627
X1347220Y0886627
X1365720Y0886627
X1358320Y0886627
X1350920Y0886627
X1343520Y0886627
X1336120Y0886627
X1369421Y0893036
X1343521Y0893036
X1339821Y0893036
X1360171Y0973143
X1365720Y0963530
X1360171Y0915466
X1369420Y0963530
X1365720Y0905853
X1352771Y0915466
X1365720Y0925079
X1365720Y0944304
X1362020Y0963530
X1369420Y0905853
X1356471Y0915466
X1369420Y0925079
X1369420Y0944304
X1362020Y0905853
X1349071Y0915466
X1362020Y0925079
X1362020Y0944304
X1363871Y0928283
X1365720Y0931488
X1369420Y0937896
X1371271Y0941100
X1365720Y0937896
X1363871Y0941100
X1371271Y0947509
X1369420Y0899445
X1371271Y0902649
X1369420Y0950713
X1365720Y0899445
X1363871Y0902649
X1371271Y0909057
X1369420Y0912262
X1363871Y0909057
X1365720Y0912262
X1356471Y0909057
X1358320Y0912262
X1352771Y0909057
X1350920Y0912262
X1363871Y0947509
X1358320Y0918670
X1356471Y0921875
X1350920Y0918670
X1352771Y0921875
X1369420Y0918670
X1371271Y0921875
X1365720Y0918670
X1363871Y0921875
X1371271Y0928283
X1369420Y0931488
X1365720Y0950713
X1352771Y0966735
X1356471Y0966735
X1358320Y0969939
X1350920Y0969939
X1371271Y0966735
X1369420Y0969939
X1363871Y0966735
X1365720Y0969939
X1369420Y0957122
X1371271Y0960326
X1365720Y0957122
X1363871Y0960326
X1349071Y0973143
X1358320Y0976347
X1350920Y0976347
X1356471Y0979552
X1352771Y0979552
X1365721Y0976347
X1363871Y0979552
X1371271Y0979552
X1369420Y0976347
X1365720Y0982756
X1369420Y0982756
X1362020Y0982756
X1347220Y0963530
X1339820Y0944304
X1360171Y0896240
X1347220Y0905853
X1360171Y0934691
X1360171Y0953917
X1347220Y0944304
X1352771Y0896240
X1339820Y0905853
X1352771Y0934691
X1352771Y0953917
X1336120Y0944304
X1356471Y0896240
X1343520Y0905853
X1356471Y0934691
X1356471Y0953917
X1343520Y0944304
X1349071Y0896240
X1336120Y0905853
X1349071Y0934691
X1349071Y0953917
X1350920Y0937896
X1352771Y0941100
X1356471Y0947509
X1358320Y0950713
X1352771Y0947509
X1350920Y0950713
X1358320Y0957122
X1362020Y0893036
X1350920Y0893036
X1356471Y0960326
X1358320Y0893036
X1347220Y0893036
X1358320Y0899445
X1356471Y0902649
X1350920Y0899445
X1352771Y0902649
X1343520Y0899445
X1345371Y0902649
X1339820Y0899445
X1337971Y0902649
X1350920Y0957122
X1345371Y0909057
X1343520Y0912262
X1337971Y0909057
X1339820Y0912262
X1356471Y0928283
X1358320Y0931488
X1352771Y0928283
X1350920Y0931488
X1358320Y0937896
X1356471Y0941100
X1352771Y0960326
X1343520Y0957122
X1345371Y0960326
X1339820Y0957122
X1337971Y0960326
X1345371Y0947509
X1343520Y0950713
X1337971Y0947509
X1339820Y0950713
X1343520Y0937896
X1345371Y0941100
X1339820Y0937896
X1337971Y0941100
X1336120Y0963530
X1345371Y0966735
X1337971Y0966735
X1343520Y0969939
X1339820Y0969939
X1334271Y0973143
X1323172Y0953917
X1321321Y0886627
X1334271Y0896240
X1334271Y0915466
X1347220Y0925079
X1330571Y0953917
X1313921Y0886627
X1326871Y0896240
X1326871Y0915466
X1339820Y0925079
X1326871Y0953917
X1317621Y0886627
X1330571Y0896240
X1330571Y0915466
X1343520Y0925079
X1334271Y0953917
X1310221Y0886627
X1323171Y0896240
X1323171Y0915466
X1336120Y0925079
X1325020Y0918670
X1326871Y0921875
X1343520Y0918670
X1345371Y0921875
X1339820Y0918670
X1337971Y0921875
X1345371Y0928283
X1343520Y0931488
X1319470Y0889832
X1317620Y0893036
X1312070Y0889832
X1313921Y0893036
X1330571Y0889832
X1332420Y0893036
X1326871Y0889832
X1325020Y0893036
X1337971Y0928283
X1332420Y0899445
X1330571Y0902649
X1325020Y0899445
X1326871Y0902649
X1330571Y0909057
X1332420Y0912262
X1326871Y0909057
X1325020Y0912262
X1332420Y0918670
X1330571Y0921875
X1339820Y0931488
X1330571Y0966735
X1332420Y0969939
X1326871Y0966735
X1325020Y0969939
X1332420Y0957122
X1330571Y0960326
X1325020Y0957122
X1326871Y0960326
X1330571Y0947509
X1332420Y0950713
X1326871Y0947509
X1325020Y0950713
X1323171Y0973143
X1332420Y0976347
X1325020Y0976347
X1330571Y0979552
X1326871Y0979552
X1339820Y0976347
X1337971Y0979552
X1343520Y0976347
X1345371Y0979552
X1347220Y0982756
X1339820Y0982756
X1343520Y0982756
X1336120Y0982756
X1334271Y0934691
X1326871Y0934691
X1330571Y0934691
X1323171Y0934691
X1330571Y0928283
X1332420Y0931488
X1326871Y0928283
X1325021Y0931488
X1332420Y0937896
X1330571Y0941100
X1325020Y0937896
X1326871Y0941100
X1367571Y0973143
X1367571Y0979552
X1371271Y0973143
X1315771Y0979552
X1310221Y0976347
X1367571Y0966735
X1367571Y0953917
X1367571Y0960326
X1371271Y0953917
X1367571Y0947509
X1367571Y0934691
X1367571Y0941100
X1371271Y0934691
X1363870Y0934691
X1354620Y0937896
X1362021Y0937896
X1347220Y0937896
X1336121Y0937896
X1337970Y0934691
X1341671Y0934691
X1345371Y0934691
X1319470Y0934692
X1321321Y0937896
X1315771Y0934692
X1328720Y0937896
X1310221Y0957122
X1308370Y0953917
X1312070Y0953917
X1308371Y0973143
X1328720Y0944304
X1317620Y0944304
X1323171Y0947509
X1325020Y0944304
X1323171Y0941100
X1328720Y0950713
X1328720Y0963530
X1328720Y0957122
X1317621Y0950713
X1319470Y0960326
X1319471Y0966735
X1319470Y0953917
X1315771Y0966735
X1315771Y0953917
X1321321Y0950713
X1323171Y0960326
X1325020Y0963530
X1323171Y0966735
X1321321Y0957122
X1328721Y0976347
X1328720Y0982756
X1326871Y0973143
X1330570Y0973143
X1328720Y0969939
X1319471Y0973143
X1315771Y0973143
X1321321Y0976347
X1323171Y0979552
X1325020Y0982756
X1321321Y0969939
X1332421Y0944304
X1334271Y0941100
X1334270Y0947509
X1341671Y0941100
X1341671Y0947509
X1336120Y0950713
X1334270Y0966735
X1332421Y0963530
X1336121Y0957122
X1334271Y0960326
X1347221Y0950713
X1341670Y0966735
X1339821Y0963530
X1343520Y0963530
X1347220Y0957122
X1341671Y0960326
X1341671Y0953917
X1345371Y0953917
X1337971Y0953917
X1332421Y0982756
X1334271Y0979552
X1336121Y0976347
X1336120Y0969939
X1341671Y0973143
X1341671Y0979552
X1345371Y0973143
X1347220Y0976347
X1337970Y0973143
X1347221Y0969939
X1349070Y0941100
X1349071Y0947509
X1350920Y0944304
X1360170Y0947509
X1354620Y0944304
X1358321Y0944304
X1360171Y0941100
X1349071Y0966735
X1350920Y0963530
X1349070Y0960326
X1362020Y0950713
X1354620Y0950713
X1360170Y0966735
X1354620Y0963530
X1358321Y0963530
X1354620Y0957122
X1362021Y0957122
X1360171Y0960326
X1363871Y0953917
X1352771Y0973143
X1349070Y0979552
X1350920Y0982756
X1354621Y0976347
X1354620Y0982756
X1356470Y0973143
X1358321Y0982756
X1360171Y0979552
X1362021Y0976347
X1363870Y0973143
X1354620Y0969939
X1362020Y0969939
X1308370Y0934692
X1308371Y0941100
X1312070Y0934692
X1367571Y0921875
X1367571Y0928283
X1354620Y0931488
X1362020Y0931488
X1349070Y0921875
X1349071Y0928283
X1350920Y0925079
X1354620Y0918670
X1354620Y0925079
X1358321Y0925079
X1360171Y0921875
X1360170Y0928283
X1362021Y0918670
X1347221Y0931488
X1336120Y0931488
X1347220Y0918670
X1334271Y0921875
X1334270Y0928283
X1336121Y0918670
X1341671Y0921875
X1341671Y0928283
X1332421Y0925079
X1321321Y0931488
X1328720Y0931488
X1317621Y0931488
X1321321Y0918670
X1323171Y0921875
X1323171Y0928283
X1317620Y0925079
X1325020Y0925079
X1328720Y0918670
X1328720Y0925079
X1308371Y0921875
X1367571Y0915466
X1371271Y0915466
X1367571Y0902649
X1367571Y0909057
X1363870Y0915466
X1349070Y0902649
X1349071Y0909057
X1350920Y0905853
X1354620Y0905853
X1354620Y0912262
X1358321Y0905853
X1360171Y0902649
X1360170Y0909057
X1362020Y0912262
X1337970Y0915466
X1341671Y0915466
X1345371Y0915466
X1347221Y0912262
X1334271Y0902649
X1334270Y0909057
X1336120Y0912262
X1341671Y0902649
X1341671Y0909057
X1332420Y0905853
X1319471Y0915466
X1315771Y0915466
X1321321Y0912262
X1323171Y0902649
X1323171Y0909057
X1328720Y0912262
X1317620Y0905853
X1317621Y0912262
X1325020Y0905853
X1328720Y0905853
X1308370Y0915466
X1312070Y0915466
X1308371Y0902649
X1365721Y0893036
X1367571Y0889832
X1367570Y0896240
X1371271Y0889832
X1371271Y0896240
X1354620Y0899445
X1362021Y0899445
X1363871Y0889832
X1363871Y0896240
X1349071Y0889832
X1352771Y0889832
X1354621Y0893036
X1356471Y0889832
X1360171Y0889832
X1347220Y0899445
X1336121Y0899445
X1334270Y0889832
X1336121Y0893036
X1337971Y0889832
X1337970Y0896240
X1341671Y0889832
X1341671Y0896240
X1345371Y0889832
X1345371Y0896240
X1332420Y0886627
X1321321Y0899445
X1319470Y0896240
X1321321Y0893036
X1323171Y0889832
X1325021Y0886627
X1328720Y0886627
X1328720Y0893036
X1315771Y0889832
X1315771Y0896240
X1328720Y0899445
X1310220Y0893036
X1312070Y0896240
X1319903Y0999684
X1358753Y1009297
X1356904Y1012501
X1351353Y1009297
X1353204Y1012501
X1356904Y1082995
X1366153Y1034931
X1366153Y1054157
X1366153Y1073383
X1353204Y1082995
X1369853Y1034931
X1369853Y1054157
X1369853Y1073383
X1360604Y1082995
X1362453Y1034931
X1362453Y1054157
X1362453Y1073383
X1349504Y1082995
X1356904Y1076587
X1358753Y1079791
X1353204Y1076587
X1351353Y1079791
X1369853Y1047749
X1371704Y1050952
X1366153Y1047749
X1364304Y1050952
X1371704Y1057361
X1369853Y1060565
X1364304Y1057361
X1366153Y1060565
X1369853Y1066974
X1371704Y1070178
X1366153Y1066974
X1364304Y1070178
X1371704Y1076587
X1369853Y1079791
X1364304Y1076587
X1366153Y1079791
X1371704Y1018910
X1369853Y1022114
X1364304Y1018910
X1366153Y1022114
X1369853Y1028523
X1371704Y1031727
X1366153Y1028523
X1364304Y1031727
X1371704Y1038136
X1369853Y1041340
X1364304Y1038136
X1366153Y1041340
X1369853Y1009297
X1366153Y1009297
X1371704Y1012501
X1364304Y1012501
X1362453Y1015705
X1356904Y0999684
X1358753Y1002888
X1345804Y0999684
X1347653Y1002888
X1353204Y0999684
X1351353Y1002888
X1338404Y0999684
X1356902Y1025318
X1360604Y1044544
X1343953Y1054157
X1356904Y1063770
X1349502Y1025318
X1353204Y1044544
X1340253Y1054157
X1353204Y1063770
X1360604Y1025318
X1356904Y1044544
X1347653Y1054157
X1360604Y1063770
X1353204Y1025318
X1349504Y1044544
X1336553Y1054157
X1349504Y1063770
X1351353Y1066974
X1353204Y1070178
X1356904Y1038136
X1358753Y1041340
X1353204Y1038136
X1351353Y1041340
X1358753Y1047749
X1356904Y1050952
X1351353Y1047749
X1353204Y1050952
X1343953Y1047749
X1345804Y1050952
X1340253Y1047749
X1338404Y1050952
X1345804Y1057361
X1343953Y1060565
X1338404Y1057361
X1340253Y1060565
X1356904Y1057361
X1358753Y1060565
X1353204Y1057361
X1351353Y1060565
X1358753Y1066974
X1356904Y1070178
X1345804Y1018910
X1343953Y1022114
X1338404Y1018910
X1340253Y1022114
X1356904Y1018910
X1358753Y1022114
X1353204Y1018910
X1351353Y1022114
X1358753Y1028523
X1356904Y1031727
X1351353Y1028523
X1353204Y1031727
X1340253Y1002888
X1343953Y1009297
X1340253Y1009297
X1345804Y1012501
X1338404Y1012501
X1347653Y1015705
X1336553Y1015705
X1360604Y1006093
X1353204Y1006093
X1356904Y1006093
X1349504Y1006093
X1371704Y0999684
X1369853Y1002888
X1364304Y0999684
X1366153Y1002888
X1334704Y1025318
X1343953Y1034931
X1334704Y1044544
X1343953Y1073383
X1334704Y1082995
X1327304Y1025318
X1340253Y1034931
X1327303Y1044544
X1340253Y1073383
X1327303Y1082995
X1331004Y1025318
X1347653Y1034931
X1331003Y1044544
X1347653Y1073383
X1331003Y1082995
X1323603Y1025318
X1336553Y1034931
X1323603Y1044544
X1336553Y1073383
X1323603Y1082995
X1338404Y1076587
X1340253Y1079791
X1331003Y1076587
X1332853Y1079791
X1327303Y1076587
X1325453Y1079791
X1343953Y1028523
X1345804Y1031727
X1340253Y1028523
X1338404Y1031727
X1345804Y1038136
X1343953Y1041340
X1338404Y1038136
X1340253Y1041340
X1331003Y1038136
X1332853Y1041340
X1327303Y1038136
X1325453Y1041340
X1332853Y1047749
X1331003Y1050952
X1325453Y1047749
X1327303Y1050952
X1343953Y1066974
X1345804Y1070178
X1340253Y1066974
X1338404Y1070178
X1345804Y1076587
X1343953Y1079791
X1332853Y1009297
X1331003Y1012501
X1325453Y1009297
X1327303Y1012501
X1331003Y1018910
X1332853Y1022114
X1327303Y1018910
X1325453Y1022114
X1332853Y1028523
X1331003Y1031727
X1325453Y1028523
X1327304Y1031727
X1331003Y0999684
X1327303Y0999684
X1332853Y1002888
X1325453Y1002888
X1334704Y1006093
X1323603Y1006093
X1343953Y1002888
X1331003Y1063770
X1327303Y1063770
X1334704Y1063770
X1323603Y1063770
X1325453Y1066974
X1327304Y1070178
X1331003Y1057361
X1332853Y1060565
X1327303Y1057361
X1325453Y1060565
X1332853Y1066974
X1331003Y1070178
X1368004Y1082995
X1371704Y1082995
X1364303Y1082995
X1338403Y1082995
X1342104Y1082995
X1345804Y1082995
X1316202Y1082995
X1319902Y1082995
X1312502Y1082995
X1368004Y1070178
X1368004Y1076587
X1355053Y1079791
X1362453Y1079791
X1349504Y1070178
X1349503Y1076587
X1351353Y1073383
X1355053Y1066974
X1355053Y1073383
X1358754Y1073383
X1360603Y1070178
X1360604Y1076587
X1362453Y1066974
X1347653Y1079791
X1336554Y1079791
X1347654Y1066974
X1334704Y1076587
X1334703Y1070178
X1336553Y1066974
X1342104Y1076587
X1342104Y1070178
X1332854Y1073383
X1318053Y1079791
X1321753Y1079791
X1329153Y1079791
X1321753Y1066974
X1325454Y1073383
X1323603Y1070178
X1323603Y1076587
X1329153Y1066974
X1316204Y1076587
X1319903Y1070178
X1319903Y1076587
X1329153Y1073383
X1368004Y1063770
X1371704Y1063770
X1364303Y1063770
X1368004Y1050952
X1368004Y1057361
X1349504Y1050952
X1349503Y1057361
X1351353Y1054157
X1355053Y1054157
X1355053Y1060565
X1358754Y1054157
X1360603Y1050952
X1360604Y1057361
X1362454Y1060565
X1338403Y1063770
X1342104Y1063770
X1345804Y1063770
X1347653Y1060565
X1334703Y1050952
X1334704Y1057361
X1336554Y1060565
X1342104Y1050952
X1342104Y1057361
X1332854Y1054157
X1319903Y1063770
X1321753Y1060565
X1323603Y1057361
X1323603Y1050952
X1319903Y1050952
X1319903Y1057361
X1325453Y1054157
X1329153Y1054157
X1329153Y1060565
X1309976Y1062790
X1314353Y1060565
X1368004Y1038136
X1368004Y1044544
X1371704Y1044544
X1364303Y1044544
X1355053Y1047749
X1362453Y1047749
X1349503Y1038136
X1351353Y1034931
X1355053Y1034931
X1355053Y1041340
X1358754Y1034931
X1360604Y1038136
X1362454Y1041340
X1347653Y1047749
X1336553Y1047749
X1347653Y1041340
X1334704Y1038136
X1336554Y1041340
X1338403Y1044544
X1342104Y1038136
X1342104Y1044544
X1345804Y1044544
X1332854Y1034931
X1321753Y1047749
X1319903Y1044544
X1321753Y1041340
X1323603Y1038136
X1325453Y1034931
X1329153Y1041340
X1319903Y1038136
X1318053Y1041340
X1329153Y1047749
X1329153Y1034931
X1310653Y1041340
X1308803Y1044544
X1314353Y1041340
X1368004Y1031727
X1366154Y1015705
X1368004Y1018910
X1368004Y1025318
X1369853Y1015705
X1371704Y1025318
X1364303Y1025318
X1349504Y1031727
X1360603Y1031727
X1349503Y1018910
X1351353Y1015705
X1355053Y1015705
X1355053Y1022114
X1355053Y1028523
X1358754Y1015705
X1360604Y1018910
X1362454Y1022114
X1362453Y1028523
X1334703Y1031727
X1342104Y1031727
X1347653Y1022114
X1347653Y1028523
X1334704Y1018910
X1336554Y1022114
X1338403Y1025318
X1336553Y1028523
X1340254Y1015705
X1342104Y1018910
X1342104Y1025318
X1343953Y1015705
X1345804Y1025318
X1332854Y1015705
X1323603Y1031727
X1319903Y1031727
X1321753Y1015705
X1321753Y1022114
X1319903Y1018910
X1321753Y1028523
X1323603Y1018910
X1325453Y1015705
X1329153Y1022114
X1318053Y1015705
X1318053Y1022114
X1329153Y1015705
X1329153Y1028523
X1308803Y1018910
X1308803Y1025318
X1314353Y1022114
X1314353Y1015705
X1368003Y1012501
X1368004Y0999684
X1368004Y1006093
X1371704Y1006093
X1364303Y1006093
X1349504Y1012501
X1360603Y1012501
X1355053Y1002888
X1355053Y1009297
X1360604Y0999684
X1362454Y1002888
X1362453Y1009297
X1349503Y0999684
X1334703Y1012501
X1342103Y1012501
X1347654Y1009297
X1334704Y0999684
X1336554Y1002888
X1336553Y1009297
X1338403Y1006093
X1342104Y1006093
X1342104Y0999684
X1345804Y1006093
X1323603Y1012501
X1321753Y1002888
X1319903Y1006093
X1321753Y1009297
X1323603Y0999684
X1329153Y1002888
X1329153Y1009297
X1331003Y1006093
X1327304Y1006093
X1318053Y1002888
X1318053Y1009297
X1308803Y1006093
X1314353Y1002888
X1351352Y0996480
X1314352Y0996480
X1311491Y0985939
X1321753Y1105426
X1319904Y1108630
X1323603Y1115039
X1331003Y1102221
X1329154Y1111834
X1327304Y1108630
X1355054Y1105426
X1353204Y1108630
X1356904Y1102221
X1355053Y1111834
X1360604Y1108630
X1358753Y1111834
X1318053Y1105426
X1318054Y1111834
X1321753Y1111834
X1327303Y1102221
X1325454Y1111834
X1329153Y1105426
X1351353Y1105426
X1351353Y1111834
X1358753Y1105426
X1356904Y1115039
X1362453Y1105426
X1362453Y1111834
X1316203Y1121447
X1319903Y1121447
X1318053Y1131060
X1323603Y1127856
X1321753Y1124651
X1338403Y1108630
X1334703Y1115039
X1342103Y1108630
X1345803Y1115039
X1343954Y1111834
X1371704Y1108630
X1368004Y1115039
X1312503Y1121447
X1318054Y1118243
X1316203Y1127856
X1319903Y1127856
X1323603Y1121447
X1334703Y1108630
X1336554Y1111834
X1340254Y1105426
X1342103Y1115039
X1345803Y1108630
X1368004Y1108630
X1369853Y1111834
X1368004Y1134264
X1368004Y1121447
X1369853Y1105426
X1368004Y1102221
X1360604Y1134264
X1353204Y1134264
X1353204Y1121447
X1360604Y1121447
X1358753Y1099017
X1356904Y1095813
X1345804Y1134264
X1338404Y1134264
X1338403Y1121447
X1345804Y1121447
X1336554Y1105426
X1343953Y1105426
X1345803Y1102221
X1334704Y1102221
X1323603Y1134264
X1331003Y1134264
X1331003Y1121447
X1329153Y1118243
X1325453Y1105426
X1314353Y1131060
X1314353Y1118243
X1327304Y1127856
X1364304Y1121447
X1360604Y1127856
X1356904Y1121447
X1353204Y1127856
X1349504Y1121447
X1345804Y1127856
X1342104Y1121447
X1338404Y1127856
X1332854Y1124651
X1369853Y1124651
X1368004Y1127856
X1331003Y1127856
X1362453Y1124651
X1358753Y1124651
X1355053Y1124651
X1351353Y1124651
X1347653Y1124651
X1343953Y1124651
X1340253Y1124651
X1336554Y1124651
X1334703Y1121447
X1371704Y1121447
X1366153Y1124651
X1329153Y1124651
X1362454Y1137469
X1358754Y1137469
X1355054Y1137469
X1351354Y1137469
X1347654Y1137469
X1343954Y1137469
X1340254Y1137469
X1336554Y1137469
X1332854Y1137469
X1369854Y1137469
X1366154Y1137469
X1327303Y1134264
X1364304Y1134264
X1360603Y1140973
X1356904Y1134264
X1353203Y1140973
X1349504Y1134264
X1345803Y1140973
X1342104Y1134264
X1338403Y1140973
X1334703Y1134264
X1371704Y1134264
X1368003Y1140973
X1325452Y1137469
X1351354Y1099017
X1366153Y1092608
X1369853Y1092608
X1362453Y1092608
X1364304Y1095813
X1366153Y1099017
X1358753Y1086200
X1356904Y1089404
X1351353Y1086200
X1369853Y1086200
X1371704Y1089404
X1366153Y1086200
X1364304Y1089404
X1371704Y1095813
X1369853Y1099017
X1353204Y1089404
X1347653Y1092608
X1340253Y1092608
X1343953Y1092608
X1336553Y1092608
X1343953Y1086200
X1345804Y1089404
X1340253Y1086200
X1338404Y1089404
X1345804Y1095813
X1343953Y1099017
X1338404Y1095813
X1340253Y1099017
X1332853Y1086200
X1331003Y1089404
X1325453Y1086200
X1327303Y1089404
X1366153Y1131060
X1369853Y1131060
X1371703Y1140973
X1364303Y1140973
X1349503Y1140973
X1351353Y1131060
X1355053Y1131060
X1356903Y1140973
X1358753Y1131060
X1362453Y1131060
X1347653Y1131060
X1332854Y1131060
X1334703Y1140973
X1336554Y1131060
X1340254Y1131060
X1342103Y1140973
X1343953Y1131060
X1319903Y1134264
X1325453Y1131060
X1321753Y1131060
X1321752Y1137469
X1329153Y1131060
X1329152Y1137469
X1371703Y1127856
X1364303Y1127856
X1366153Y1118243
X1369853Y1118243
X1371703Y1115039
X1364303Y1115039
X1349503Y1127856
X1356903Y1127856
X1349503Y1115039
X1351353Y1118243
X1353203Y1115039
X1355053Y1118243
X1358753Y1118243
X1360603Y1115039
X1362453Y1118243
X1334703Y1127856
X1342104Y1127856
X1347653Y1118243
X1332853Y1118243
X1336553Y1118243
X1338403Y1115039
X1340253Y1118243
X1343953Y1118243
X1318053Y1124651
X1319903Y1115039
X1321753Y1118243
X1325454Y1118243
X1325453Y1124651
X1327303Y1115039
X1327303Y1121447
X1331003Y1115039
X1316203Y1115039
X1312503Y1127856
X1312503Y1115039
X1314353Y1124651
X1366153Y1111834
X1366153Y1105426
X1371704Y1102221
X1364304Y1102221
X1364304Y1108630
X1349503Y1102221
X1349503Y1108630
X1353204Y1102221
X1355053Y1099017
X1356904Y1108630
X1360604Y1102221
X1362454Y1099017
X1347654Y1111834
X1332854Y1111834
X1340254Y1111834
X1347654Y1099017
X1347654Y1105426
X1332853Y1099017
X1332853Y1105426
X1336553Y1099017
X1338404Y1102221
X1342104Y1102221
X1319903Y1102221
X1323603Y1102221
X1325453Y1099017
X1316203Y1102221
X1316203Y1108630
X1323603Y1108630
X1329153Y1099017
X1331003Y1108630
X1311486Y1097289
X1314353Y1105426
X1314353Y1111834
X1368004Y1095813
X1368004Y1089404
X1349504Y1095813
X1360604Y1095813
X1349504Y1089404
X1351353Y1092608
X1355053Y1086200
X1355053Y1092608
X1358753Y1092608
X1360603Y1089404
X1362453Y1086200
X1334703Y1095813
X1342104Y1095813
X1347654Y1086200
X1332854Y1092608
X1334703Y1089404
X1336553Y1086200
X1342104Y1089404
X1316203Y1095813
X1319849Y1091513
X1321752Y1086200
X1323603Y1089404
X1325452Y1092609
X1329153Y1092608
X1329153Y1086200
X1305774Y1092168
X1371212Y1578088
X1363412Y1578182
X1359152Y1578182
X1351352Y1578182
X1339292Y1578182
X1347092Y1578182
X1335032Y1578182
X1327232Y1578182
X1322972Y1578182
X1315172Y1578182
X1310912Y1578182
X1303112Y1578182
X1291052Y1578182
X1298852Y1578182
X1286792Y1578182
X1278992Y1578182
X1274732Y1578182
X1355315Y1679920
X1355315Y1675383
X1363189Y1679320
X1347441Y1679320
X1331693Y1679320
X1339567Y1679920
X1339567Y1675383
X1315945Y1679320
X1323819Y1679920
X1323819Y1675383
X1308071Y1679920
X1308071Y1675383
X1288386Y1679920
X1288386Y1675383
X1296260Y1679320
X1280512Y1679320
X1272638Y1679920
X1272638Y1675383
X1368712Y1614292
X1368712Y1602380
X1364452Y1614292
X1364452Y1602380
X1356652Y1614292
X1356652Y1602380
X1352392Y1614292
X1352392Y1602380
X1344592Y1614292
X1344592Y1602380
X1332532Y1614292
X1332532Y1602380
X1340332Y1614292
X1340332Y1602380
X1320472Y1614292
X1320472Y1602380
X1328272Y1614292
X1328272Y1602380
X1316212Y1602380
X1316212Y1614292
X1308412Y1614292
X1308412Y1602380
X1304152Y1614292
X1304152Y1602380
X1296352Y1614292
X1296352Y1602380
X1292092Y1602380
X1292092Y1614292
X1284292Y1614292
X1284292Y1602380
X1280032Y1602380
X1280032Y1614292
X1272232Y1614292
X1272232Y1602380
X1371212Y1590094
X1363412Y1590094
X1359152Y1590094
X1351352Y1590094
X1339292Y1590094
X1347092Y1590094
X1335032Y1590094
X1327232Y1590094
X1322972Y1590094
X1315172Y1590094
X1310912Y1590094
X1303112Y1590094
X1291052Y1590094
X1298852Y1590094
X1286792Y1590094
X1278992Y1590094
X1274732Y1590094
X1355315Y1717903
X1355315Y1722440
X1355315Y1726974
X1363189Y1716737
X1363189Y1721840
X1363189Y1726377
X1363189Y1730911
X1347441Y1716737
X1347441Y1721840
X1347441Y1726377
X1347441Y1730911
X1331693Y1716737
X1331693Y1721840
X1331693Y1726377
X1331693Y1730911
X1339567Y1717903
X1339567Y1722440
X1339567Y1726974
X1315945Y1716737
X1315945Y1721840
X1315945Y1726377
X1315945Y1730911
X1323819Y1717903
X1323819Y1722440
X1323819Y1726974
X1308071Y1717903
X1308071Y1722440
X1308071Y1726974
X1288386Y1717903
X1288386Y1722440
X1288386Y1726974
X1296260Y1716737
X1296260Y1721840
X1296260Y1726377
X1296260Y1730911
X1280512Y1716737
X1280512Y1721840
X1280512Y1726377
X1280512Y1730911
X1272638Y1717903
X1272638Y1722440
X1272638Y1726974
X1355315Y1712800
X1355315Y1708266
X1355315Y1703729
X1363189Y1702564
X1363189Y1712203
X1363189Y1707666
X1347441Y1702564
X1347441Y1712203
X1347441Y1707666
X1331693Y1702564
X1331693Y1712203
X1331693Y1707666
X1339567Y1712800
X1339567Y1708266
X1339567Y1703729
X1315945Y1702564
X1315945Y1712203
X1315945Y1707666
X1323819Y1712800
X1323819Y1708266
X1323819Y1703729
X1308071Y1712800
X1308071Y1708266
X1308071Y1703729
X1288386Y1712800
X1288386Y1708266
X1288386Y1703729
X1296260Y1702564
X1296260Y1712203
X1296260Y1707666
X1280512Y1702564
X1280512Y1712203
X1280512Y1707666
X1272638Y1712800
X1272638Y1708266
X1272638Y1703729
X1355315Y1698627
X1355315Y1694093
X1355315Y1689556
X1355315Y1684454
X1363189Y1683857
X1363189Y1698030
X1363189Y1693493
X1363189Y1688391
X1347441Y1683857
X1347441Y1698030
X1347441Y1693493
X1347441Y1688391
X1331693Y1683857
X1331693Y1698030
X1331693Y1693493
X1331693Y1688391
X1339567Y1698627
X1339567Y1694093
X1339567Y1689556
X1339567Y1684454
X1315945Y1683857
X1315945Y1698030
X1315945Y1693493
X1315945Y1688391
X1323819Y1698627
X1323819Y1694093
X1323819Y1689556
X1323819Y1684454
X1308071Y1698627
X1308071Y1694093
X1308071Y1689556
X1308071Y1684454
X1288386Y1698627
X1288386Y1694093
X1288386Y1689556
X1288386Y1684454
X1296260Y1683857
X1296260Y1698030
X1296260Y1693493
X1296260Y1688391
X1280512Y1683857
X1280512Y1698030
X1280512Y1693493
X1280512Y1688391
X1272638Y1698627
X1272638Y1694093
X1272638Y1689556
X1272638Y1684454
X1465395Y1614292
X1465395Y1602380
X1388572Y1602380
X1388572Y1614292
X1380772Y1614292
X1380772Y1602380
X1376512Y1614292
X1376512Y1602286
X1467895Y1590094
X1460095Y1590094
X1383272Y1590094
X1375472Y1590094
X1467895Y1578182
X1460095Y1578182
X1383272Y1578182
X1375472Y1578182
X1454954Y1086199
X1438303Y1089403
X1434603Y1089403
X1430903Y1095812
X1440154Y1092607
X1436454Y1099016
X1442003Y1095812
X1451254Y1086199
X1447554Y1092607
X1453103Y1095812
X1458654Y1092607
X1436454Y1086199
X1430903Y1089403
X1432754Y1092607
X1442003Y1089403
X1434603Y1095812
X1438303Y1095812
X1447554Y1086199
X1449403Y1089403
X1451254Y1092607
X1454954Y1092607
X1390204Y1127856
X1388354Y1137469
X1382803Y1121447
X1375404Y1121447
X1384653Y1092608
X1386504Y1089404
X1380953Y1086200
X1395753Y1092608
X1401304Y1095813
X1403153Y1092608
X1395753Y1086200
X1406852Y1086200
X1403154Y1086200
X1382804Y1089404
X1390204Y1089404
X1379103Y1089404
X1397604Y1089404
X1399453Y1092608
X1406853Y1092608
X1399453Y1086200
X1405003Y1089404
X1388353Y1086200
X1375404Y1108630
X1379104Y1115039
X1377253Y1111834
X1386504Y1108630
X1384653Y1111834
X1390204Y1115039
X1388353Y1105426
X1395753Y1111834
X1392053Y1105426
X1384653Y1099017
X1379104Y1102221
X1373553Y1105426
X1375404Y1115039
X1379104Y1108630
X1384653Y1105426
X1388353Y1111834
X1392053Y1111834
X1390204Y1102221
X1393904Y1108630
X1395753Y1105426
X1380953Y1099017
X1377253Y1099017
X1390203Y1095813
X1445703Y1134264
X1442003Y1140973
X1442003Y1134264
X1440154Y1137469
X1440154Y1131060
X1438303Y1140973
X1438303Y1134264
X1436454Y1137469
X1436454Y1131060
X1434603Y1140973
X1432754Y1137469
X1432753Y1131060
X1430903Y1140973
X1430903Y1134264
X1443854Y1137469
X1443854Y1131060
X1442003Y1127856
X1440154Y1124651
X1440153Y1118243
X1438303Y1127856
X1438303Y1121447
X1438303Y1115039
X1436454Y1124651
X1436454Y1118243
X1432753Y1124651
X1432753Y1118243
X1430903Y1127856
X1430903Y1121447
X1430903Y1115039
X1436454Y1111834
X1434603Y1108630
X1432753Y1111834
X1432754Y1105426
X1430903Y1108630
X1430903Y1102221
X1429054Y1137769
X1429054Y1131060
X1427203Y1134264
X1425354Y1137769
X1425354Y1131060
X1421653Y1137769
X1421653Y1131060
X1419803Y1134264
X1417954Y1137769
X1417954Y1131060
X1416103Y1134264
X1414254Y1137769
X1414254Y1131060
X1429054Y1124651
X1429054Y1118243
X1427203Y1127856
X1427203Y1121447
X1427203Y1115039
X1425354Y1124651
X1425354Y1118243
X1421653Y1124651
X1421653Y1118243
X1419803Y1127856
X1419803Y1121447
X1419803Y1115039
X1417954Y1124651
X1417954Y1118243
X1416103Y1127856
X1416103Y1121447
X1416103Y1115039
X1414254Y1124651
X1414254Y1118243
X1429054Y1111834
X1429054Y1105426
X1427203Y1108630
X1427203Y1102221
X1425354Y1111834
X1425354Y1105426
X1425354Y1099017
X1421653Y1111834
X1421653Y1105426
X1421653Y1099017
X1419803Y1108630
X1419803Y1102221
X1417954Y1111834
X1417954Y1105426
X1417954Y1099017
X1416103Y1108630
X1416103Y1102221
X1414254Y1111834
X1414254Y1105426
X1414254Y1099017
X1425353Y1092608
X1423503Y1095813
X1423503Y1089404
X1421653Y1092608
X1421653Y1086200
X1419803Y1095813
X1419803Y1089404
X1417954Y1092608
X1417954Y1086200
X1416103Y1095813
X1416103Y1089404
X1414254Y1092608
X1414254Y1086200
X1408703Y1134264
X1406853Y1137769
X1406853Y1131060
X1405003Y1140973
X1405003Y1134264
X1403154Y1137569
X1403154Y1131060
X1401303Y1140973
X1401304Y1134264
X1397603Y1140973
X1397603Y1134264
X1412403Y1134264
X1408703Y1127856
X1408703Y1121447
X1408703Y1115039
X1406853Y1124651
X1406853Y1118243
X1405003Y1127856
X1405003Y1121447
X1405003Y1115039
X1403154Y1124651
X1403154Y1118243
X1401304Y1127856
X1401304Y1121447
X1401304Y1115039
X1397603Y1127856
X1397603Y1121447
X1412404Y1127856
X1412404Y1121447
X1412404Y1115039
X1410554Y1099017
X1408703Y1108630
X1408703Y1102221
X1406853Y1111834
X1406853Y1105426
X1406853Y1099017
X1405003Y1108630
X1405003Y1102221
X1403154Y1111834
X1403154Y1105426
X1401304Y1108630
X1412404Y1108630
X1412404Y1102221
X1412403Y1095813
X1412404Y1089404
X1395754Y1137469
X1395754Y1131060
X1393903Y1140973
X1393903Y1134264
X1392054Y1137469
X1392054Y1131060
X1390203Y1140973
X1395754Y1124651
X1395754Y1118243
X1393903Y1127856
X1393903Y1121447
X1392054Y1124651
X1374847Y1153069
X1464204Y1134264
X1471604Y1134264
X1464204Y1121447
X1464204Y1115039
X1464204Y1095813
X1456804Y1134264
X1449404Y1121447
X1456804Y1121447
X1456804Y1102221
X1449404Y1095813
X1456804Y1089404
X1443853Y1099017
X1438304Y1102221
X1429053Y1086200
X1399453Y1099017
X1397604Y1102221
X1382804Y1134264
X1393904Y1095813
X1380953Y1092608
X1375404Y1134264
X1386504Y1121447
X1382804Y1127856
X1379104Y1121447
X1375404Y1127856
X1384653Y1124651
X1380953Y1124651
X1377253Y1124651
X1373553Y1124651
X1384654Y1137469
X1380954Y1137469
X1377254Y1137469
X1373554Y1137469
X1386504Y1134264
X1382803Y1140973
X1379104Y1134264
X1375403Y1140973
X1469753Y1124651
X1447553Y1124651
X1451253Y1124651
X1454953Y1124651
X1458653Y1124651
X1462353Y1124651
X1466053Y1124651
X1467904Y1121447
X1471604Y1127856
X1445704Y1121447
X1449404Y1127856
X1453104Y1121447
X1456804Y1127856
X1460504Y1121447
X1464204Y1127856
X1449403Y1140973
X1454954Y1137469
X1456803Y1140973
X1462354Y1137469
X1466054Y1137469
X1467904Y1134264
X1471603Y1140973
X1451254Y1137469
X1453104Y1134264
X1458654Y1137469
X1460504Y1134264
X1464203Y1140973
X1469754Y1137469
X1395754Y1099017
X1462353Y1086200
X1464204Y1089404
X1469753Y1086200
X1467904Y1089404
X1373553Y1092608
X1467903Y1140973
X1466053Y1131060
X1469753Y1131060
X1462353Y1131060
X1460503Y1140973
X1449403Y1134264
X1447554Y1131060
X1447554Y1137469
X1451253Y1131060
X1453103Y1140973
X1454953Y1131060
X1458653Y1131060
X1445703Y1140973
X1434604Y1134264
X1423503Y1134264
X1410553Y1131060
X1410554Y1137769
X1399453Y1131060
X1399454Y1137469
X1384653Y1131060
X1386503Y1140973
X1388354Y1131060
X1390204Y1134264
X1380953Y1131060
X1373553Y1131060
X1377253Y1131060
X1379103Y1140973
X1471604Y1115039
X1467904Y1115039
X1467903Y1127856
X1466053Y1118243
X1469754Y1118243
X1471604Y1121447
X1462353Y1118243
X1449404Y1115039
X1460504Y1115039
X1453103Y1127856
X1460503Y1127856
X1445704Y1127856
X1447553Y1118243
X1451253Y1118243
X1453103Y1115039
X1454953Y1118243
X1456803Y1115039
X1458653Y1118243
X1445703Y1115039
X1434604Y1127856
X1442004Y1115039
X1442004Y1121447
X1443853Y1118243
X1443854Y1124651
X1434604Y1115039
X1434604Y1121447
X1423503Y1127856
X1423503Y1115039
X1423503Y1121447
X1410553Y1118243
X1410553Y1124651
X1397604Y1115039
X1399453Y1118243
X1399453Y1124651
X1386503Y1127856
X1382803Y1115039
X1384653Y1118243
X1386503Y1115039
X1388353Y1118243
X1388353Y1124651
X1390203Y1121447
X1392053Y1118243
X1393903Y1115039
X1380953Y1118243
X1379103Y1127856
X1373553Y1118243
X1377253Y1118243
X1464204Y1108630
X1467904Y1108630
X1469753Y1111834
X1462353Y1111834
X1466053Y1105426
X1471604Y1108630
X1469753Y1099017
X1471604Y1102221
X1466053Y1099017
X1466053Y1111834
X1464203Y1102221
X1467904Y1102221
X1469753Y1105426
X1462354Y1099017
X1462353Y1105426
X1460504Y1102221
X1451253Y1105426
X1447553Y1105426
X1453104Y1108630
X1454953Y1111834
X1458653Y1099017
X1449404Y1102221
X1445704Y1108630
X1454953Y1105426
X1447553Y1111834
X1451253Y1111834
X1460504Y1108630
X1458653Y1111834
X1447553Y1099017
X1451254Y1099017
X1453104Y1102221
X1449404Y1108630
X1454953Y1099017
X1456804Y1108630
X1458653Y1105426
X1445704Y1102221
X1443853Y1111834
X1443853Y1105426
X1440154Y1111834
X1438304Y1108630
X1440154Y1099017
X1440154Y1105426
X1442003Y1102221
X1442003Y1108630
X1432753Y1099017
X1434604Y1102221
X1436454Y1105426
X1423503Y1102221
X1423503Y1108630
X1429053Y1099017
X1410553Y1111834
X1399453Y1111834
X1410553Y1105426
X1397604Y1108630
X1399453Y1105426
X1401303Y1102221
X1403153Y1099017
X1380954Y1111834
X1382803Y1102221
X1382803Y1108630
X1386504Y1102221
X1388353Y1099017
X1390204Y1108630
X1392054Y1099017
X1393904Y1102221
X1380954Y1105426
X1373553Y1111834
X1373554Y1099017
X1375404Y1102221
X1377253Y1105426
X1467904Y1095813
X1471604Y1095813
X1471603Y1089404
X1466053Y1086200
X1466053Y1092608
X1469754Y1092608
X1462353Y1092608
X1456803Y1095813
X1460504Y1095813
X1445704Y1095813
X1460504Y1089404
X1453104Y1089404
X1458654Y1086200
X1445703Y1089404
X1443854Y1092608
X1440153Y1086200
X1443854Y1086200
X1436453Y1092608
X1432753Y1086200
X1427203Y1095812
X1425354Y1086200
X1427204Y1089404
X1429053Y1092608
X1397604Y1095813
X1405003Y1095813
X1408703Y1095813
X1410553Y1086200
X1410553Y1092608
X1401304Y1089404
X1408703Y1089404
X1382804Y1095813
X1386504Y1095813
X1384653Y1086200
X1388353Y1092608
X1392054Y1086200
X1392053Y1092608
X1393903Y1089404
X1375403Y1095813
X1379104Y1095813
X1373554Y1086200
X1375404Y1089404
X1377253Y1086200
X1377254Y1092608
X1434604Y1076587
X1427202Y1082995
X1430902Y1082995
X1453103Y1082994
X1384653Y1079791
X1382804Y1082995
X1390204Y1082995
X1401304Y1082995
X1386504Y1082995
X1379104Y1082995
X1406853Y1079791
X1405003Y1076587
X1406853Y1060565
X1405003Y1063770
X1403153Y1060565
X1399453Y1060565
X1395753Y1060565
X1406853Y1066974
X1405004Y1070178
X1401304Y1070178
X1390204Y1063770
X1395753Y1066974
X1388353Y1066974
X1397604Y1070178
X1393904Y1070178
X1390204Y1070178
X1392053Y1073383
X1388353Y1073383
X1401304Y1063770
X1393904Y1063770
X1384653Y1066974
X1390204Y1044544
X1390204Y1057361
X1380953Y1054157
X1384653Y1047749
X1379104Y1050952
X1386504Y1044544
X1388353Y1054157
X1386504Y1063770
X1382804Y1044544
X1384653Y1060565
X1382804Y1063770
X1377253Y1047749
X1427204Y1057361
X1430904Y1057361
X1436453Y1060565
X1434603Y1050952
X1430903Y1050952
X1395753Y1054157
X1379104Y1038136
X1397604Y1050952
X1405004Y1050952
X1377253Y1054157
X1399453Y1054157
X1401304Y1050952
X1397604Y1057361
X1393904Y1057361
X1390204Y1050952
X1392053Y1047749
X1440154Y1060565
X1434604Y1044544
X1438304Y1044544
X1440153Y1041340
X1377253Y1015705
X1458653Y1073383
X1440153Y1073383
X1427204Y1070178
X1432753Y1041340
X1458653Y1015705
X1395753Y1047749
X1427203Y1050952
X1429053Y1054157
X1442004Y1076587
X1451253Y1073383
X1397604Y1044544
X1456804Y1025318
X1379104Y1012501
X1377253Y1009297
X1432753Y1066974
X1430903Y1063770
X1437113Y1037069
X1439413Y1037069
X1434813Y1037069
X1434083Y1034408
X1434083Y1031908
X1425353Y1066974
X1429053Y1066974
X1427203Y1063770
X1447345Y1014539
X1447545Y1000079
X1447545Y0985579
X1445036Y1014549
X1434545Y1014539
X1437436Y1014509
X1429544Y1014498
X1445045Y1000079
X1434545Y1000079
X1437565Y1000079
X1429544Y1000698
X1429544Y1012198
X1429544Y0998398
X1445045Y0985579
X1434545Y0985579
X1437565Y0985579
X1429544Y0984598
X1429544Y0986898
X1419803Y1082995
X1416103Y1082995
X1421653Y1079791
X1417954Y1079791
X1414254Y1079791
X1421653Y1073383
X1421653Y1066974
X1419803Y1076587
X1419803Y1070178
X1417954Y1073383
X1417954Y1066974
X1416103Y1076587
X1416103Y1070178
X1414254Y1073383
X1414254Y1066974
X1419803Y1063770
X1416103Y1063770
X1421653Y1060565
X1419803Y1057361
X1417954Y1060565
X1416103Y1057361
X1414254Y1060565
X1421653Y1054157
X1419803Y1050952
X1417954Y1054157
X1416103Y1050952
X1414254Y1054157
X1417954Y1047749
X1414254Y1047749
X1421653Y1047749
X1427203Y1038136
X1425353Y1041340
X1425354Y1034931
X1423503Y1044544
X1421653Y1041340
X1421653Y1034931
X1419803Y1044544
X1419803Y1038136
X1417954Y1041340
X1417954Y1034931
X1416103Y1044544
X1416103Y1038136
X1414254Y1041340
X1414254Y1034931
X1427203Y1031727
X1419803Y1031727
X1416103Y1031727
X1427203Y1025318
X1419803Y1025318
X1416103Y1025318
X1427203Y1018910
X1425354Y1022114
X1425354Y1015705
X1421653Y1022114
X1421653Y1015705
X1419803Y1018910
X1417954Y1022114
X1417954Y1015705
X1416103Y1018910
X1414254Y1022114
X1414254Y1015705
X1425354Y1028523
X1417954Y1028523
X1414254Y1028523
X1421653Y1028523
X1427203Y1012501
X1427203Y1006093
X1427203Y0999684
X1425354Y1009297
X1425354Y1002888
X1421653Y1009297
X1421653Y1002888
X1419803Y1012501
X1419803Y1006093
X1419803Y0999684
X1417954Y1009297
X1417954Y1002888
X1416103Y1012501
X1416103Y1006093
X1416103Y0999684
X1414254Y1009297
X1414254Y1002888
X1412404Y1082995
X1412404Y1076587
X1412404Y1070178
X1412404Y1063770
X1412404Y1057361
X1412404Y1050952
X1410554Y1047749
X1399426Y1032283
X1399426Y1034583
X1399426Y1036883
X1404016Y1033603
X1410554Y1041340
X1408703Y1044544
X1408703Y1038136
X1406853Y1041340
X1406853Y1034931
X1412403Y1044544
X1412403Y1038136
X1404016Y1031303
X1404016Y1029003
X1408703Y1031727
X1412404Y1031727
X1404016Y1026703
X1408703Y1025318
X1412404Y1025318
X1408703Y1018910
X1406853Y1022114
X1406853Y1015705
X1412404Y1018910
X1406853Y1028523
X1399156Y1014469
X1404016Y1014451
X1398826Y1000059
X1404016Y0999820
X1404016Y1012151
X1408703Y1012501
X1408703Y1006093
X1408703Y0999684
X1406853Y1009297
X1406853Y1002888
X1412404Y1012501
X1412404Y1006093
X1412404Y0999684
X1404016Y0997520
X1398826Y0985579
X1404016Y0985410
X1396546Y1014469
X1388526Y1000079
X1396356Y1000039
X1386226Y1000079
X1386206Y0985609
X1388506Y0985609
X1396286Y0985549
X1449404Y1050952
X1445703Y1050952
X1451254Y1054157
X1449404Y1063770
X1449403Y1057361
X1447554Y1060565
X1445704Y1063770
X1445703Y1057361
X1453103Y1050952
X1456803Y1057361
X1454954Y1060565
X1453104Y1063770
X1453104Y1057361
X1454954Y1054157
X1458653Y1054157
X1456804Y1063770
X1453104Y1044544
X1454953Y1047749
X1452466Y1027194
X1452466Y1029494
X1452466Y1031794
X1446934Y1028889
X1443854Y1060565
X1443854Y1054157
X1401304Y1044544
X1399454Y1041340
X1395753Y1041340
X1392053Y1041340
X1388353Y1041340
X1445704Y1082995
X1442004Y1082995
X1438304Y1082995
X1441821Y1028854
X1434321Y1028854
X1436821Y1028854
X1439321Y1028854
X1399453Y1079791
X1398102Y1028854
X1392053Y1079791
X1395602Y1028854
X1393102Y1028854
X1390602Y1028854
X1388102Y1028854
X1375404Y1082995
X1380953Y1041340
X1383226Y1014539
X1387826Y1014539
X1385526Y1014539
X1379104Y1044544
X1377253Y1041340
X1375404Y1044544
X1454953Y1015705
X1456803Y1018910
X1454953Y1022114
X1454953Y1028523
X1379104Y1025318
X1379102Y1018910
X1377253Y1022114
X1375404Y1025318
X1434604Y1057361
X1436454Y1054157
X1447553Y1079791
X1438304Y1076587
X1386504Y1057361
X1449404Y1044544
X1456804Y1044544
X1454953Y1041340
X1456804Y1038136
X1436454Y1079791
X1430904Y1038136
X1440154Y1079791
X1430904Y1044544
X1445704Y1076587
X1449404Y1076587
X1447553Y1073383
X1453104Y1070178
X1456804Y1070178
X1456804Y1076587
X1453104Y1076587
X1456804Y1031727
X1454953Y1034931
X1440153Y1054157
X1442002Y1050952
X1443853Y1047750
X1436453Y1047750
X1399453Y1073383
X1382804Y1057361
X1408703Y1063770
X1408702Y1070178
X1447553Y1066974
X1445702Y1070178
X1375404Y1063770
X1377254Y1066974
X1408703Y1057361
X1405003Y1057361
X1454953Y1066974
X1377255Y1060565
X1379104Y1063770
X1442002Y1070178
X1440153Y1066974
X1438303Y1063770
X1436453Y1066974
X1434602Y1070178
X1436453Y1073383
X1393904Y1076587
X1425355Y1060565
X1379104Y1057361
X1445704Y1044544
X1425353Y1054157
X1429053Y1047749
X1451253Y1047749
X1443853Y1041340
X1447553Y1041340
X1403154Y1041340
X1377253Y1028523
X1427203Y1076587
X1429053Y1073383
X1467904Y1025318
X1467904Y1044544
X1467904Y1063770
X1467904Y1082995
X1460504Y1025318
X1460504Y1044544
X1460504Y1063770
X1464204Y1082995
X1471604Y1025318
X1471604Y1044544
X1471604Y1063770
X1471604Y1082995
X1464204Y1025318
X1464204Y1044544
X1464204Y1063770
X1460504Y1082995
X1467904Y1038136
X1469753Y1041340
X1464204Y1038136
X1462353Y1041340
X1469753Y1047749
X1467904Y1050952
X1462353Y1047749
X1464204Y1050952
X1467904Y1057361
X1469753Y1060565
X1464204Y1057361
X1462353Y1060565
X1469753Y1066974
X1467904Y1070178
X1462353Y1066974
X1464204Y1070178
X1467904Y1076587
X1469753Y1079791
X1464204Y1076587
X1462353Y1079791
X1462353Y1009297
X1464204Y1012501
X1469753Y1009297
X1467903Y1012501
X1467904Y1018910
X1469753Y1022114
X1464204Y1018910
X1462353Y1022114
X1469753Y1028523
X1467904Y1031727
X1462353Y1028523
X1464204Y1031727
X1467904Y0999684
X1464204Y0999684
X1469753Y1002888
X1462353Y1002888
X1471604Y1006093
X1460504Y1006093
X1456804Y1012501
X1454953Y1009297
X1454953Y1002888
X1456804Y0999684
X1373553Y1034931
X1373553Y1054157
X1373553Y1073383
X1373553Y1015705
X1379104Y0999684
X1375404Y0999684
X1379104Y1006093
X1375404Y1006093
X1403153Y1047749
X1449404Y1082995
X1456804Y1082995
X1434603Y1082995
X1423503Y1082995
X1397604Y1082995
X1405003Y1082995
X1408703Y1082995
X1393903Y1082995
X1466053Y1079791
X1466053Y1073383
X1471603Y1070178
X1466053Y1066974
X1469754Y1073383
X1471604Y1076587
X1462353Y1073383
X1451253Y1079791
X1454954Y1079791
X1458653Y1079791
X1454953Y1073383
X1458654Y1066974
X1460504Y1070178
X1449404Y1070178
X1451253Y1066974
X1460503Y1076587
X1443853Y1079791
X1432754Y1079791
X1438304Y1070178
X1443853Y1066974
X1443853Y1073383
X1430904Y1070178
X1430903Y1076587
X1432753Y1073383
X1425353Y1079791
X1429053Y1079791
X1423503Y1070178
X1423503Y1076587
X1425353Y1073383
X1410553Y1079791
X1403154Y1079791
X1410553Y1066974
X1410553Y1073383
X1399453Y1066974
X1401304Y1076587
X1403153Y1066974
X1403153Y1073383
X1406853Y1073383
X1408703Y1076587
X1388353Y1079791
X1380953Y1079791
X1382803Y1076587
X1386504Y1070178
X1386504Y1076587
X1392053Y1066974
X1395753Y1073383
X1380953Y1066974
X1373553Y1079791
X1377253Y1079791
X1373554Y1066974
X1375404Y1070178
X1375403Y1076587
X1377253Y1073383
X1469753Y1054157
X1471603Y1050952
X1466053Y1054157
X1466053Y1060565
X1471604Y1057361
X1462353Y1054157
X1460504Y1050952
X1447553Y1054157
X1451253Y1060565
X1456804Y1050952
X1458653Y1060565
X1460503Y1057361
X1442004Y1063770
X1434604Y1063770
X1438304Y1050952
X1442004Y1057361
X1432753Y1054157
X1423503Y1063770
X1423503Y1050952
X1423503Y1057361
X1429053Y1060565
X1397604Y1063770
X1410553Y1054157
X1410553Y1060565
X1401304Y1057361
X1408703Y1050952
X1384653Y1054157
X1386504Y1050952
X1388353Y1060565
X1392053Y1054157
X1392053Y1060565
X1393904Y1050952
X1380953Y1060565
X1373553Y1060565
X1375404Y1050952
X1375403Y1057361
X1466053Y1047749
X1469754Y1034931
X1471604Y1038136
X1466053Y1034931
X1466053Y1041340
X1462353Y1034931
X1447553Y1047749
X1458653Y1047749
X1460503Y1038136
X1451253Y1041340
X1458654Y1034931
X1458653Y1041340
X1440153Y1047749
X1432753Y1047749
X1442003Y1044544
X1436453Y1041340
X1443541Y1036914
X1449649Y1035928
X1447424Y1036526
X1425353Y1047749
X1423503Y1038136
X1427203Y1044544
X1429053Y1041340
X1399453Y1047749
X1406854Y1047749
X1410553Y1034931
X1405004Y1044544
X1388353Y1047749
X1380953Y1047749
X1384653Y1041340
X1393904Y1044544
X1373553Y1047749
X1373553Y1041340
X1375403Y1038136
X1471603Y1031727
X1469754Y1015705
X1471604Y1018910
X1466053Y1015705
X1466053Y1022114
X1466053Y1028523
X1462353Y1015705
X1460503Y1031727
X1460503Y1018910
X1458653Y1022114
X1458653Y1028523
X1423503Y1031727
X1423503Y1018910
X1423503Y1025318
X1410553Y1015705
X1410553Y1022114
X1410553Y1028523
X1375404Y1031727
X1373553Y1022114
X1373553Y1028523
X1375403Y1018910
X1471603Y1012501
X1464204Y1006093
X1467903Y1006093
X1466054Y1002888
X1466053Y1009297
X1471604Y0999684
X1460504Y1012501
X1458653Y1002888
X1458654Y1009297
X1460503Y0999684
X1423503Y1012501
X1423503Y0999684
X1423503Y1006093
X1410553Y1002888
X1410553Y1009297
X1375404Y1012501
X1373553Y1002888
X1373554Y1009297
X1377253Y1002888
X1442413Y0985579
X1430604Y0992998
X1430604Y0995298
X1440015Y0985579
X1442413Y1000059
X1442413Y1014539
X1430584Y1007108
X1430584Y1009408
X1440015Y1000059
X1440015Y1014539
X1430575Y1019885
X1430575Y1022185
X1452426Y0987625
X1452426Y0989925
X1452426Y0994525
X1452426Y0996825
X1452426Y1012925
X1452426Y1003725
X1452426Y1006025
X1452436Y1010499
X1452426Y1017525
X1452416Y1022635
X1391326Y0985579
X1393716Y0985579
X1381003Y0988721
X1381243Y0995271
X1381243Y0992971
X1381003Y0986421
X1391326Y1000059
X1393716Y1000059
X1393716Y1014539
X1391326Y1014539
X1381373Y1004848
X1381369Y1007156
X1381140Y1026821
X1381128Y1022427
X1384466Y1031970
X1384466Y1034270
X1403046Y0994721
X1403046Y0992421
X1403046Y1006874
X1403046Y1009174
X1403046Y1019662
X1403046Y1021962
X1380953Y1073383
X1382804Y1070178
X1379104Y1070178
X1379104Y1076587
X1384653Y1073383
X1438303Y1057361
X1379104Y1031727
X1432753Y1060565
X1397604Y1076587
X1395753Y1079791
X1406853Y1054157
X1382804Y1050952
X1403153Y1054157
X1410121Y0912262
X1426771Y0928283
X1411971Y0928283
X1413820Y0925079
X1415671Y0928283
X1421220Y0925079
X1415671Y0934691
X1421220Y0931488
X1419371Y0934691
X1424921Y0925079
X1408271Y0934691
X1406420Y0931488
X1408271Y0928283
X1406420Y0925079
X1411971Y0934691
X1413820Y0931488
X1419371Y0928283
X1423071Y0934691
X1424921Y0931488
X1452671Y0909057
X1445271Y0909057
X1448971Y0909057
X1454520Y0905853
X1443420Y0905853
X1447120Y0905853
X1439720Y0905853
X1436020Y0905853
X1387921Y0918670
X1391621Y0918670
X1436020Y0912262
X1439720Y0912262
X1436020Y0918670
X1430471Y0915466
X1424921Y0918670
X1434171Y0915466
X1428620Y0912262
X1447120Y0899445
X1452671Y0896240
X1428620Y0918670
X1426771Y0915466
X1434171Y0921875
X1441571Y0921875
X1439720Y0918670
X1445271Y0921875
X1380520Y0899445
X1437871Y0909057
X1448970Y0915466
X1445271Y0915466
X1443420Y0912262
X1454520Y0976347
X1437871Y0915466
X1393471Y0915466
X1391620Y0912262
X1387920Y0912262
X1391620Y0905853
X1402720Y0918670
X1391550Y0925219
X1393471Y0921875
X1397171Y0921875
X1399020Y0918670
X1400871Y0921875
X1419371Y0921875
X1421220Y0918670
X1456371Y0973143
X1452671Y0902649
X1454520Y0982756
X1456371Y0979552
X1378671Y0902649
X1384221Y0899446
X1391620Y0899445
X1399020Y0899445
X1406420Y0899445
X1399317Y0929464
X1401817Y0929464
X1399028Y0927155
X1401528Y0927155
X1447545Y0956619
X1434545Y0971099
X1437565Y0971139
X1429544Y0973098
X1429544Y0970798
X1445045Y0956619
X1434545Y0956619
X1437565Y0956619
X1429544Y0956998
X1429544Y0959298
X1429726Y0942237
X1429726Y0939937
X1429726Y0944537
X1426771Y0979552
X1424921Y0982756
X1421220Y0982756
X1419370Y0979552
X1417521Y0982756
X1415670Y0979552
X1413821Y0982756
X1426771Y0973143
X1424921Y0976347
X1424921Y0969939
X1421220Y0976347
X1421220Y0969939
X1419370Y0973143
X1417521Y0976347
X1417521Y0969939
X1415670Y0973143
X1413821Y0976347
X1413821Y0969939
X1426771Y0966735
X1424921Y0963530
X1421220Y0963530
X1419370Y0966735
X1417521Y0963530
X1415670Y0966735
X1413821Y0963530
X1426771Y0960326
X1426771Y0953917
X1424921Y0957122
X1424921Y0950713
X1421220Y0957122
X1421220Y0950713
X1419370Y0960326
X1419370Y0953917
X1417521Y0957122
X1417521Y0950713
X1415670Y0960326
X1415670Y0953917
X1413821Y0957122
X1413821Y0950713
X1426771Y0947509
X1419370Y0947509
X1415670Y0947509
X1426771Y0941100
X1424921Y0944304
X1421220Y0944304
X1419371Y0941100
X1417521Y0944304
X1415671Y0941100
X1413821Y0944304
X1404016Y0983110
X1411971Y0979552
X1408270Y0979552
X1406421Y0982756
X1398826Y0971099
X1404016Y0968966
X1404016Y0971266
X1411971Y0973143
X1408270Y0973143
X1406409Y0976347
X1406421Y0969939
X1411971Y0966735
X1408270Y0966735
X1406421Y0963530
X1398826Y0956619
X1401326Y0956619
X1404016Y0956372
X1404016Y0954072
X1411971Y0960326
X1411971Y0953917
X1408270Y0960326
X1408270Y0953917
X1406421Y0957122
X1406421Y0950713
X1411971Y0947509
X1408270Y0947509
X1404016Y0941929
X1404016Y0944229
X1411971Y0941100
X1408271Y0941100
X1406421Y0944304
X1396346Y0971099
X1385526Y0956619
X1391326Y0956619
X1387826Y0956619
X1393826Y0956619
X1394834Y0942097
X1392534Y0942097
X1465620Y0886627
X1446677Y0928348
X1458220Y0905853
X1450820Y0886627
X1458220Y0886627
X1442077Y0928348
X1444377Y0928348
X1435177Y0928348
X1437477Y0928348
X1439777Y0928348
X1443420Y0886627
X1436020Y0886627
X1443420Y0899445
X1436020Y0899445
X1421220Y0886627
X1428620Y0886627
X1428620Y0899445
X1399020Y0886627
X1406420Y0886627
X1391620Y0886627
X1384220Y0886627
X1382371Y0896240
X1447692Y0942195
X1449992Y0942195
X1445392Y0942195
X1381430Y0942163
X1383730Y0942163
X1386030Y0942163
X1376820Y0886627
X1452426Y0971525
X1452426Y0973825
X1447745Y0971099
X1445445Y0971099
X1450045Y0971099
X1454520Y0950713
X1454520Y0957122
X1456371Y0953917
X1456371Y0947509
X1385526Y0971099
X1387826Y0971099
X1383226Y0971099
X1380926Y0971099
X1376822Y0950713
X1374971Y0953917
X1378671Y0953917
X1378671Y0947509
X1382371Y0902649
X1454520Y0899445
X1384220Y0912262
X1411971Y0921875
X1376820Y0912262
X1376820Y0893036
X1397171Y0915466
X1456370Y0909057
X1419371Y0915466
X1448971Y0902649
X1434171Y0909057
X1380520Y0893036
X1374971Y0896240
X1469320Y0886627
X1461920Y0886627
X1454520Y0886627
X1417520Y0886627
X1424920Y0886627
X1432320Y0886627
X1439720Y0886627
X1395320Y0886627
X1402720Y0886627
X1410120Y0886627
X1447120Y0886627
X1387920Y0886627
X1380520Y0886627
X1373120Y0886627
X1384220Y0905853
X1387920Y0905853
X1385070Y0928468
X1382809Y0927986
X1447120Y0918670
X1448971Y0921875
X1454522Y0912262
X1452671Y0915466
X1454521Y0918670
X1447122Y0912262
X1378671Y0921875
X1382371Y0921875
X1421222Y0912262
X1415671Y0909057
X1373121Y0893036
X1378671Y0960326
X1378671Y0966735
X1384220Y0918670
X1382371Y0915466
X1417522Y0912262
X1424922Y0912262
X1424921Y0905853
X1428621Y0905853
X1402720Y0905853
X1406420Y0905853
X1426772Y0909057
X1430471Y0909057
X1426771Y0921875
X1399020Y0905853
X1400870Y0909057
X1410120Y0905853
X1408270Y0909057
X1454521Y0969939
X1417521Y0905853
X1421221Y0905853
X1458220Y0982756
X1456370Y0960326
X1456371Y0915466
X1460071Y0953917
X1471171Y0896240
X1467471Y0915466
X1467471Y0934691
X1467471Y0953917
X1463771Y0896240
X1460071Y0915466
X1460071Y0934691
X1463771Y0953917
X1467471Y0896240
X1471171Y0915466
X1471171Y0934691
X1471171Y0953917
X1460071Y0896240
X1463771Y0915466
X1463771Y0934691
X1461920Y0918670
X1463771Y0921875
X1463771Y0928283
X1469320Y0931488
X1467471Y0928283
X1461920Y0931488
X1469320Y0937896
X1461920Y0893036
X1467471Y0941100
X1458220Y0893036
X1469320Y0893036
X1469320Y0899445
X1467471Y0902649
X1461920Y0899445
X1463771Y0902649
X1461920Y0937896
X1467471Y0909057
X1469320Y0912262
X1463771Y0909057
X1461920Y0912262
X1469320Y0918670
X1467471Y0921875
X1463771Y0941100
X1461920Y0957122
X1463771Y0960326
X1469320Y0957122
X1467471Y0960326
X1467471Y0947509
X1469320Y0950713
X1463771Y0947509
X1461920Y0950713
X1469320Y0969939
X1467471Y0966735
X1463771Y0966735
X1461920Y0969939
X1460071Y0973143
X1467471Y0973143
X1463771Y0973143
X1471171Y0973143
X1469320Y0976347
X1467471Y0979552
X1461920Y0976347
X1463771Y0979552
X1373120Y0905853
X1373120Y0925079
X1373120Y0944304
X1373120Y0963530
X1373120Y0982756
X1378671Y0973143
X1378671Y0979552
X1376820Y0976347
X1374971Y0973143
X1410121Y0918670
X1415671Y0915466
X1411971Y0915466
X1417520Y0918670
X1448971Y0896240
X1450820Y0893036
X1419371Y0909057
X1411971Y0909057
X1389771Y0915466
X1397171Y0909057
X1376820Y0899445
X1378671Y0909057
X1408271Y0921875
X1445271Y0902649
X1458220Y0963529
X1443420Y0918670
X1456371Y0966735
X1454520Y0963530
X1378671Y0896240
X1378671Y0915466
X1430471Y0921875
X1376820Y0905853
X1389771Y0909057
X1382371Y0909057
X1393471Y0909057
X1408271Y0915466
X1406420Y0912262
X1465620Y0982756
X1469321Y0982756
X1461920Y0982756
X1471171Y0979552
X1465620Y0969939
X1465620Y0976347
X1458220Y0976347
X1460070Y0979552
X1458221Y0969939
X1430404Y0978908
X1430404Y0981208
X1452476Y0980736
X1452333Y0977669
X1423071Y0973143
X1423071Y0979552
X1410121Y0982756
X1410121Y0969939
X1410121Y0976347
X1373121Y0969939
X1373120Y0976347
X1374970Y0979552
X1376820Y0969939
X1376820Y0982756
X1381003Y0978969
X1381003Y0981269
X1403046Y0980335
X1403046Y0978035
X1465620Y0963530
X1469321Y0963530
X1471170Y0966735
X1461920Y0963530
X1465620Y0950713
X1465620Y0957122
X1471171Y0960326
X1460071Y0966735
X1458221Y0950713
X1458220Y0957122
X1460070Y0960326
X1423071Y0966735
X1423071Y0953917
X1423071Y0960326
X1410121Y0963530
X1410121Y0950713
X1410121Y0957122
X1374971Y0966735
X1376820Y0963530
X1373121Y0950713
X1373120Y0957122
X1374970Y0960326
X1376820Y0957122
X1471170Y0947509
X1465620Y0937896
X1465620Y0944304
X1469321Y0944304
X1471171Y0941100
X1461920Y0944304
X1460070Y0947509
X1456371Y0934691
X1458220Y0937896
X1458221Y0944304
X1460070Y0941100
X1430564Y0949138
X1430534Y0966128
X1430534Y0963828
X1442413Y0956539
X1430564Y0951438
X1440015Y0956539
X1442413Y0971099
X1440015Y0971139
X1452321Y0947654
X1452321Y0945354
X1454520Y0944304
X1452426Y0964625
X1452426Y0960025
X1452426Y0962325
X1452426Y0966925
X1423071Y0947509
X1423070Y0941100
X1410121Y0944304
X1374971Y0947509
X1373120Y0937896
X1374970Y0941100
X1376820Y0937896
X1465620Y0931488
X1471171Y0921875
X1465620Y0918670
X1465620Y0925079
X1469321Y0925079
X1471170Y0928283
X1461920Y0925079
X1458220Y0931488
X1450820Y0918670
X1452670Y0921875
X1460070Y0921875
X1456371Y0921875
X1458220Y0918670
X1460071Y0928283
X1432320Y0918670
X1437871Y0921875
X1423071Y0921875
X1413820Y0918670
X1404571Y0921875
X1381189Y0930811
X1390234Y0942097
X1381189Y0935745
X1381287Y0948539
X1381287Y0946239
X1381189Y0938045
X1381264Y0963596
X1381264Y0965896
X1392896Y0971139
X1390506Y0971139
X1410121Y0931488
X1410121Y0925079
X1410120Y0937896
X1404016Y0936469
X1406420Y0937896
X1403016Y0947198
X1403016Y0949498
X1403046Y0965934
X1403046Y0963634
X1417520Y0931488
X1417520Y0925079
X1423071Y0928283
X1413820Y0937896
X1417520Y0937896
X1421220Y0937896
X1424920Y0937896
X1430244Y0933658
X1430244Y0931358
X1443002Y0942151
X1440702Y0942151
X1438402Y0942151
X1452426Y0930125
X1452426Y0934725
X1386071Y0921875
X1395320Y0918670
X1395187Y0926265
X1380520Y0918670
X1373120Y0931488
X1373120Y0918670
X1374970Y0921875
X1374971Y0928283
X1376820Y0925079
X1469321Y0905853
X1471171Y0902649
X1465620Y0905853
X1465620Y0912262
X1471171Y0909057
X1461920Y0905853
X1460070Y0902649
X1450820Y0905853
X1450820Y0912262
X1458221Y0912262
X1460071Y0909057
X1441571Y0915466
X1441571Y0909057
X1441571Y0902649
X1430471Y0902649
X1432320Y0905853
X1432320Y0912262
X1434171Y0902649
X1437871Y0902649
X1423071Y0915466
X1415670Y0902649
X1419371Y0902649
X1423071Y0902649
X1423071Y0909057
X1426771Y0902649
X1413821Y0905853
X1413820Y0912262
X1404571Y0915466
X1411971Y0902649
X1404571Y0902649
X1404571Y0909057
X1408271Y0902649
X1397171Y0902649
X1400871Y0902649
X1386071Y0915466
X1386071Y0909057
X1389771Y0902649
X1393471Y0902649
X1395321Y0905853
X1395320Y0912262
X1380520Y0905853
X1380520Y0912262
X1373121Y0912262
X1374970Y0902649
X1374971Y0909057
X1465620Y0899445
X1463771Y0889832
X1467471Y0889832
X1471171Y0889832
X1465621Y0893036
X1450820Y0899445
X1458220Y0899445
X1448971Y0889832
X1452671Y0889832
X1460071Y0889832
X1447121Y0893036
X1454521Y0893036
X1456371Y0889832
X1456370Y0896240
X1441571Y0889832
X1445271Y0889832
X1439721Y0893036
X1445271Y0896240
X1430471Y0889832
X1432321Y0893036
X1434171Y0889832
X1437871Y0889832
X1413821Y0899445
X1415671Y0889832
X1415671Y0896240
X1417521Y0893036
X1419371Y0889832
X1423071Y0889832
X1424921Y0893036
X1426771Y0889832
X1413820Y0886627
X1411971Y0889832
X1400871Y0889832
X1402721Y0893036
X1404571Y0889832
X1408271Y0889832
X1410121Y0893036
X1397171Y0889832
X1382371Y0889832
X1384221Y0893036
X1386071Y0889832
X1387921Y0893036
X1389771Y0889832
X1393471Y0889832
X1395321Y0893036
X1373120Y0899445
X1374971Y0889832
X1378671Y0889832
X1386071Y0902649
X1456371Y0902649
X1415671Y0921875
X1443420Y0893036
X1439720Y0899445
X1434171Y0896240
X1432320Y0899445
X1428621Y0893036
X1423071Y0896240
X1421220Y0893036
X1417520Y0899445
X1441571Y0896240
X1437871Y0896240
X1436020Y0893036
X1430471Y0896240
X1426772Y0896240
X1424920Y0899445
X1419371Y0896240
X1421220Y0899445
X1411971Y0896240
X1408271Y0896240
X1406420Y0893036
X1400871Y0896240
X1399020Y0893036
X1395320Y0899445
X1391620Y0893036
X1387920Y0899445
X1413820Y0893036
X1410120Y0899445
X1404571Y0896240
X1402720Y0899445
X1397171Y0896240
X1393471Y0896240
X1389771Y0896240
X1386071Y0896240
X1406420Y0918670
X1402720Y0912262
X1400871Y0915466
X1399020Y0912262
X1456371Y0941100
X1454520Y0937896
X1458220Y0925079
X1454520Y0925079
X1378671Y0928283
X1376820Y0931488
X1454522Y0931488
X1456371Y0928283
X1378671Y0934691
X1374971Y0934691
X1421220Y0873810
X1428621Y0873810
X1376820Y0873810
X1384220Y0873810
X1413821Y0873810
X1406420Y0873810
X1413821Y0854584
X1408271Y0857789
X1406420Y0854584
X1400871Y0857789
X1399020Y0854584
X1393471Y0857789
X1391620Y0854584
X1386071Y0857789
X1384220Y0854584
X1378671Y0857789
X1376820Y0854584
X1411971Y0857789
X1410121Y0860993
X1404571Y0857789
X1402720Y0860993
X1397171Y0857789
X1395320Y0860993
X1389771Y0857789
X1387920Y0860993
X1382371Y0857789
X1380520Y0860993
X1374971Y0857789
X1373120Y0860993
X1469320Y0860993
X1419371Y0857789
X1423071Y0857789
X1426771Y0857789
X1428620Y0854584
X1434171Y0857789
X1436020Y0854584
X1441571Y0857789
X1443420Y0854584
X1448971Y0857789
X1450820Y0854584
X1456371Y0857789
X1458220Y0854584
X1463771Y0857789
X1465620Y0854584
X1471171Y0857789
X1417520Y0860993
X1421220Y0854584
X1424921Y0860993
X1430471Y0857789
X1432320Y0860993
X1437871Y0857789
X1439720Y0860993
X1445271Y0857789
X1447120Y0860993
X1452671Y0857789
X1454520Y0860993
X1460071Y0857789
X1461920Y0860993
X1467471Y0857789
X1413820Y0848176
X1410120Y0848176
X1404569Y0844971
X1400869Y0844971
X1395320Y0848176
X1391621Y0841467
X1387920Y0848176
X1384221Y0841467
X1382369Y0844971
X1378669Y0844971
X1374969Y0844971
X1411969Y0844971
X1406420Y0848176
X1402720Y0848176
X1399021Y0841467
X1397169Y0844971
X1393469Y0844971
X1389769Y0844971
X1386069Y0844971
X1380520Y0848176
X1376821Y0841467
X1373120Y0848176
X1465620Y0873810
X1465620Y0860993
X1465620Y0848176
X1450820Y0873810
X1458220Y0873810
X1458220Y0860993
X1450820Y0860993
X1458220Y0848176
X1450820Y0848176
X1443420Y0873810
X1436020Y0873810
X1436020Y0860993
X1443420Y0860993
X1436020Y0848176
X1443420Y0848176
X1428621Y0860993
X1421220Y0860993
X1399020Y0873810
X1399020Y0860993
X1406420Y0860993
X1399020Y0848176
X1391620Y0873810
X1391620Y0860993
X1384220Y0860993
X1384220Y0848176
X1391620Y0848176
X1376820Y0860993
X1376820Y0848176
X1471171Y0883423
X1463771Y0883423
X1456371Y0883423
X1448971Y0883423
X1467471Y0883423
X1465620Y0880219
X1460071Y0883423
X1458220Y0880219
X1452671Y0883423
X1450820Y0880219
X1469320Y0873810
X1467471Y0870606
X1461920Y0873810
X1460071Y0870606
X1454520Y0873810
X1452671Y0870606
X1471171Y0870606
X1465620Y0867401
X1463771Y0870606
X1458220Y0867401
X1456371Y0870606
X1450820Y0867401
X1411971Y0883423
X1419371Y0883423
X1426771Y0883423
X1434171Y0883423
X1441571Y0883423
X1389771Y0883423
X1397171Y0883423
X1404571Y0883423
X1413820Y0880219
X1415671Y0883423
X1421220Y0880219
X1423071Y0883423
X1428621Y0880219
X1430471Y0883423
X1436020Y0880219
X1437871Y0883423
X1443420Y0880219
X1391620Y0880219
X1393471Y0883423
X1399020Y0880219
X1400871Y0883423
X1406420Y0880219
X1408271Y0883423
X1445271Y0883423
X1411971Y0870606
X1413820Y0867401
X1419371Y0870606
X1421220Y0867401
X1426771Y0870606
X1428620Y0867401
X1434171Y0870606
X1436020Y0867401
X1441571Y0870606
X1389771Y0870606
X1391620Y0867401
X1397171Y0870606
X1399020Y0867401
X1404571Y0870606
X1406420Y0867401
X1443420Y0867401
X1410121Y0873810
X1415671Y0870606
X1417520Y0873810
X1423071Y0870606
X1424921Y0873810
X1430471Y0870606
X1432320Y0873810
X1437871Y0870606
X1439720Y0873810
X1387920Y0873810
X1393471Y0870606
X1395320Y0873810
X1400871Y0870606
X1402720Y0873810
X1408271Y0870606
X1445271Y0870606
X1382371Y0883423
X1374971Y0883423
X1386071Y0883423
X1384220Y0880219
X1378671Y0883423
X1376820Y0880219
X1382371Y0870606
X1380520Y0873810
X1374971Y0870606
X1373120Y0873810
X1384220Y0867401
X1378671Y0870606
X1376820Y0867401
X1463771Y0877014
X1467471Y0877014
X1469321Y0880219
X1471171Y0877014
X1461921Y0880219
X1447121Y0873810
X1447121Y0880219
X1448970Y0870606
X1448971Y0877014
X1452671Y0877014
X1454521Y0880219
X1456371Y0877014
X1460071Y0877014
X1439721Y0880219
X1441571Y0877014
X1445271Y0877014
X1430471Y0877014
X1432321Y0880219
X1434171Y0877014
X1437871Y0877014
X1415671Y0877014
X1417521Y0880219
X1419371Y0877014
X1423071Y0877014
X1424921Y0880219
X1426771Y0877014
X1411971Y0877014
X1400871Y0877014
X1402721Y0880219
X1404571Y0877014
X1408271Y0877014
X1410121Y0880219
X1397171Y0877014
X1382371Y0877014
X1386071Y0870606
X1386071Y0877014
X1387921Y0880219
X1389771Y0877014
X1393471Y0877014
X1395321Y0880219
X1380521Y0880219
X1373121Y0880219
X1374971Y0877014
X1378671Y0877014
X1469321Y0867401
X1461921Y0867401
X1463771Y0864197
X1467471Y0864197
X1469321Y0854584
X1471171Y0864197
X1461921Y0854584
X1447121Y0867401
X1454521Y0867401
X1448971Y0864197
X1447121Y0854584
X1452671Y0864197
X1454521Y0854584
X1456371Y0864197
X1460071Y0864197
X1439721Y0867401
X1432321Y0867401
X1441571Y0864197
X1445271Y0864197
X1430471Y0864197
X1434171Y0864197
X1437871Y0864197
X1417521Y0867401
X1424921Y0867401
X1415671Y0857789
X1415671Y0864197
X1417521Y0854584
X1419371Y0864197
X1423071Y0864197
X1424921Y0854584
X1426771Y0864197
X1413822Y0860993
X1402721Y0867401
X1410121Y0867401
X1411971Y0864197
X1410121Y0854584
X1400871Y0864197
X1402721Y0854584
X1404571Y0864197
X1408271Y0864197
X1397171Y0864197
X1387921Y0867401
X1395321Y0867401
X1380521Y0867401
X1382371Y0864197
X1386071Y0864197
X1387921Y0854584
X1389771Y0864197
X1393471Y0864197
X1395321Y0854584
X1380521Y0854584
X1373121Y0867401
X1373121Y0854584
X1374971Y0864197
X1378671Y0864197
X1463771Y0851380
X1467471Y0851380
X1471171Y0851380
X1448971Y0851380
X1456371Y0851380
X1452671Y0851380
X1460071Y0851380
X1447121Y0841467
X1441571Y0851380
X1445271Y0851380
X1439721Y0841467
X1415671Y0851380
X1419370Y0851380
X1423070Y0851380
X1426771Y0851380
X1417520Y0848176
X1421220Y0848176
X1411971Y0851380
X1400871Y0851380
X1404571Y0851380
X1408271Y0851380
X1397171Y0851380
X1382371Y0851380
X1386071Y0851380
X1389771Y0851380
X1393471Y0851380
X1374971Y0851380
X1378671Y0851380
X1373121Y0841467
X1387921Y0841467
X1395321Y0841467
X1380521Y0841467
X1402721Y0841467
X1408269Y0844971
X1415669Y0844971
X1428620Y0848176
X1432321Y0841467
X1430470Y0851380
X1434171Y0851380
X1437871Y0851380
X1432321Y0854584
X1439721Y0854584
X1454521Y0841467
X1461921Y0841467
X1469321Y0841467
X1473020Y0854584
X1478571Y0857789
X1480420Y0854584
X1485971Y0857789
X1487820Y0854584
X1493371Y0857789
X1495220Y0854584
X1500771Y0857789
X1502620Y0854584
X1474871Y0857789
X1476720Y0860993
X1482271Y0857789
X1484120Y0860993
X1489671Y0857789
X1491520Y0860993
X1497071Y0857789
X1498920Y0860993
X1504471Y0857789
X1473020Y0873810
X1473020Y0860993
X1473020Y0848176
X1502621Y0873810
X1495220Y0873810
X1502621Y0860993
X1495220Y0860993
X1495220Y0848176
X1480420Y0873810
X1487820Y0873810
X1480420Y0860993
X1487820Y0860993
X1480420Y0848176
X1487820Y0848176
X1478571Y0883423
X1500771Y0883423
X1493371Y0883423
X1485971Y0883423
X1482271Y0883423
X1480420Y0880219
X1474871Y0883423
X1473020Y0880219
X1504471Y0883423
X1502621Y0880219
X1497071Y0883423
X1495220Y0880219
X1489671Y0883423
X1487820Y0880219
X1484120Y0873810
X1482271Y0870606
X1476720Y0873810
X1474871Y0870606
X1506321Y0873810
X1504471Y0870606
X1498920Y0873810
X1497071Y0870606
X1491520Y0873810
X1489671Y0870606
X1485971Y0870606
X1480420Y0867401
X1478571Y0870606
X1473020Y0867401
X1508171Y0870606
X1502621Y0867401
X1500771Y0870606
X1495220Y0867401
X1493371Y0870606
X1487820Y0867401
X1517421Y0854584
X1517421Y0860993
X1515571Y0857789
X1519271Y0857789
X1515571Y0851380
X1519271Y0851380
X1510021Y0854584
X1511871Y0857789
X1522970Y0864197
X1519270Y0864197
X1508171Y0864197
X1511871Y0864197
X1519271Y0877014
X1511871Y0877014
X1522970Y0877014
X1515570Y0877014
X1519271Y0870606
X1521121Y0873810
X1515571Y0870606
X1513720Y0873810
X1521121Y0880219
X1519271Y0883423
X1513720Y0880219
X1515571Y0883423
X1522971Y0883423
X1517421Y0880219
X1511871Y0883423
X1517421Y0873810
X1522971Y0870606
X1511871Y0870606
X1508170Y0883423
X1510021Y0873810
X1510021Y0880219
X1500771Y0877014
X1506321Y0880219
X1497071Y0877014
X1508171Y0877014
X1498921Y0880219
X1504471Y0877014
X1493371Y0877014
X1482271Y0877014
X1489671Y0877014
X1484121Y0880219
X1485971Y0877014
X1491521Y0880219
X1478571Y0877014
X1474871Y0877014
X1476721Y0880219
X1513721Y0867401
X1517421Y0867401
X1521121Y0867401
X1513721Y0860993
X1513721Y0854584
X1515570Y0864197
X1521121Y0854584
X1521121Y0860993
X1510021Y0867401
X1498921Y0867401
X1506320Y0867401
X1510021Y0860993
X1498921Y0854584
X1506321Y0854584
X1506321Y0860993
X1497071Y0864197
X1508170Y0857789
X1500771Y0864197
X1504471Y0864197
X1484121Y0854584
X1484121Y0867401
X1491521Y0867401
X1493371Y0864197
X1482271Y0864197
X1485971Y0864197
X1489671Y0864197
X1491521Y0854584
X1478571Y0864197
X1476721Y0867401
X1476721Y0854584
X1474871Y0864197
X1511871Y0851380
X1513722Y0848176
X1511871Y0844671
X1497071Y0851380
X1500771Y0851380
X1504471Y0851380
X1508171Y0851380
X1498921Y0841467
X1504471Y0844671
X1493371Y0851380
X1485971Y0851380
X1489671Y0851380
X1482271Y0851380
X1478571Y0851380
X1484121Y0841467
X1491521Y0841467
X1474871Y0851380
X1476721Y0841467
X1473020Y0886627
X1510021Y0886627
X1502621Y0886627
X1495220Y0886627
X1487820Y0886627
X1480420Y0886627
X1484120Y0886627
X1476720Y0886627
X1506321Y0886627
X1498920Y0886627
X1491520Y0886627
X1506320Y0893036
X1484120Y0963530
X1480420Y0905853
X1473020Y0905853
X1484120Y0905853
X1476720Y0905853
X1473020Y0893036
X1480420Y0899445
X1482271Y0902649
X1476720Y0899445
X1474871Y0902649
X1482271Y0909057
X1480420Y0912262
X1474871Y0909057
X1476720Y0912262
X1482271Y0960326
X1474871Y0960326
X1480420Y0957122
X1476720Y0957122
X1473020Y0963530
X1482271Y0966735
X1474871Y0966735
X1480420Y0969939
X1476720Y0969939
X1497071Y0973143
X1485971Y0953917
X1493371Y0915466
X1484120Y0925079
X1480420Y0944304
X1493371Y0953917
X1485971Y0915466
X1476720Y0925079
X1476720Y0944304
X1489671Y0953917
X1497071Y0915466
X1480420Y0925079
X1484120Y0944304
X1497071Y0953917
X1489671Y0915466
X1473020Y0925079
X1473020Y0944304
X1474871Y0928283
X1480420Y0931488
X1480420Y0937896
X1482271Y0941100
X1476720Y0937896
X1474871Y0941100
X1482271Y0947509
X1480420Y0950713
X1493371Y0909057
X1495220Y0912262
X1489671Y0909057
X1487820Y0912262
X1474871Y0947509
X1495220Y0918670
X1493371Y0921875
X1487820Y0918670
X1489671Y0921875
X1480420Y0918670
X1482271Y0921875
X1476720Y0918670
X1474871Y0921875
X1482271Y0928283
X1476720Y0931488
X1476720Y0950713
X1489671Y0966735
X1487820Y0969939
X1493371Y0966735
X1495220Y0969939
X1495220Y0957122
X1493371Y0960326
X1487820Y0957122
X1489671Y0960326
X1493371Y0947509
X1495220Y0950713
X1489671Y0947509
X1487820Y0950713
X1485971Y0973143
X1495220Y0976347
X1487820Y0976347
X1493371Y0979552
X1489671Y0979552
X1482271Y0979552
X1480420Y0976347
X1476720Y0976347
X1474871Y0979552
X1473020Y0982756
X1480420Y0982756
X1476720Y0982756
X1484120Y0982756
X1510021Y0963530
X1498920Y0944304
X1497071Y0896240
X1506321Y0905853
X1493371Y0934691
X1506320Y0944304
X1489671Y0896240
X1498920Y0905853
X1485971Y0934691
X1502621Y0944304
X1493371Y0896240
X1510021Y0905853
X1497071Y0934691
X1510021Y0944304
X1485971Y0896240
X1502621Y0905853
X1489671Y0934691
X1500771Y0909057
X1502621Y0912262
X1493371Y0928283
X1495220Y0931488
X1489671Y0928283
X1487820Y0931488
X1495220Y0937896
X1484120Y0893036
X1498920Y0893036
X1493371Y0941100
X1487820Y0893036
X1495220Y0893036
X1495220Y0899445
X1493371Y0902649
X1487820Y0899445
X1489671Y0902649
X1487820Y0937896
X1506320Y0899445
X1508171Y0902649
X1502621Y0899445
X1500771Y0902649
X1508171Y0909057
X1506321Y0912262
X1489671Y0941100
X1502621Y0957122
X1500771Y0960326
X1506320Y0957122
X1508171Y0960326
X1508171Y0947509
X1506320Y0950713
X1500771Y0947509
X1502621Y0950713
X1506321Y0937896
X1508171Y0941100
X1502621Y0937896
X1500771Y0941100
X1498920Y0963530
X1508171Y0966735
X1500771Y0966735
X1506321Y0969939
X1502621Y0969939
X1506321Y0925079
X1498920Y0925079
X1510021Y0925079
X1502621Y0925079
X1506321Y0918670
X1508171Y0921875
X1502621Y0918670
X1500771Y0921875
X1508171Y0928283
X1506321Y0931488
X1500771Y0928283
X1502621Y0931488
X1526843Y0972608
X1527571Y0979057
X1515571Y0973143
X1517421Y0969939
X1511871Y0973143
X1513721Y0982756
X1515571Y0979552
X1508171Y0973143
X1510021Y0969939
X1510043Y0980606
X1495221Y0982756
X1510021Y0976347
X1497071Y0979552
X1500770Y0973143
X1498920Y0969939
X1498921Y0976347
X1504471Y0973143
X1504471Y0979552
X1487820Y0982756
X1491520Y0982756
X1493370Y0973143
X1482271Y0973143
X1485970Y0979552
X1489671Y0973143
X1484121Y0969939
X1484120Y0976347
X1491520Y0969939
X1491521Y0976347
X1478571Y0973143
X1478571Y0979552
X1474870Y0973143
X1473020Y0969939
X1473021Y0976347
X1513721Y0963530
X1524288Y0965640
X1511871Y0966735
X1513721Y0950713
X1513721Y0957122
X1511871Y0960326
X1525861Y0962436
X1504471Y0966735
X1506320Y0963530
X1510021Y0950713
X1508171Y0953917
X1510021Y0957122
X1502621Y0963530
X1497070Y0966735
X1495221Y0963530
X1498920Y0950713
X1497071Y0960326
X1498921Y0957122
X1500771Y0953917
X1504471Y0953917
X1504471Y0960326
X1480420Y0963530
X1487820Y0963530
X1485971Y0966735
X1491520Y0963530
X1478570Y0966735
X1484121Y0950713
X1482271Y0953917
X1484120Y0957122
X1485970Y0960326
X1491520Y0950713
X1491520Y0957122
X1478571Y0953917
X1478571Y0960326
X1476721Y0963530
X1473020Y0950713
X1473021Y0957122
X1474871Y0953917
X1515571Y0947509
X1519271Y0947509
X1525420Y0949619
X1511871Y0947509
X1513720Y0944304
X1524820Y0944304
X1513721Y0937896
X1511871Y0941100
X1504471Y0947509
X1510021Y0937896
X1508171Y0934691
X1497070Y0947509
X1497071Y0941100
X1498921Y0937896
X1500770Y0934691
X1504471Y0934691
X1504471Y0941100
X1495221Y0944304
X1485971Y0947509
X1478571Y0947509
X1482271Y0934691
X1484120Y0937896
X1485970Y0941100
X1487820Y0944304
X1491520Y0937896
X1491520Y0944304
X1478571Y0934691
X1478571Y0941100
X1473021Y0937896
X1474871Y0934691
X1513720Y0931488
X1524820Y0931488
X1513720Y0925079
X1524820Y0925079
X1513721Y0918670
X1515571Y0928283
X1519271Y0928283
X1511871Y0921875
X1511871Y0928283
X1510020Y0931488
X1510021Y0918670
X1504471Y0928283
X1498920Y0931488
X1497071Y0921875
X1498921Y0918670
X1497070Y0928283
X1504471Y0921875
X1495221Y0925079
X1484121Y0931488
X1491520Y0931488
X1484120Y0918670
X1485970Y0921875
X1485971Y0928283
X1487820Y0925079
X1491520Y0918670
X1491520Y0925079
X1478571Y0921875
X1478571Y0928283
X1473020Y0931488
X1473021Y0918670
X1519271Y0909057
X1513721Y0905853
X1524821Y0905853
X1515571Y0909057
X1513721Y0912262
X1511871Y0902649
X1511871Y0909057
X1524821Y0912262
X1510021Y0912262
X1504471Y0909057
X1500770Y0915466
X1504471Y0915466
X1508171Y0915466
X1497071Y0902649
X1497070Y0909057
X1498920Y0912262
X1504471Y0902649
X1495221Y0905853
X1482271Y0915466
X1478571Y0915466
X1485970Y0902649
X1491520Y0905853
X1484121Y0912262
X1485971Y0909057
X1487820Y0905853
X1491520Y0912262
X1478571Y0902649
X1478571Y0909057
X1474870Y0915466
X1473020Y0912262
X1513721Y0899445
X1526671Y0889832
X1513721Y0886627
X1521121Y0886627
X1517421Y0886627
X1513721Y0893036
X1511871Y0889832
X1510021Y0899445
X1498921Y0899445
X1510021Y0893036
X1497071Y0889832
X1500771Y0896240
X1502621Y0893036
X1508171Y0896240
X1500771Y0889832
X1504471Y0889832
X1504471Y0896240
X1508171Y0889832
X1484120Y0899445
X1491520Y0899445
X1493371Y0889832
X1480421Y0893036
X1482270Y0896240
X1485971Y0889832
X1489671Y0889832
X1482271Y0889832
X1491521Y0893036
X1478571Y0889832
X1478570Y0896240
X1473021Y0899445
X1474871Y0896240
X1476721Y0893036
X1474871Y0889832
X1501204Y0999684
X1503053Y1002888
X1508603Y0999684
X1506753Y1002888
X1490104Y0999684
X1488253Y1002888
X1493803Y0999684
X1495655Y1002888
X1480853Y1034931
X1480853Y1054157
X1493804Y1044544
X1480853Y1073383
X1493804Y1082995
X1473453Y1034931
X1473453Y1054157
X1490104Y1044544
X1477153Y1073383
X1486404Y1082995
X1484553Y1034931
X1484553Y1054157
X1497504Y1044544
X1484553Y1073383
X1497504Y1082995
X1477153Y1034931
X1477153Y1054157
X1486404Y1044544
X1473453Y1073383
X1490104Y1082995
X1475304Y1076587
X1477153Y1079791
X1493804Y1076587
X1495653Y1079791
X1490104Y1076587
X1488253Y1079791
X1480853Y1047749
X1482704Y1050952
X1477153Y1047749
X1475304Y1050952
X1482704Y1057361
X1480853Y1060565
X1475304Y1057361
X1477153Y1060565
X1493804Y1038136
X1495653Y1041340
X1490104Y1038136
X1488253Y1041340
X1495653Y1047749
X1493804Y1050952
X1488253Y1047749
X1490104Y1050952
X1480853Y1066974
X1482704Y1070178
X1477153Y1066974
X1475304Y1070178
X1482704Y1076587
X1480853Y1079791
X1475304Y1018910
X1477153Y1022114
X1482704Y1018910
X1480853Y1022114
X1480853Y1028523
X1482704Y1031727
X1477153Y1028523
X1475304Y1031727
X1482704Y1038136
X1480853Y1041340
X1475304Y1038136
X1477153Y1041340
X1480853Y1009297
X1477153Y1009297
X1482704Y1012501
X1475304Y1012501
X1484553Y1015705
X1473453Y1015705
X1475304Y0999684
X1477153Y1002888
X1488253Y1009297
X1490104Y1012501
X1482703Y0999684
X1480853Y1002888
X1495653Y1009297
X1506753Y1034931
X1493804Y1025318
X1506753Y1054157
X1493804Y1063770
X1499353Y1034931
X1486404Y1025318
X1503053Y1054157
X1490104Y1063770
X1510453Y1034931
X1497504Y1025318
X1510453Y1054157
X1497504Y1063770
X1503053Y1034931
X1490104Y1025318
X1499353Y1054157
X1486404Y1063770
X1488253Y1066974
X1490104Y1070178
X1493804Y1018910
X1495653Y1022114
X1490104Y1018910
X1488253Y1022114
X1495653Y1028523
X1493804Y1031727
X1488253Y1028523
X1490104Y1031727
X1506753Y1047749
X1508604Y1050953
X1503053Y1047749
X1501203Y1050952
X1508604Y1057361
X1506753Y1060565
X1501204Y1057361
X1503053Y1060565
X1493804Y1057361
X1495653Y1060565
X1490104Y1057361
X1488253Y1060565
X1495653Y1066974
X1493804Y1070178
X1501204Y1018910
X1503053Y1022114
X1508603Y1018910
X1506753Y1022114
X1506753Y1028523
X1508603Y1031727
X1503053Y1028523
X1501204Y1031727
X1508603Y1038136
X1506753Y1041340
X1501204Y1038136
X1503053Y1041340
X1493804Y1012501
X1506753Y1009297
X1503053Y1009297
X1508603Y1012501
X1501204Y1012501
X1510453Y1015705
X1499353Y1015705
X1486404Y1006093
X1497504Y1006093
X1490104Y1006093
X1493804Y1006093
X1479004Y1006093
X1506753Y1073383
X1503053Y1073383
X1510453Y1073383
X1499353Y1073383
X1501204Y1076587
X1503053Y1079791
X1506753Y1066974
X1508604Y1070178
X1503053Y1066974
X1501204Y1070178
X1508604Y1076587
X1506753Y1079791
X1512304Y1082996
X1523404Y1082996
X1508604Y1082996
X1501203Y1082995
X1504904Y1082995
X1482704Y1082995
X1479004Y1082995
X1475303Y1082995
X1514153Y1073383
X1512304Y1070178
X1512303Y1076587
X1516003Y1076587
X1521553Y1066974
X1517853Y1073383
X1514153Y1066974
X1523404Y1070178
X1525564Y1064850
X1510453Y1079791
X1510453Y1066974
X1499354Y1079791
X1499353Y1066974
X1495654Y1073383
X1497503Y1070178
X1497504Y1076587
X1504904Y1070178
X1504904Y1076587
X1491953Y1079791
X1484553Y1079791
X1491953Y1066974
X1491953Y1073383
X1484553Y1066974
X1488253Y1073383
X1486404Y1070178
X1486404Y1076587
X1479004Y1070178
X1479004Y1076587
X1473454Y1079791
X1473453Y1066974
X1512303Y1050952
X1514153Y1060565
X1521553Y1054157
X1512303Y1057361
X1514153Y1054157
X1517853Y1054157
X1508604Y1063770
X1510453Y1060565
X1501203Y1063770
X1504904Y1063770
X1495654Y1054157
X1497503Y1050952
X1497504Y1057361
X1499354Y1060565
X1504904Y1050952
X1504904Y1057361
X1482704Y1063770
X1479004Y1063770
X1491953Y1060565
X1486404Y1050952
X1488253Y1054157
X1484553Y1060565
X1486404Y1057361
X1491953Y1054157
X1479004Y1050952
X1479004Y1057361
X1475304Y1063770
X1473453Y1060565
X1512303Y1038136
X1514153Y1034931
X1517853Y1034931
X1516003Y1038136
X1516004Y1044544
X1521554Y1034931
X1525254Y1034931
X1510453Y1047749
X1510453Y1041340
X1504904Y1038136
X1499353Y1047749
X1508604Y1044544
X1495654Y1034931
X1497504Y1038136
X1499354Y1041340
X1501203Y1044544
X1504904Y1044544
X1484553Y1047749
X1491953Y1047749
X1482704Y1044544
X1484553Y1041340
X1486403Y1038136
X1488253Y1034931
X1491953Y1041340
X1491953Y1034931
X1479004Y1038136
X1479004Y1044544
X1473453Y1047749
X1475303Y1044544
X1473454Y1041340
X1527103Y1031726
X1512303Y1031727
X1512303Y1018910
X1514154Y1015705
X1521554Y1015705
X1525254Y1015705
X1517854Y1015705
X1516003Y1018910
X1512303Y1025318
X1508603Y1025318
X1510452Y1022114
X1510453Y1028523
X1506753Y1015705
X1504904Y1018910
X1503054Y1015705
X1499353Y1022114
X1497504Y1018910
X1495654Y1015705
X1497503Y1031727
X1504904Y1031727
X1501203Y1025318
X1499353Y1028523
X1504904Y1025318
X1491953Y1015705
X1488253Y1015705
X1486404Y1031727
X1479004Y1031727
X1480853Y1015705
X1482704Y1025318
X1484553Y1022114
X1486403Y1018910
X1484553Y1028523
X1491953Y1022114
X1491953Y1028523
X1479004Y1018910
X1479004Y1025318
X1473453Y1022114
X1475303Y1025318
X1477154Y1015705
X1473453Y1028523
X1512303Y1012501
X1525396Y1000648
X1519705Y1006092
X1512303Y1006093
X1512303Y0999684
X1516003Y0999684
X1516004Y1006092
X1504903Y1012501
X1508603Y1006093
X1510453Y1002888
X1510453Y1009297
X1499354Y1002888
X1499353Y1009297
X1501203Y1006093
X1504904Y0999684
X1504904Y1006093
X1497503Y0999684
X1497503Y1012501
X1484554Y1009297
X1491953Y1002888
X1491953Y1009297
X1486404Y1012501
X1479003Y1012501
X1482704Y1006093
X1484553Y1002888
X1486403Y0999684
X1479004Y0999684
X1473454Y1002888
X1473453Y1009297
X1475303Y1006093
X1519871Y0984866
X1482703Y1115038
X1484554Y1105426
X1488254Y1111833
X1486403Y1108630
X1514154Y1131059
X1508603Y1127855
X1519703Y1127855
X1517853Y1124650
X1480854Y1105426
X1477154Y1111833
X1516003Y1121446
X1512303Y1121446
X1480854Y1111833
X1482703Y1102220
X1484554Y1111833
X1488254Y1105426
X1512303Y1127855
X1510453Y1124650
X1516003Y1127855
X1519703Y1121446
X1477154Y1105426
X1479003Y1108629
X1508603Y1121446
X1504903Y1140973
X1508603Y1140973
X1517853Y1118243
X1501204Y1134264
X1501204Y1121447
X1510453Y1118243
X1503053Y1118243
X1499354Y1099017
X1501204Y1102221
X1504904Y1102221
X1506753Y1105426
X1486404Y1134264
X1493804Y1134264
X1479004Y1134264
X1486404Y1121447
X1493804Y1121447
X1479004Y1121447
X1479004Y1115039
X1486404Y1102221
X1473453Y1124651
X1477153Y1124651
X1480853Y1124651
X1484553Y1124651
X1488253Y1124651
X1491953Y1124651
X1495653Y1124651
X1499353Y1124651
X1501204Y1127856
X1475304Y1121447
X1479004Y1127856
X1482704Y1121447
X1486404Y1127856
X1490104Y1121447
X1493804Y1127856
X1497504Y1121447
X1503053Y1124651
X1473454Y1137469
X1475304Y1134264
X1479003Y1140973
X1484554Y1137469
X1486403Y1140973
X1491954Y1137469
X1495654Y1137469
X1497504Y1134264
X1503054Y1137469
X1510454Y1137469
X1477154Y1137469
X1480854Y1137469
X1482704Y1134264
X1488254Y1137469
X1490104Y1134264
X1493803Y1140973
X1499354Y1137469
X1501203Y1140973
X1508604Y1134264
X1480853Y1092608
X1477153Y1092608
X1484553Y1092608
X1473453Y1092608
X1480853Y1086200
X1482704Y1089404
X1477153Y1086200
X1475304Y1089404
X1482703Y1095813
X1491953Y1099017
X1486404Y1095813
X1493804Y1102221
X1495653Y1086200
X1493804Y1089404
X1488253Y1086200
X1490104Y1089404
X1506753Y1092608
X1499353Y1092608
X1510452Y1092608
X1503053Y1092608
X1506753Y1086200
X1508604Y1089404
X1503053Y1086200
X1501204Y1089404
X1506753Y1099017
X1501204Y1095813
X1508603Y1095813
X1497504Y1095813
X1512304Y1134264
X1517854Y1131560
X1510453Y1131060
X1497503Y1140973
X1504904Y1134264
X1495653Y1131060
X1499353Y1131060
X1503053Y1131060
X1506753Y1131060
X1506754Y1137469
X1491953Y1131060
X1482703Y1140973
X1480853Y1131060
X1484553Y1131060
X1488253Y1131060
X1490103Y1140973
X1473453Y1131060
X1475303Y1140973
X1477153Y1131060
X1512303Y1115039
X1514153Y1124651
X1516004Y1115039
X1519704Y1115039
X1521553Y1118243
X1521553Y1124651
X1504904Y1115039
X1501204Y1115039
X1497503Y1127856
X1504904Y1127856
X1508603Y1115039
X1495653Y1118243
X1497503Y1115039
X1499353Y1118243
X1504904Y1121447
X1506753Y1118243
X1506753Y1124651
X1493804Y1115039
X1482703Y1127856
X1490103Y1127856
X1491953Y1118243
X1486403Y1115039
X1480853Y1118243
X1484553Y1118243
X1488253Y1118243
X1490103Y1115039
X1475303Y1127856
X1473453Y1118243
X1475303Y1115039
X1477153Y1118243
X1519703Y1108630
X1514153Y1111834
X1512303Y1108630
X1514153Y1105426
X1521553Y1111834
X1517853Y1111834
X1512303Y1102221
X1516003Y1102221
X1516003Y1108630
X1517853Y1105426
X1521554Y1105426
X1503053Y1111834
X1495653Y1111834
X1504904Y1108630
X1510453Y1105426
X1499353Y1105426
X1510453Y1111834
X1501204Y1108630
X1497504Y1108630
X1508602Y1102221
X1510453Y1099017
X1503053Y1099017
X1499353Y1111834
X1506754Y1111834
X1508603Y1108630
X1495654Y1099017
X1495653Y1105426
X1497503Y1102221
X1503053Y1105426
X1493804Y1108630
X1491953Y1111834
X1491953Y1105426
X1480853Y1099017
X1482704Y1108630
X1484553Y1099017
X1488254Y1099017
X1490104Y1102221
X1490104Y1108630
X1479004Y1102221
X1473453Y1099017
X1477153Y1099017
X1473454Y1111834
X1473454Y1105426
X1475303Y1102221
X1475303Y1108630
X1512303Y1095813
X1519703Y1095813
X1523403Y1095813
X1521553Y1092608
X1512303Y1089404
X1514153Y1092608
X1504903Y1095813
X1510453Y1086200
X1504904Y1089404
X1495653Y1092608
X1497503Y1089404
X1499353Y1086200
X1493804Y1095813
X1490103Y1095813
X1479004Y1095813
X1491953Y1086200
X1491954Y1092608
X1484554Y1086200
X1486404Y1089404
X1488254Y1092608
X1479004Y1089404
X1475304Y1095813
X1473453Y1086200
X1564375Y1578182
X1568635Y1578182
X1552315Y1578182
X1544515Y1578182
X1556575Y1578182
X1528195Y1578182
X1532455Y1578182
X1540255Y1578182
X1516135Y1578182
X1520395Y1578182
X1504075Y1578182
X1496275Y1578182
X1508335Y1578182
X1479955Y1578182
X1484215Y1578182
X1492015Y1578182
X1472155Y1578182
X1560433Y1679320
X1544685Y1679320
X1552559Y1679920
X1552559Y1675383
X1528937Y1679320
X1536811Y1679920
X1536811Y1675383
X1513189Y1679320
X1521063Y1679920
X1521063Y1675383
X1505315Y1679920
X1505315Y1675383
X1561875Y1602380
X1561875Y1614292
X1569675Y1602380
X1569675Y1614292
X1545555Y1614292
X1545555Y1602380
X1557615Y1614292
X1557615Y1602380
X1549815Y1602380
X1549815Y1614292
X1533495Y1614292
X1533495Y1602380
X1537755Y1602380
X1537755Y1614292
X1513635Y1602380
X1513635Y1614292
X1521435Y1614292
X1521435Y1602380
X1525695Y1602380
X1525695Y1614292
X1497315Y1614292
X1497315Y1602380
X1509375Y1614292
X1509375Y1602380
X1501575Y1602380
X1501575Y1614292
X1485255Y1614292
X1485255Y1602380
X1489515Y1602380
X1489515Y1614292
X1473195Y1602380
X1473195Y1614292
X1477455Y1614292
X1477455Y1602380
X1564375Y1590094
X1568635Y1590094
X1552315Y1590094
X1544515Y1590094
X1556575Y1590094
X1528195Y1590094
X1532455Y1590094
X1540255Y1590094
X1516135Y1590094
X1520395Y1590094
X1504075Y1590094
X1496275Y1590094
X1508335Y1590094
X1479955Y1590094
X1484215Y1590094
X1492015Y1590094
X1472155Y1590094
X1560433Y1716737
X1560433Y1721840
X1560433Y1726377
X1560433Y1730911
X1544685Y1716737
X1544685Y1721840
X1544685Y1726377
X1544685Y1730911
X1552559Y1717903
X1552559Y1722440
X1552559Y1726974
X1528937Y1716737
X1528937Y1721840
X1528937Y1726377
X1528937Y1730911
X1536811Y1717903
X1536811Y1722440
X1536811Y1726974
X1513189Y1716737
X1513189Y1721840
X1513189Y1726377
X1513189Y1730911
X1521063Y1717903
X1521063Y1722440
X1521063Y1726974
X1505315Y1717903
X1505315Y1722440
X1505315Y1726974
X1560433Y1702564
X1560433Y1712203
X1560433Y1707666
X1544685Y1702564
X1544685Y1712203
X1544685Y1707666
X1552559Y1712800
X1552559Y1708266
X1552559Y1703729
X1528937Y1702564
X1528937Y1712203
X1528937Y1707666
X1536811Y1712800
X1536811Y1708266
X1536811Y1703729
X1513189Y1702564
X1513189Y1712203
X1513189Y1707666
X1521063Y1712800
X1521063Y1708266
X1521063Y1703729
X1505315Y1712800
X1505315Y1708266
X1505315Y1703729
X1560433Y1683857
X1560433Y1698030
X1560433Y1693493
X1560433Y1688391
X1544685Y1683857
X1544685Y1698030
X1544685Y1693493
X1544685Y1688391
X1552559Y1698627
X1552559Y1694093
X1552559Y1689556
X1552559Y1684454
X1528937Y1683857
X1528937Y1698030
X1528937Y1693493
X1528937Y1688391
X1536811Y1698627
X1536811Y1694093
X1536811Y1689556
X1536811Y1684454
X1513189Y1683857
X1513189Y1698030
X1513189Y1693493
X1513189Y1688391
X1521063Y1698627
X1521063Y1694093
X1521063Y1689556
X1521063Y1684454
X1505315Y1698627
X1505315Y1694093
X1505315Y1689556
X1505315Y1684454
X1627362Y1716737
X1627362Y1721840
X1627362Y1726377
X1627362Y1730911
X1611614Y1716737
X1611614Y1721840
X1611614Y1726377
X1611614Y1730911
X1619488Y1717903
X1619488Y1722440
X1619488Y1726974
X1595866Y1716737
X1595866Y1721840
X1595866Y1726377
X1595866Y1730911
X1603740Y1717903
X1603740Y1722440
X1603740Y1726974
X1580118Y1716737
X1580118Y1721840
X1580118Y1726377
X1580118Y1730911
X1587992Y1717903
X1587992Y1722440
X1587992Y1726974
X1572244Y1717903
X1572244Y1722440
X1572244Y1726974
X1627362Y1702564
X1627362Y1712203
X1627362Y1707666
X1611614Y1702564
X1611614Y1712203
X1611614Y1707666
X1619488Y1712800
X1619488Y1708266
X1619488Y1703729
X1595866Y1702564
X1595866Y1712203
X1595866Y1707666
X1603740Y1712800
X1603740Y1708266
X1603740Y1703729
X1580118Y1702564
X1580118Y1712203
X1580118Y1707666
X1587992Y1712800
X1587992Y1708266
X1587992Y1703729
X1572244Y1712800
X1572244Y1708266
X1572244Y1703729
X1627362Y1683857
X1627362Y1698030
X1627362Y1693493
X1627362Y1688391
X1611614Y1683857
X1611614Y1698030
X1611614Y1693493
X1611614Y1688391
X1619488Y1698627
X1619488Y1694093
X1619488Y1689556
X1619488Y1684454
X1595866Y1683857
X1595866Y1698030
X1595866Y1693493
X1595866Y1688391
X1603740Y1698627
X1603740Y1694093
X1603740Y1689556
X1603740Y1684454
X1580118Y1683857
X1580118Y1698030
X1580118Y1693493
X1580118Y1688391
X1587992Y1698627
X1587992Y1694093
X1587992Y1689556
X1587992Y1684454
X1572244Y1698627
X1572244Y1694093
X1572244Y1689556
X1572244Y1684454
X1627362Y1679320
X1611614Y1679320
X1619488Y1679920
X1619488Y1675383
X1595866Y1679320
X1603740Y1679920
X1603740Y1675383
X1580118Y1679320
X1587992Y1679920
X1587992Y1675383
X1572244Y1679920
X1572244Y1675383
X1642035Y1602286
X1642035Y1614292
X1654095Y1602380
X1654095Y1614292
X1646295Y1602380
X1646295Y1614292
X1629975Y1602380
X1629975Y1614292
X1634235Y1602380
X1634235Y1614292
X1610115Y1602380
X1610115Y1614292
X1617915Y1602380
X1617915Y1614292
X1622175Y1602380
X1622175Y1614292
X1593795Y1602380
X1593795Y1614292
X1605855Y1602380
X1605855Y1614292
X1598055Y1602380
X1598055Y1614292
X1581735Y1614292
X1581735Y1602380
X1585995Y1602380
X1585995Y1614292
X1573935Y1602380
X1573935Y1614292
X1648795Y1590094
X1640995Y1590094
X1624675Y1590094
X1628935Y1590094
X1636735Y1590094
X1612615Y1590094
X1616875Y1590094
X1600555Y1590094
X1592755Y1590094
X1604815Y1590094
X1576435Y1590094
X1580695Y1590094
X1588495Y1590094
X1648795Y1578182
X1640995Y1578182
X1624675Y1578182
X1628935Y1578182
X1636735Y1578088
X1612615Y1578182
X1616875Y1578182
X1600555Y1578182
X1592755Y1578182
X1604815Y1578182
X1576435Y1578182
X1580695Y1578182
X1588495Y1578182
X1623930Y1252242
X1653140Y1257862
X1609056Y1250602
X1654600Y1262742
X1613027Y1248805
X1613183Y1252034
X1608000Y1261662
X1651679Y1248885
X1642883Y1252034
X1624600Y1262074
X1621983Y1258727
X1642883Y1258727
X1611475Y1259227
X1642883Y1255381
X1656170Y1260352
X1626741Y1258727
X1606481Y1258649
X1642883Y1262074
X1642788Y1264464
X1656188Y1264964
X1613019Y1261235
X1607897Y1264445
X1656441Y1195144
X1656441Y1231955
X1656441Y1191798
X1656441Y1228609
X1656441Y1201837
X1656441Y1208530
X1656441Y1215223
X1656441Y1221916
X1656441Y1238648
X1656441Y1185105
X1656441Y1245341
X1613083Y1188451
X1596941Y1195144
X1613083Y1191798
X1596941Y1191798
X1596941Y1201837
X1596941Y1208530
X1596941Y1185105
X1613083Y1198491
X1613083Y1205184
X1601388Y1273144
X1603788Y1273144
X1662288Y1273344
X1659488Y1273344
X1665688Y1257964
X1665141Y1248688
X1665141Y1241995
X1665141Y1235302
X1665141Y1218570
X1665941Y1225263
X1665141Y1211877
X1665141Y1205184
X1665141Y1198491
X1665141Y1188452
X1645788Y1273344
X1648588Y1273344
X1642883Y1245341
X1651583Y1245341
X1656441Y1248688
X1642883Y1238648
X1651583Y1238648
X1642054Y1231955
X1652604Y1231955
X1656441Y1241995
X1656441Y1235302
X1642883Y1215223
X1651583Y1215223
X1656441Y1218570
X1656441Y1225263
X1641793Y1221916
X1652590Y1221916
X1656441Y1211877
X1651583Y1208530
X1642883Y1208530
X1651583Y1201837
X1642883Y1201837
X1651583Y1195144
X1642883Y1195144
X1656441Y1205184
X1656441Y1198491
X1642883Y1185105
X1651583Y1185105
X1656441Y1188452
X1625729Y1266766
X1632588Y1273344
X1629788Y1273344
X1635441Y1248688
X1626741Y1248688
X1635688Y1257664
X1626741Y1241995
X1635441Y1241995
X1625843Y1235302
X1636376Y1235302
X1626055Y1225263
X1636212Y1225263
X1626741Y1218570
X1635441Y1218570
X1626741Y1211877
X1635441Y1211877
X1635441Y1205184
X1626741Y1205184
X1635441Y1198491
X1626741Y1198491
X1635441Y1188452
X1626741Y1188452
X1616088Y1273344
X1618888Y1273344
X1613183Y1245341
X1621883Y1245341
X1610150Y1257172
X1613183Y1238648
X1621883Y1238648
X1622681Y1231955
X1612137Y1231862
X1622712Y1221916
X1612147Y1221916
X1613183Y1215223
X1621883Y1215223
X1613183Y1208530
X1621883Y1208530
X1613183Y1201837
X1621883Y1201837
X1621883Y1195144
X1613183Y1195144
X1613183Y1185105
X1621883Y1185105
X1605741Y1248688
X1597041Y1248688
X1597041Y1241995
X1605741Y1241995
X1596178Y1235302
X1607064Y1235302
X1605741Y1225263
X1597041Y1225263
X1605741Y1218570
X1597041Y1218570
X1605741Y1211877
X1597041Y1211877
X1597041Y1205184
X1605741Y1205184
X1605741Y1198491
X1597041Y1198491
X1597041Y1188452
X1606765Y1188452
X1656441Y1084711
X1656441Y1121522
X1656441Y1158333
X1656441Y1118176
X1656441Y1154987
X1656441Y1104790
X1656441Y1111483
X1656441Y1128215
X1656441Y1134908
X1656441Y1141601
X1656441Y1148294
X1656441Y1165026
X1656441Y1171719
X1656441Y1178412
X1656441Y1091404
X1656441Y1098097
X1613083Y1175066
X1613083Y1181759
X1596941Y1178412
X1665141Y1181759
X1665141Y1175066
X1665141Y1168373
X1665141Y1161680
X1666141Y1151641
X1665141Y1144948
X1665141Y1138255
X1665141Y1131562
X1665141Y1124869
X1665141Y1114829
X1665141Y1108137
X1665141Y1101444
X1665141Y1094751
X1665141Y1088058
X1642883Y1178412
X1651583Y1178412
X1656441Y1181759
X1642883Y1165026
X1651583Y1165026
X1651583Y1171719
X1642883Y1171719
X1656441Y1175066
X1656441Y1168373
X1641744Y1148294
X1652794Y1148294
X1642083Y1158333
X1652383Y1158333
X1656441Y1161680
X1656441Y1151641
X1656441Y1144948
X1651583Y1141601
X1642883Y1141601
X1651583Y1134908
X1642883Y1134908
X1656441Y1138255
X1656441Y1131562
X1651583Y1128215
X1642883Y1128215
X1651583Y1121522
X1642883Y1121522
X1656441Y1124869
X1656441Y1114829
X1651583Y1111483
X1642883Y1111483
X1651583Y1104790
X1642883Y1104790
X1651583Y1098097
X1642883Y1098097
X1656441Y1108137
X1656441Y1101444
X1642883Y1091404
X1651583Y1091404
X1642083Y1084711
X1652383Y1084711
X1656441Y1094751
X1656441Y1088058
X1635441Y1181759
X1626741Y1181759
X1635441Y1175066
X1626741Y1175066
X1635441Y1168373
X1626741Y1168373
X1626741Y1151641
X1635441Y1151641
X1635441Y1161680
X1626741Y1161680
X1626741Y1130762
X1635441Y1130762
X1626741Y1138255
X1635441Y1138255
X1626741Y1144948
X1635441Y1144948
X1626741Y1114829
X1635441Y1114829
X1636341Y1124869
X1626074Y1124640
X1635441Y1108137
X1626741Y1108137
X1635441Y1101444
X1626741Y1101444
X1626741Y1094751
X1635441Y1094751
X1636241Y1088058
X1625941Y1088058
X1613183Y1178412
X1621883Y1178412
X1621883Y1171719
X1613183Y1171719
X1613183Y1165026
X1621883Y1165026
X1613183Y1148294
X1621883Y1148294
X1613183Y1158333
X1621883Y1158333
X1611886Y1134908
X1622726Y1135108
X1613183Y1141601
X1621883Y1141601
X1621883Y1121522
X1613183Y1121522
X1621883Y1128215
X1613183Y1128915
X1613183Y1111483
X1621883Y1111483
X1613183Y1098097
X1621883Y1098097
X1613183Y1104790
X1621883Y1104790
X1621883Y1091404
X1613183Y1091404
X1612383Y1084711
X1621883Y1084711
X1597041Y1181759
X1605741Y1181759
X1597041Y1175066
X1605741Y1175066
X1597041Y1168373
X1605741Y1168373
X1605975Y1161581
X1596653Y1161680
X1597041Y1151641
X1605741Y1151641
X1605741Y1131562
X1597041Y1131562
X1597041Y1144948
X1605741Y1144948
X1597041Y1138255
X1605741Y1138255
X1606505Y1124674
X1596511Y1124969
X1596241Y1114829
X1606541Y1114829
X1605741Y1108137
X1597041Y1108137
X1597041Y1101444
X1605741Y1101444
X1605741Y1088058
X1597041Y1088058
X1597041Y1094751
X1605741Y1094751
X1620399Y1000325
X1648205Y0998632
X1626249Y1002825
X1623589Y1002865
X1620489Y1003135
X1623539Y1000135
X1616469Y1003135
X1616609Y1000735
X1599489Y0999665
X1601922Y1000198
X1656441Y0987664
X1656441Y0994357
X1656441Y1021129
X1656441Y1081365
X1656141Y1054593
X1656441Y1067979
X1656441Y1074672
X1656141Y1027822
X1656141Y1034514
X1656141Y1041207
X1656141Y1047900
X1656441Y1061286
X1597041Y1061286
X1665141Y1077118
X1665141Y1071326
X1665141Y1064633
X1665141Y1057940
X1665141Y1051247
X1665141Y1037861
X1665141Y1044554
X1665141Y1031168
X1665141Y1024475
X1665141Y1017782
X1665141Y0991011
X1665141Y0984318
X1642883Y1067979
X1651583Y1067979
X1641983Y1074672
X1652483Y1074672
X1656441Y1078018
X1656441Y1071326
X1656441Y1064633
X1642883Y1054593
X1651583Y1054593
X1656441Y1057940
X1656441Y1051247
X1651583Y1061286
X1642883Y1061286
X1642883Y1047900
X1651583Y1047900
X1642883Y1041207
X1651583Y1041207
X1642883Y1034515
X1651583Y1034515
X1656441Y1037861
X1656441Y1044554
X1656441Y1031168
X1642883Y1027822
X1651583Y1027822
X1656441Y1024475
X1656441Y1017782
X1642883Y1017782
X1651583Y1017782
X1642883Y0987664
X1651583Y0987664
X1656441Y0991011
X1656441Y0984318
X1625941Y1078018
X1636241Y1078018
X1626741Y1071326
X1635441Y1071326
X1626741Y1064633
X1635441Y1064633
X1626741Y1051247
X1635441Y1051247
X1635441Y1057940
X1626741Y1057940
X1626741Y1044554
X1635441Y1044554
X1626741Y1037861
X1635441Y1037861
X1626741Y1031168
X1635441Y1031168
X1626741Y1017782
X1635441Y1017782
X1626741Y1024475
X1635441Y1024475
X1635441Y0991011
X1626741Y0991011
X1626741Y0984318
X1635441Y0984318
X1622683Y1074672
X1612283Y1074672
X1612983Y1067979
X1621883Y1067979
X1621883Y1061286
X1613183Y1061286
X1613183Y1054593
X1621883Y1054593
X1621883Y1047900
X1613183Y1047900
X1621883Y1041207
X1613183Y1041207
X1621883Y1034515
X1613183Y1034515
X1621883Y1027822
X1613183Y1027822
X1613183Y1017782
X1621883Y1017782
X1621883Y0987664
X1613183Y0987664
X1605741Y1078018
X1597041Y1078018
X1596141Y1071326
X1606541Y1071326
X1605741Y1064633
X1597041Y1064633
X1605741Y1057940
X1597041Y1057940
X1597041Y1051247
X1605741Y1051247
X1605741Y1044554
X1597041Y1044554
X1605741Y1037861
X1597041Y1037861
X1605741Y1031168
X1597041Y1031168
X1605741Y1017782
X1597041Y1017782
X1605741Y1024475
X1597041Y1024475
X1605741Y0991011
X1597041Y0991011
X1605741Y0984318
X1597041Y0984318
X1613083Y0954200
X1613083Y0957546
X1642783Y0954200
X1642783Y0957546
X1656441Y0957546
X1656441Y0937467
X1656441Y0900656
X1656441Y0934121
X1656441Y0897310
X1656441Y0883924
X1656441Y0890617
X1656441Y0907349
X1656441Y0914042
X1656441Y0967585
X1656441Y0944160
X1656441Y0950853
X1656441Y0920735
X1656441Y0927428
X1656441Y0974278
X1656441Y0980971
X1656441Y0960892
X1596941Y0957546
X1626641Y0957546
X1613083Y0893963
X1596941Y0900656
X1613083Y0897310
X1596941Y0897310
X1613083Y0887270
X1596941Y0883924
X1596941Y0890617
X1613083Y0904003
X1613083Y0910696
X1596941Y0907349
X1596941Y0914042
X1596941Y0960892
X1626641Y0960892
X1665141Y0970932
X1665141Y0977625
X1665141Y0964239
X1665141Y0954200
X1665141Y0947507
X1665141Y0940814
X1666246Y0930774
X1665141Y0924081
X1665141Y0917389
X1665141Y0910696
X1665141Y0904003
X1665141Y0893963
X1665141Y0887270
X1642883Y0980971
X1651583Y0980971
X1642883Y0974278
X1651583Y0974278
X1642883Y0967585
X1651583Y0967585
X1656441Y0970932
X1656441Y0977625
X1656441Y0964239
X1642883Y0960892
X1651583Y0960892
X1651583Y0950853
X1642883Y0950853
X1656441Y0954200
X1642883Y0944160
X1651583Y0944160
X1642065Y0937467
X1652501Y0937467
X1656441Y0947507
X1656441Y0940814
X1642883Y0920735
X1651583Y0920735
X1642038Y0927428
X1652630Y0927428
X1656441Y0930774
X1656441Y0924081
X1642883Y0914042
X1651583Y0914042
X1656441Y0917389
X1651583Y0907349
X1642883Y0907349
X1656441Y0910696
X1656441Y0904003
X1651583Y0900656
X1642883Y0900656
X1651583Y0890617
X1642883Y0890617
X1656441Y0893963
X1656441Y0887270
X1651583Y0883924
X1642883Y0883924
X1626741Y0970932
X1635441Y0970932
X1626741Y0977625
X1635441Y0977625
X1635441Y0964239
X1626741Y0964239
X1626741Y0954200
X1635441Y0954200
X1626741Y0947507
X1635441Y0947507
X1626741Y0940814
X1635441Y0940814
X1626741Y0924081
X1636646Y0924081
X1625803Y0930774
X1636316Y0930774
X1626741Y0917389
X1635441Y0917389
X1626741Y0910696
X1635441Y0910696
X1635441Y0904003
X1626741Y0904003
X1635441Y0893963
X1626741Y0893963
X1635441Y0887270
X1626741Y0887270
X1621883Y0967585
X1613183Y0967585
X1621883Y0980971
X1613183Y0980971
X1621883Y0974278
X1613183Y0974278
X1613183Y0960892
X1621883Y0960892
X1613183Y0950853
X1621883Y0950853
X1613183Y0944160
X1621883Y0944160
X1612312Y0937467
X1622845Y0937467
X1612168Y0927428
X1622535Y0927526
X1613183Y0920735
X1621883Y0920735
X1621883Y0914042
X1613183Y0914042
X1613183Y0907349
X1621883Y0907349
X1621883Y0900656
X1613183Y0900656
X1621883Y0890617
X1613183Y0890617
X1613183Y0883924
X1621883Y0883924
X1597041Y0970932
X1605741Y0970932
X1605741Y0977625
X1597041Y0977625
X1605741Y0964239
X1597041Y0964239
X1597041Y0954200
X1605741Y0954200
X1597041Y0947507
X1605741Y0947507
X1606919Y0940814
X1596106Y0940814
X1596047Y0930774
X1606541Y0930697
X1605741Y0924081
X1597041Y0924081
X1605741Y0910696
X1597041Y0910696
X1605741Y0917389
X1597041Y0917389
X1597041Y0904003
X1605741Y0904003
X1597041Y0893963
X1606898Y0893963
X1605741Y0887270
X1597041Y0887270
X1656441Y0790223
X1656441Y0827034
X1656441Y0863845
X1656441Y0786877
X1656441Y0823688
X1656441Y0860499
X1656441Y0870538
X1656441Y0877231
X1656441Y0796916
X1656441Y0803609
X1656441Y0810302
X1656441Y0816995
X1656441Y0833727
X1656441Y0840420
X1656441Y0847113
X1656441Y0853806
X1613083Y0880577
X1665141Y0880577
X1665141Y0873885
X1665141Y0867192
X1666038Y0857152
X1665141Y0850459
X1665141Y0843766
X1665141Y0837074
X1665141Y0830381
X1666030Y0820341
X1665141Y0813648
X1665141Y0806955
X1665141Y0800263
X1665141Y0793570
X1642883Y0877231
X1651583Y0877231
X1642883Y0870538
X1651583Y0870538
X1656441Y0880577
X1656441Y0873885
X1642032Y0853806
X1652559Y0853806
X1656441Y0867192
X1656441Y0857152
X1652742Y0863845
X1642058Y0863845
X1642883Y0847113
X1651583Y0847113
X1656441Y0850459
X1651583Y0840420
X1642883Y0840420
X1656441Y0843766
X1656441Y0837074
X1642883Y0833727
X1651583Y0833727
X1642018Y0827034
X1652767Y0827034
X1656441Y0830381
X1641945Y0816995
X1652545Y0816995
X1642883Y0810302
X1651583Y0810302
X1656441Y0820341
X1656441Y0813648
X1656441Y0806955
X1642883Y0803609
X1651583Y0803609
X1656441Y0800263
X1651583Y0796916
X1642883Y0796916
X1651583Y0790223
X1642883Y0790223
X1656441Y0793570
X1626741Y0873885
X1635441Y0873885
X1635441Y0880577
X1626741Y0880577
X1626741Y0857152
X1635441Y0857152
X1636441Y0867192
X1625705Y0867192
X1626741Y0850459
X1635441Y0850459
X1635441Y0843766
X1626741Y0843766
X1626741Y0837074
X1635441Y0837074
X1626741Y0830381
X1635441Y0830381
X1626741Y0806955
X1635441Y0806955
X1626741Y0813648
X1636574Y0813648
X1626741Y0820341
X1636341Y0820341
X1626741Y0800263
X1635441Y0800263
X1635441Y0793570
X1626741Y0793570
X1621883Y0877231
X1613183Y0877231
X1621883Y0870538
X1613183Y0870538
X1622961Y0853806
X1612474Y0853955
X1612408Y0863845
X1622060Y0863845
X1621943Y0847113
X1613183Y0847113
X1621883Y0840420
X1613183Y0840420
X1613183Y0833727
X1621883Y0833727
X1621883Y0827034
X1613183Y0827034
X1622986Y0810302
X1612363Y0810302
X1613183Y0816995
X1622916Y0816995
X1621883Y0803609
X1613183Y0803609
X1621883Y0796916
X1613183Y0796916
X1613183Y0790223
X1621883Y0790223
X1605741Y0880577
X1597041Y0880577
X1605741Y0873885
X1597041Y0873885
X1605741Y0867192
X1597041Y0867192
X1606623Y0857152
X1596200Y0857152
X1606896Y0850459
X1596147Y0850459
X1605741Y0843766
X1597041Y0843766
X1597041Y0837074
X1605741Y0837074
X1605741Y0830381
X1597041Y0830381
X1605741Y0820341
X1597041Y0820341
X1606735Y0813648
X1596218Y0813648
X1606934Y0806955
X1595774Y0806955
X1605741Y0800263
X1596988Y0800263
X1597041Y0793570
X1605741Y0793570
X1656441Y0766798
X1605800Y0766478
X1626741Y0766798
X1656441Y0773491
X1656441Y0780184
X1665141Y0783530
X1665141Y0776837
X1665141Y0770144
X1656441Y0783530
X1651583Y0780184
X1642883Y0780184
X1651583Y0773491
X1642883Y0773491
X1656441Y0776837
X1656441Y0770144
X1642883Y0766798
X1635441Y0783530
X1626741Y0783530
X1635441Y0776837
X1626741Y0776837
X1635441Y0770144
X1626741Y0770144
X1613183Y0780184
X1621883Y0780184
X1613183Y0773491
X1621883Y0773491
X1621883Y0766798
X1613183Y0766798
X1597041Y0783530
X1605741Y0783530
X1597041Y0776837
X1605741Y0776837
X1605741Y0770144
X1597041Y0770144
X1651583Y0766798
X1715841Y0766798
X1745541Y0766798
X1686041Y0766798
X1731983Y0783530
X1731983Y0770144
X1731983Y0776837
X1715841Y0773491
X1715841Y0780184
X1672583Y0783530
X1672583Y0770144
X1672583Y0776837
X1770383Y0780184
X1761683Y0780184
X1761683Y0773491
X1770383Y0773491
X1761683Y0766798
X1770383Y0766798
X1754241Y0783530
X1745541Y0783530
X1754241Y0776837
X1745541Y0776837
X1740683Y0780184
X1740683Y0773491
X1754241Y0770144
X1745541Y0770144
X1740683Y0766798
X1724541Y0776837
X1724541Y0783530
X1731983Y0780184
X1731983Y0773491
X1724541Y0770144
X1731983Y0766798
X1715841Y0776837
X1715841Y0783530
X1710983Y0780184
X1710983Y0773491
X1715841Y0770144
X1710983Y0766798
X1702283Y0780184
X1702283Y0773491
X1694841Y0783530
X1694841Y0776837
X1702283Y0766798
X1694841Y0770144
X1686141Y0783530
X1686141Y0776837
X1681283Y0780184
X1681283Y0773491
X1686141Y0770144
X1681283Y0766798
X1672583Y0780184
X1672583Y0773491
X1672583Y0766798
X1731983Y0820341
X1731983Y0857152
X1715841Y0790223
X1715841Y0827034
X1715841Y0863845
X1731983Y0786877
X1731983Y0823688
X1731983Y0860499
X1715841Y0786877
X1715841Y0823688
X1715841Y0860499
X1715841Y0870538
X1715841Y0877231
X1731983Y0880577
X1731983Y0793570
X1731983Y0800263
X1715841Y0796916
X1715841Y0803609
X1731983Y0806955
X1731983Y0813648
X1715841Y0810302
X1715841Y0816995
X1731983Y0830381
X1731983Y0837074
X1715841Y0833727
X1715841Y0840420
X1731983Y0843766
X1731983Y0850459
X1715841Y0847113
X1715841Y0853806
X1731983Y0867192
X1731983Y0873885
X1672583Y0820341
X1672583Y0857152
X1672583Y0786877
X1672583Y0823688
X1672583Y0860499
X1672583Y0880577
X1672583Y0793570
X1672583Y0800263
X1672583Y0806955
X1672583Y0813648
X1672583Y0830381
X1672583Y0837074
X1672583Y0843766
X1672583Y0850459
X1672583Y0867192
X1672583Y0873885
X1770383Y0877231
X1761683Y0877231
X1770383Y0870538
X1761683Y0870538
X1770383Y0863845
X1761683Y0863845
X1770383Y0853806
X1761683Y0853806
X1770383Y0847113
X1761683Y0847113
X1770383Y0840420
X1761683Y0840420
X1770383Y0833727
X1761683Y0833727
X1770383Y0827034
X1761683Y0827034
X1770383Y0816995
X1761683Y0816995
X1770383Y0810302
X1761683Y0810302
X1770383Y0803609
X1761683Y0803609
X1770383Y0796916
X1761683Y0796916
X1770383Y0790223
X1761683Y0790223
X1754241Y0880577
X1745541Y0880577
X1754241Y0873885
X1745541Y0873885
X1740683Y0877231
X1740683Y0870538
X1745541Y0867192
X1754241Y0867192
X1754241Y0857152
X1745541Y0857152
X1740683Y0863845
X1740683Y0853806
X1754241Y0850459
X1745541Y0850459
X1754241Y0837074
X1745541Y0837074
X1745541Y0843766
X1754241Y0843766
X1740683Y0847113
X1740683Y0840420
X1754241Y0830381
X1745541Y0830381
X1740683Y0833727
X1740683Y0827034
X1754241Y0820341
X1745541Y0820341
X1754241Y0813648
X1745541Y0813648
X1754241Y0806955
X1745541Y0806955
X1740683Y0816995
X1740683Y0810302
X1754241Y0800263
X1745541Y0800263
X1754241Y0793570
X1745541Y0793570
X1740683Y0803609
X1740683Y0796916
X1740683Y0790223
X1731983Y0877231
X1731983Y0870538
X1724541Y0880577
X1724541Y0873885
X1731983Y0863845
X1731983Y0853806
X1724541Y0867192
X1724541Y0857152
X1731983Y0847113
X1731983Y0840420
X1724541Y0850459
X1724541Y0843766
X1724541Y0837074
X1731983Y0833727
X1731983Y0827034
X1724541Y0830381
X1731983Y0816995
X1731983Y0810302
X1724541Y0820341
X1724541Y0813648
X1724541Y0806955
X1731983Y0803609
X1731983Y0796916
X1731983Y0790223
X1724541Y0800263
X1724541Y0793570
X1715841Y0880577
X1715841Y0873885
X1710983Y0877231
X1710983Y0870538
X1715841Y0867192
X1715841Y0857152
X1710983Y0863845
X1710983Y0853806
X1715841Y0850459
X1715841Y0843766
X1715841Y0837074
X1710983Y0847113
X1710983Y0840420
X1715841Y0830381
X1710983Y0833727
X1710983Y0827034
X1715841Y0820341
X1715841Y0813648
X1715841Y0806955
X1710983Y0816995
X1710983Y0810302
X1715841Y0800263
X1715841Y0793570
X1710983Y0803609
X1710983Y0796916
X1710983Y0790223
X1702283Y0877231
X1702283Y0870538
X1694841Y0880577
X1694841Y0873885
X1702283Y0863845
X1702283Y0853806
X1694841Y0867192
X1694841Y0857152
X1702283Y0847113
X1702283Y0840420
X1694841Y0850459
X1694841Y0843766
X1694841Y0837074
X1702283Y0833727
X1702283Y0827034
X1694841Y0830381
X1702283Y0816995
X1702283Y0810302
X1694841Y0820341
X1694841Y0813648
X1694841Y0806955
X1702283Y0803609
X1702283Y0796916
X1702283Y0790223
X1694841Y0800263
X1694841Y0793570
X1681283Y0877231
X1681283Y0870538
X1686141Y0880577
X1686141Y0873885
X1681283Y0863845
X1681283Y0853806
X1686141Y0867192
X1686141Y0857152
X1681283Y0847113
X1686141Y0850459
X1686141Y0843766
X1686141Y0837074
X1681283Y0840420
X1686141Y0830381
X1681283Y0833727
X1681283Y0827034
X1686141Y0820341
X1686141Y0813648
X1686141Y0806955
X1681283Y0816995
X1681283Y0810302
X1686141Y0800263
X1686141Y0793570
X1681283Y0803609
X1681283Y0796916
X1681283Y0790223
X1672583Y0877231
X1672583Y0870538
X1672583Y0863845
X1672583Y0853806
X1672583Y0847113
X1672583Y0840420
X1672583Y0833727
X1672583Y0827034
X1672583Y0816995
X1672583Y0810302
X1672583Y0803609
X1672583Y0796916
X1672583Y0790223
X1731983Y0954200
X1731983Y0957546
X1761683Y0954200
X1761683Y0957546
X1672583Y0954200
X1672583Y0957546
X1702183Y0954200
X1702183Y0957546
X1715841Y0957546
X1745541Y0957546
X1731883Y0970932
X1715841Y0937467
X1731983Y0893963
X1731983Y0930774
X1715841Y0900656
X1715841Y0934121
X1731983Y0897310
X1731983Y0934121
X1715841Y0897310
X1731983Y0887270
X1715841Y0883924
X1715841Y0890617
X1731983Y0904003
X1731983Y0910696
X1715841Y0907349
X1715841Y0914042
X1731983Y0964239
X1715841Y0967585
X1761683Y0964239
X1745541Y0967585
X1731983Y0940814
X1731983Y0947507
X1715841Y0944160
X1715841Y0950853
X1731983Y0917389
X1731983Y0924081
X1715841Y0920735
X1715841Y0927428
X1715841Y0974278
X1731983Y0977625
X1715841Y0980971
X1715841Y0960892
X1745541Y0960892
X1686041Y0957546
X1672583Y0970932
X1672583Y0893963
X1672583Y0930774
X1672583Y0897310
X1672583Y0934121
X1672583Y0887270
X1672583Y0904003
X1672583Y0910696
X1672583Y0964239
X1702283Y0964239
X1686141Y0967585
X1672583Y0940814
X1672583Y0947507
X1672583Y0917389
X1672583Y0924081
X1672583Y0977625
X1686041Y0960892
X1770383Y0980971
X1761683Y0980971
X1770383Y0974278
X1761683Y0974278
X1770383Y0967585
X1761683Y0967585
X1770383Y0960892
X1761683Y0960892
X1770383Y0950853
X1761683Y0950853
X1770383Y0944160
X1761683Y0944160
X1770383Y0937467
X1761683Y0937467
X1770383Y0920735
X1761683Y0920735
X1761683Y0927428
X1770383Y0927428
X1770383Y0914042
X1761683Y0914042
X1770383Y0907349
X1761683Y0907349
X1770383Y0900656
X1761683Y0900656
X1770383Y0890617
X1761683Y0890617
X1770383Y0883924
X1761683Y0883924
X1745541Y0977625
X1754241Y0977625
X1745541Y0970932
X1754241Y0970932
X1740683Y0980971
X1740683Y0974278
X1740683Y0967585
X1745541Y0964239
X1754241Y0964239
X1745541Y0954200
X1754241Y0954200
X1740683Y0960892
X1740683Y0950853
X1745541Y0947507
X1754241Y0947507
X1745541Y0940814
X1754241Y0940814
X1740683Y0944160
X1740683Y0937467
X1745541Y0930774
X1754241Y0930774
X1745541Y0924081
X1754241Y0924081
X1740683Y0927428
X1740683Y0920735
X1745541Y0917389
X1754241Y0917389
X1745541Y0910696
X1754241Y0910696
X1745541Y0904003
X1754241Y0904003
X1740683Y0914042
X1740683Y0907349
X1754241Y0887270
X1745541Y0887270
X1745541Y0893963
X1754241Y0893963
X1740683Y0900656
X1740683Y0890617
X1740683Y0883924
X1731983Y0980971
X1731983Y0974278
X1731983Y0967585
X1724541Y0977625
X1724541Y0970932
X1731983Y0960892
X1731983Y0950853
X1724541Y0964239
X1724541Y0954200
X1731983Y0944160
X1731983Y0937467
X1724541Y0947507
X1724541Y0940814
X1731983Y0927428
X1731983Y0920735
X1724541Y0930774
X1724541Y0924081
X1731983Y0914042
X1731983Y0907349
X1724541Y0917389
X1724541Y0910696
X1724541Y0904003
X1731983Y0900656
X1731983Y0890617
X1724541Y0887270
X1724541Y0893963
X1731983Y0883924
X1715841Y0977625
X1715841Y0970932
X1710983Y0980971
X1710983Y0974278
X1710983Y0967585
X1715841Y0964239
X1715841Y0954200
X1710983Y0960892
X1710983Y0950853
X1715841Y0947507
X1715841Y0940814
X1710983Y0944160
X1710983Y0937467
X1715841Y0930774
X1715841Y0924081
X1710983Y0927428
X1710983Y0920735
X1715841Y0917389
X1715841Y0910696
X1715841Y0904003
X1710983Y0914042
X1710983Y0907349
X1715841Y0887270
X1715841Y0893963
X1710983Y0900656
X1710983Y0890617
X1710983Y0883924
X1702283Y0980971
X1702283Y0974278
X1702283Y0967585
X1694841Y0977625
X1694841Y0970932
X1702283Y0960892
X1702283Y0950853
X1694841Y0964239
X1694841Y0954200
X1702283Y0944160
X1702283Y0937467
X1694841Y0947507
X1694841Y0940814
X1702283Y0927428
X1702283Y0920735
X1694841Y0930774
X1694841Y0924081
X1702283Y0914042
X1702283Y0907349
X1694841Y0917389
X1694841Y0910696
X1694841Y0904003
X1702283Y0900656
X1702283Y0890617
X1694841Y0893963
X1694841Y0887270
X1702283Y0883924
X1681283Y0980971
X1681283Y0974278
X1681283Y0967585
X1686141Y0977625
X1686141Y0970932
X1681283Y0960892
X1681283Y0950853
X1686141Y0964239
X1686141Y0954200
X1681283Y0944160
X1681283Y0937467
X1686141Y0947507
X1686141Y0940814
X1681283Y0927428
X1681283Y0920735
X1686141Y0930774
X1686141Y0924081
X1681283Y0914042
X1681283Y0907349
X1686141Y0917389
X1686141Y0910696
X1686141Y0904003
X1681283Y0900656
X1681283Y0890617
X1686141Y0893963
X1686141Y0887270
X1681283Y0883924
X1672583Y0980971
X1672583Y0974278
X1672583Y0967585
X1672583Y0960892
X1672583Y0950853
X1672583Y0944160
X1672583Y0937467
X1672583Y0927428
X1672583Y0920735
X1672583Y0914042
X1672583Y0907349
X1672583Y0900656
X1672583Y0890617
X1672583Y0883924
X1731983Y0994357
X1761683Y0994357
X1672583Y0994357
X1702183Y0994357
X1731683Y1057940
X1702283Y1057940
X1731983Y0984318
X1715841Y0987664
X1731983Y0991011
X1715841Y0994357
X1715841Y1021129
X1731983Y1078018
X1731983Y1081365
X1715841Y1081365
X1731983Y1051247
X1715841Y1054593
X1761683Y1051247
X1745541Y1054593
X1731883Y1064633
X1731818Y1071326
X1715841Y1067979
X1715841Y1074672
X1715841Y1027822
X1731983Y1031168
X1715841Y1034514
X1731683Y1037861
X1715841Y1041207
X1731683Y1044554
X1715841Y1047900
X1731983Y1024475
X1761683Y1024475
X1731983Y1021129
X1761683Y1021129
X1715841Y1061286
X1672583Y0984318
X1672583Y0991011
X1672583Y1078018
X1672583Y1081365
X1672583Y1051247
X1702283Y1051247
X1686141Y1054593
X1672583Y1064633
X1672583Y1071325
X1672583Y1031168
X1672283Y1037861
X1672283Y1044554
X1672583Y1024475
X1702283Y1024475
X1672583Y1021129
X1702283Y1021129
X1770383Y1074672
X1761683Y1074672
X1770383Y1067979
X1761683Y1067979
X1770383Y1061286
X1761683Y1061286
X1770383Y1054593
X1761683Y1054593
X1770383Y1047900
X1761683Y1047900
X1770383Y1041207
X1761683Y1041207
X1770383Y1034515
X1761683Y1034515
X1770383Y1027822
X1761683Y1027822
X1770383Y1017782
X1761683Y1017782
X1770383Y0987664
X1761683Y0987664
X1745541Y1078018
X1754241Y1078018
X1754241Y1064633
X1745541Y1064633
X1745541Y1071326
X1754241Y1071326
X1740683Y1067979
X1740683Y1074672
X1754241Y1057940
X1745541Y1057940
X1754241Y1051247
X1745541Y1051247
X1740683Y1061286
X1740683Y1054593
X1754241Y1037861
X1745541Y1037861
X1745541Y1044554
X1754241Y1044554
X1740683Y1047900
X1740683Y1041207
X1740683Y1034515
X1754241Y1031168
X1745541Y1031168
X1754241Y1024475
X1745541Y1024475
X1745541Y1017782
X1754241Y1017782
X1740683Y1027822
X1740683Y1017782
X1745541Y0991011
X1754241Y0991011
X1745541Y0984318
X1754241Y0984318
X1740683Y0987664
X1731983Y1067979
X1731983Y1074672
X1724541Y1078018
X1724541Y1064633
X1724541Y1071326
X1731983Y1061286
X1731983Y1054593
X1724541Y1057940
X1724541Y1051247
X1731983Y1047900
X1731983Y1041207
X1731983Y1034515
X1724541Y1044554
X1724541Y1037861
X1731983Y1027822
X1731983Y1017782
X1724541Y1031168
X1724541Y1024475
X1724541Y1017782
X1731983Y0987664
X1724541Y0991011
X1724541Y0984318
X1715841Y1078018
X1715841Y1064633
X1715841Y1071326
X1710983Y1074672
X1710983Y1067979
X1715841Y1057940
X1715841Y1051247
X1710983Y1061286
X1710983Y1054593
X1715841Y1044554
X1715841Y1037861
X1710983Y1047900
X1710983Y1041207
X1710983Y1034515
X1715841Y1031168
X1715841Y1024475
X1715841Y1017782
X1710983Y1027822
X1710983Y1017782
X1715841Y0991011
X1715841Y0984318
X1710983Y0987664
X1702283Y1074672
X1702283Y1067979
X1694841Y1078018
X1694841Y1071326
X1694841Y1064633
X1702283Y1061286
X1702283Y1054593
X1694841Y1057940
X1694841Y1051247
X1702283Y1047900
X1702283Y1041207
X1702283Y1034515
X1694841Y1044554
X1694841Y1037861
X1702283Y1027822
X1702283Y1017782
X1694841Y1031168
X1694841Y1024475
X1694841Y1017782
X1702283Y0987664
X1694841Y0991011
X1694841Y0984318
X1681283Y1074672
X1681283Y1067979
X1686141Y1078018
X1686141Y1071326
X1686141Y1064633
X1681283Y1054593
X1681283Y1061286
X1686141Y1057940
X1686141Y1051247
X1681283Y1047900
X1681283Y1041207
X1681283Y1034515
X1686141Y1044554
X1686141Y1037861
X1681283Y1027822
X1681283Y1017782
X1686141Y1031168
X1686141Y1024475
X1686141Y1017782
X1681283Y0987664
X1686141Y0991011
X1686141Y0984318
X1672583Y1074672
X1672583Y1067979
X1672583Y1054593
X1672583Y1061286
X1672583Y1047900
X1672583Y1041207
X1672583Y1034515
X1672583Y1027822
X1672583Y1017782
X1672583Y0987664
X1731983Y1114829
X1731983Y1151640
X1715841Y1084711
X1715841Y1121522
X1715841Y1158333
X1731983Y1118176
X1731983Y1154987
X1715841Y1118176
X1715841Y1154987
X1731983Y1101444
X1731818Y1108137
X1715841Y1104790
X1715841Y1111483
X1731983Y1124869
X1731983Y1131562
X1715841Y1128215
X1715841Y1134908
X1731983Y1138255
X1731983Y1144947
X1715841Y1141601
X1715841Y1148294
X1731983Y1161680
X1731983Y1168373
X1715841Y1165026
X1715841Y1171719
X1731983Y1175066
X1731818Y1181759
X1715841Y1178412
X1731983Y1088058
X1731983Y1094751
X1715841Y1091404
X1715841Y1098097
X1672583Y1114829
X1672583Y1151640
X1672583Y1118176
X1672583Y1154987
X1672583Y1101444
X1672583Y1108136
X1672583Y1124869
X1672583Y1131562
X1672583Y1138255
X1672583Y1144947
X1672583Y1161680
X1672583Y1168373
X1672583Y1175066
X1672583Y1181758
X1672583Y1088058
X1672583Y1094751
X1770383Y1178412
X1761683Y1178412
X1770383Y1171719
X1761683Y1171719
X1770383Y1165026
X1761683Y1165026
X1770383Y1158333
X1761683Y1158333
X1770383Y1148294
X1761683Y1148294
X1770383Y1141601
X1761683Y1141601
X1770383Y1134908
X1761683Y1134908
X1770383Y1128215
X1761683Y1128215
X1770383Y1121522
X1761683Y1121522
X1770383Y1111483
X1761683Y1111483
X1770383Y1104790
X1761683Y1104790
X1761683Y1098097
X1770383Y1098097
X1770383Y1091404
X1761683Y1091404
X1770383Y1084711
X1761683Y1084711
X1754241Y1181759
X1745541Y1181759
X1740683Y1178412
X1745541Y1168373
X1754241Y1168373
X1754241Y1175066
X1745541Y1175066
X1740683Y1171719
X1740683Y1165026
X1745541Y1161680
X1754241Y1161680
X1745541Y1151641
X1754241Y1151641
X1740683Y1158333
X1740683Y1148294
X1745541Y1144948
X1754241Y1144948
X1745541Y1138255
X1754241Y1138255
X1745541Y1131562
X1754241Y1131562
X1740683Y1141601
X1740683Y1134908
X1745541Y1124869
X1754241Y1124869
X1745541Y1114829
X1754241Y1114829
X1740683Y1128215
X1740683Y1121522
X1745541Y1108137
X1754241Y1108137
X1745541Y1101444
X1754241Y1101444
X1740683Y1111483
X1740683Y1104790
X1740683Y1098097
X1745541Y1094751
X1754241Y1094751
X1745541Y1088058
X1754241Y1088058
X1740683Y1091404
X1740683Y1084711
X1731983Y1178412
X1724541Y1181759
X1731983Y1171719
X1731983Y1165026
X1724541Y1175066
X1724541Y1168373
X1731983Y1158333
X1731983Y1148294
X1724541Y1161680
X1724541Y1151641
X1731983Y1141601
X1731983Y1134908
X1724541Y1144948
X1724541Y1138255
X1724541Y1131562
X1731983Y1128215
X1731983Y1121522
X1724541Y1124869
X1724541Y1114829
X1731983Y1111483
X1731983Y1104790
X1731983Y1098097
X1724541Y1108137
X1724541Y1101444
X1731983Y1091404
X1731983Y1084711
X1724541Y1094751
X1724541Y1088058
X1715841Y1181759
X1710983Y1178412
X1715841Y1175066
X1715841Y1168373
X1710983Y1171719
X1710983Y1165026
X1715841Y1161680
X1715841Y1151641
X1710983Y1158333
X1710983Y1148294
X1715841Y1144948
X1715841Y1138255
X1715841Y1131562
X1710983Y1141601
X1710983Y1134908
X1715841Y1124869
X1715841Y1114829
X1710983Y1128215
X1710983Y1121522
X1715841Y1108137
X1715841Y1101444
X1710983Y1111483
X1710983Y1104790
X1710983Y1098097
X1715841Y1094751
X1715841Y1088058
X1710983Y1091404
X1710983Y1084711
X1702283Y1178412
X1694841Y1181759
X1702283Y1171719
X1702283Y1165026
X1694841Y1175066
X1694841Y1168373
X1702283Y1158333
X1702283Y1148294
X1694841Y1161680
X1694841Y1151641
X1702283Y1141601
X1702283Y1134908
X1694841Y1144948
X1694841Y1138255
X1694841Y1131562
X1702283Y1128215
X1702283Y1121522
X1694841Y1124869
X1694841Y1114829
X1702283Y1111483
X1702283Y1104790
X1702283Y1098097
X1694841Y1108137
X1694841Y1101444
X1702283Y1091404
X1702283Y1084711
X1694841Y1094751
X1694841Y1088058
X1681283Y1178412
X1686141Y1181759
X1681283Y1171719
X1681283Y1165026
X1686141Y1175066
X1686141Y1168373
X1681283Y1158333
X1681283Y1148294
X1686141Y1161680
X1686141Y1151641
X1681283Y1141601
X1681283Y1134908
X1686141Y1144948
X1686141Y1138255
X1686141Y1131562
X1681283Y1128215
X1681283Y1121522
X1686141Y1124869
X1686141Y1114829
X1681283Y1111483
X1681283Y1104790
X1681283Y1098097
X1686141Y1108137
X1686141Y1101444
X1681283Y1091404
X1681283Y1084711
X1686141Y1094751
X1686141Y1088058
X1672583Y1178412
X1672583Y1171719
X1672583Y1165026
X1672583Y1158333
X1672583Y1148294
X1672583Y1141601
X1672583Y1134908
X1672583Y1128215
X1672583Y1121522
X1672583Y1111483
X1672583Y1104790
X1672583Y1098097
X1672583Y1091404
X1672583Y1084711
X1714440Y1255381
X1742337Y1252300
X1683578Y1253780
X1731983Y1248688
X1731983Y1252034
X1713930Y1262074
X1761683Y1248688
X1770299Y1252034
X1743710Y1262074
X1672583Y1248688
X1681179Y1252034
X1702283Y1248688
X1711109Y1252034
X1683500Y1264312
X1731983Y1258727
X1761683Y1258727
X1672583Y1258727
X1699030Y1263912
X1731983Y1255381
X1761683Y1255381
X1672583Y1255381
X1699089Y1258842
X1745541Y1258727
X1713620Y1258512
X1686141Y1258727
X1761683Y1265420
X1761683Y1262074
X1745541Y1265420
X1731983Y1262074
X1731939Y1265420
X1715839Y1265420
X1702283Y1262074
X1702249Y1265420
X1681309Y1262074
X1686119Y1264985
X1672188Y1263764
X1731818Y1188452
X1731983Y1225262
X1715841Y1195144
X1715841Y1231955
X1731983Y1191798
X1731983Y1228609
X1715841Y1191798
X1715841Y1228609
X1715841Y1201837
X1715841Y1208530
X1731983Y1211877
X1731983Y1218569
X1715841Y1215223
X1715841Y1221916
X1731983Y1235302
X1731983Y1241995
X1715841Y1238648
X1715841Y1185105
X1731983Y1198491
X1731983Y1205184
X1715841Y1245341
X1672583Y1188451
X1672583Y1225262
X1672583Y1191798
X1672583Y1228609
X1672583Y1211877
X1672583Y1218569
X1672583Y1235302
X1672583Y1241995
X1672583Y1198491
X1672583Y1205184
X1756922Y1247632
X1727041Y1248688
X1699852Y1245418
X1764588Y1273344
X1767388Y1273344
X1770383Y1245341
X1761683Y1245341
X1770383Y1238648
X1761683Y1238648
X1770383Y1231955
X1761683Y1231955
X1770383Y1221916
X1761683Y1221916
X1770383Y1215223
X1761683Y1215223
X1770383Y1208530
X1761683Y1208530
X1770383Y1201837
X1761683Y1201837
X1770383Y1195144
X1761683Y1195144
X1770383Y1185105
X1761683Y1185105
X1748588Y1273344
X1751388Y1273344
X1754488Y1257264
X1745541Y1248688
X1754241Y1248688
X1740683Y1245341
X1745541Y1241995
X1754241Y1241995
X1745541Y1235302
X1754241Y1235302
X1740683Y1238648
X1740683Y1231955
X1745541Y1225263
X1754241Y1225263
X1745541Y1218570
X1754241Y1218570
X1745541Y1211877
X1754241Y1211877
X1740683Y1221916
X1740683Y1215223
X1745541Y1205184
X1754241Y1205184
X1745541Y1198491
X1754241Y1198491
X1740683Y1208530
X1740683Y1201837
X1740683Y1195144
X1745541Y1188452
X1754241Y1188452
X1740683Y1185105
X1737688Y1273344
X1734888Y1273344
X1731983Y1245341
X1724588Y1257164
X1724541Y1248688
X1731983Y1238648
X1731983Y1231955
X1724541Y1241995
X1724541Y1235302
X1731983Y1221916
X1731983Y1215223
X1724541Y1225263
X1724541Y1218570
X1724541Y1211877
X1731983Y1208530
X1731983Y1201837
X1731983Y1195144
X1724541Y1205184
X1724541Y1198491
X1731983Y1185105
X1724541Y1188452
X1721688Y1273344
X1718888Y1273344
X1707514Y1273444
X1715841Y1248688
X1710983Y1245341
X1715841Y1241995
X1715841Y1235302
X1710983Y1238648
X1710983Y1231955
X1715841Y1225263
X1715841Y1218570
X1715841Y1211877
X1710983Y1221916
X1710983Y1215223
X1715841Y1205184
X1715841Y1198491
X1710983Y1208530
X1710983Y1201837
X1710983Y1195144
X1715841Y1188452
X1710983Y1185105
X1705188Y1273344
X1691988Y1273344
X1702283Y1245341
X1695188Y1257064
X1694841Y1248688
X1702283Y1238648
X1702283Y1231955
X1694841Y1241995
X1694841Y1235302
X1702283Y1221916
X1702283Y1215223
X1694841Y1225263
X1694841Y1218570
X1694841Y1211877
X1702283Y1208530
X1702283Y1201837
X1702283Y1195144
X1694841Y1205184
X1694841Y1198491
X1702283Y1185105
X1694841Y1188452
X1689188Y1273344
X1678288Y1273344
X1675488Y1273344
X1686141Y1248688
X1681283Y1245341
X1686141Y1241995
X1686141Y1235302
X1681283Y1238648
X1681283Y1231955
X1681283Y1221916
X1681283Y1215223
X1686141Y1225263
X1686141Y1218570
X1686141Y1211877
X1681283Y1208530
X1681283Y1201837
X1681283Y1195144
X1686141Y1205184
X1686141Y1198491
X1681283Y1185105
X1686141Y1188452
X1672583Y1245341
X1672583Y1238648
X1672583Y1231955
X1672583Y1221916
X1672583Y1215223
X1672583Y1208530
X1672583Y1201837
X1672583Y1195144
X1672583Y1185105
X1746288Y1310474
X1749088Y1310474
X1773480Y1253692
X1813814Y1254693
X1791383Y1248688
X1800019Y1252034
X1773390Y1262074
X1821139Y1248155
X1821083Y1252034
X1803100Y1262074
X1788360Y1264522
X1829940Y1263662
X1788219Y1259312
X1829920Y1258322
X1804941Y1258727
X1800427Y1248125
X1775241Y1258727
X1821083Y1265420
X1821083Y1262074
X1804941Y1265420
X1791383Y1262074
X1791383Y1265420
X1775241Y1265420
X1791383Y1188451
X1791383Y1225263
X1775241Y1195144
X1775241Y1231955
X1791383Y1191798
X1791383Y1228609
X1775241Y1191798
X1775241Y1228609
X1775241Y1201837
X1775241Y1208530
X1791383Y1211877
X1791383Y1218570
X1775241Y1215223
X1775241Y1221916
X1791383Y1235302
X1791383Y1241995
X1775241Y1238648
X1775241Y1185105
X1791383Y1198491
X1791383Y1205184
X1775241Y1245341
X1830379Y1250358
X1788373Y1241769
X1815063Y1233103
X1821083Y1245341
X1829783Y1245341
X1829783Y1238648
X1821083Y1238648
X1829783Y1231955
X1821083Y1231955
X1829783Y1221916
X1821083Y1221916
X1829783Y1215223
X1821083Y1215223
X1829783Y1208530
X1821083Y1208530
X1829783Y1201837
X1821083Y1201837
X1829783Y1195144
X1821083Y1195144
X1829783Y1185105
X1821083Y1185105
X1815388Y1273044
X1807988Y1273344
X1810788Y1273344
X1818188Y1273044
X1819054Y1253986
X1804941Y1248688
X1813641Y1248688
X1804941Y1241995
X1813641Y1241995
X1804941Y1235302
X1813641Y1235302
X1804941Y1225263
X1813641Y1225263
X1804941Y1218570
X1813641Y1218570
X1804941Y1211877
X1813641Y1211877
X1804941Y1205184
X1813641Y1205184
X1804941Y1198491
X1813641Y1198491
X1804941Y1188452
X1813641Y1188452
X1794288Y1273344
X1797088Y1273344
X1800083Y1245341
X1791383Y1245341
X1800083Y1238648
X1791383Y1238648
X1800083Y1231955
X1791383Y1231955
X1800083Y1221916
X1791383Y1221916
X1800083Y1215223
X1791383Y1215223
X1800083Y1208530
X1791383Y1208530
X1800083Y1201837
X1791383Y1201837
X1800083Y1195144
X1791383Y1195144
X1800083Y1185105
X1791383Y1185105
X1778288Y1273344
X1781088Y1273344
X1783941Y1248688
X1775241Y1248688
X1784188Y1257664
X1783941Y1241995
X1775241Y1241995
X1783941Y1235302
X1775241Y1235302
X1783941Y1225263
X1775241Y1225263
X1783941Y1218570
X1775241Y1218570
X1783941Y1211877
X1775241Y1211877
X1783941Y1205184
X1775241Y1205184
X1783941Y1198491
X1775241Y1198491
X1783941Y1188452
X1775241Y1188452
X1791383Y1114829
X1791383Y1151640
X1775241Y1084711
X1775241Y1121522
X1775241Y1158333
X1791383Y1118176
X1791383Y1154987
X1775241Y1118176
X1775241Y1154987
X1791383Y1101444
X1791383Y1108136
X1775241Y1104790
X1775241Y1111483
X1791383Y1124869
X1791383Y1131562
X1775241Y1128215
X1775241Y1134908
X1791383Y1138255
X1791383Y1144947
X1775241Y1141601
X1775241Y1148294
X1791383Y1161680
X1791383Y1168373
X1775241Y1165026
X1775241Y1171719
X1791383Y1175066
X1791383Y1181758
X1775241Y1178412
X1791383Y1088058
X1791383Y1094751
X1775241Y1091404
X1775241Y1098097
X1829783Y1178412
X1821083Y1178412
X1829783Y1171719
X1821083Y1171719
X1829783Y1165026
X1821083Y1165026
X1829783Y1158333
X1821083Y1158333
X1829783Y1148294
X1821083Y1148294
X1829783Y1141601
X1821083Y1141601
X1829783Y1134908
X1821083Y1134908
X1829783Y1128215
X1821083Y1128215
X1829783Y1121522
X1821083Y1121522
X1829783Y1111483
X1821083Y1111483
X1829783Y1104790
X1821083Y1104790
X1829783Y1098097
X1821083Y1098097
X1829783Y1091404
X1821083Y1091404
X1829783Y1084711
X1821083Y1084711
X1804941Y1181759
X1813641Y1181759
X1804941Y1175066
X1813641Y1175066
X1804941Y1168373
X1813641Y1168373
X1804941Y1161680
X1813641Y1161680
X1804941Y1151641
X1813641Y1151641
X1804941Y1144948
X1813641Y1144948
X1804941Y1138255
X1813641Y1138255
X1804941Y1131562
X1813641Y1131562
X1804941Y1124869
X1813641Y1124869
X1804941Y1114829
X1813641Y1114829
X1804941Y1108137
X1813641Y1108137
X1804941Y1101444
X1813641Y1101444
X1804941Y1094751
X1813641Y1094751
X1804941Y1088058
X1813641Y1088058
X1800083Y1178412
X1791383Y1178412
X1800083Y1171719
X1791383Y1171719
X1800083Y1165026
X1791383Y1165026
X1800083Y1158333
X1791383Y1158333
X1800083Y1148294
X1791383Y1148294
X1800083Y1141601
X1791383Y1141601
X1791383Y1134908
X1800083Y1134908
X1800083Y1128215
X1791383Y1128215
X1800083Y1121522
X1791383Y1121522
X1800083Y1111483
X1791383Y1111483
X1800083Y1104790
X1791383Y1104790
X1800083Y1098097
X1791383Y1098097
X1800083Y1091404
X1791383Y1091404
X1800083Y1084711
X1791383Y1084711
X1783941Y1181759
X1775241Y1181759
X1783941Y1175066
X1775241Y1175066
X1783941Y1168373
X1775241Y1168373
X1783941Y1161680
X1775241Y1161680
X1775241Y1151641
X1783941Y1151641
X1783941Y1144948
X1775241Y1144948
X1783941Y1138255
X1775241Y1138255
X1783941Y1131562
X1775241Y1131562
X1783941Y1124869
X1775241Y1124869
X1783941Y1114829
X1775241Y1114829
X1783941Y1108137
X1775241Y1108137
X1783941Y1101444
X1775241Y1101444
X1783941Y1094751
X1775241Y1094751
X1783941Y1088058
X1775241Y1088058
X1791383Y0994357
X1820983Y0994357
X1791383Y0984318
X1775241Y0987664
X1791383Y0991011
X1775241Y0994357
X1775241Y1021129
X1791383Y1078018
X1791383Y1081365
X1775241Y1081365
X1791083Y1051247
X1775241Y1054593
X1821083Y1051247
X1804941Y1054593
X1791383Y1064633
X1791383Y1071325
X1775241Y1067979
X1775241Y1074672
X1775241Y1027822
X1791383Y1031168
X1775241Y1034515
X1791383Y1037861
X1775241Y1041207
X1791383Y1044554
X1775241Y1047900
X1791383Y1024475
X1821083Y1024475
X1791383Y1021129
X1821083Y1021129
X1775241Y1061286
X1829783Y1074672
X1821083Y1074672
X1821083Y1067979
X1829783Y1067979
X1821083Y1061286
X1829783Y1061286
X1821083Y1054593
X1829783Y1054593
X1821083Y1047900
X1829783Y1047900
X1821083Y1041207
X1829783Y1041207
X1821083Y1034515
X1829783Y1034515
X1821083Y1027822
X1829783Y1027822
X1821083Y1017782
X1829783Y1017782
X1821083Y0987664
X1829783Y0987664
X1804941Y1078018
X1813641Y1078018
X1804941Y1071326
X1813641Y1071326
X1813641Y1064633
X1804941Y1064633
X1813641Y1051247
X1804941Y1051247
X1804941Y1057940
X1813641Y1057940
X1813641Y1044554
X1804941Y1044554
X1813641Y1037861
X1804941Y1037861
X1813641Y1031168
X1804941Y1031168
X1813641Y1024475
X1804941Y1024475
X1813641Y1017782
X1804941Y1017782
X1813641Y0991011
X1804941Y0991011
X1813641Y0984318
X1804941Y0984318
X1800083Y1074672
X1791383Y1074672
X1800083Y1067979
X1791383Y1067979
X1800083Y1061286
X1791383Y1061286
X1800083Y1054593
X1791383Y1054593
X1800083Y1047900
X1791383Y1047900
X1800083Y1041207
X1791383Y1041207
X1800083Y1034515
X1791383Y1034515
X1800083Y1027822
X1791383Y1027822
X1800083Y1017782
X1791383Y1017782
X1800083Y0987664
X1791383Y0987664
X1783941Y1078018
X1775241Y1078018
X1783941Y1071326
X1775241Y1071326
X1783941Y1064633
X1775241Y1064633
X1783941Y1057940
X1775241Y1057940
X1783941Y1051247
X1775241Y1051247
X1783941Y1044554
X1775241Y1044554
X1783941Y1037861
X1775241Y1037861
X1783941Y1031168
X1775241Y1031168
X1783941Y1024475
X1775241Y1024475
X1783941Y1017782
X1775241Y1017782
X1783941Y0991011
X1775241Y0991011
X1783941Y0984318
X1775241Y0984318
X1791383Y0954200
X1791383Y0957546
X1820983Y0954200
X1820983Y0957546
X1775241Y0957546
X1804941Y0957546
X1791383Y0970932
X1775241Y0937467
X1791383Y0893963
X1791383Y0930774
X1775241Y0900656
X1775241Y0934121
X1791383Y0897310
X1791383Y0934121
X1775241Y0897310
X1791383Y0887270
X1775241Y0883924
X1775241Y0890617
X1791383Y0904003
X1791383Y0910696
X1775241Y0907349
X1775241Y0914042
X1791383Y0964239
X1775241Y0967585
X1821083Y0964239
X1804941Y0967585
X1791383Y0940814
X1791383Y0947507
X1775241Y0944160
X1775241Y0950853
X1791383Y0917389
X1791383Y0924081
X1775241Y0920735
X1775241Y0927428
X1775241Y0974278
X1791383Y0977625
X1775241Y0980971
X1775241Y0960892
X1804941Y0960892
X1821083Y0980971
X1829783Y0980971
X1821083Y0974278
X1829783Y0974278
X1821083Y0967585
X1829783Y0967585
X1821083Y0960892
X1829783Y0960892
X1821083Y0950853
X1829783Y0950853
X1821083Y0944160
X1829783Y0944160
X1821083Y0937467
X1829783Y0937467
X1821083Y0927428
X1829783Y0927428
X1821083Y0920735
X1829783Y0920735
X1821083Y0914042
X1829783Y0914042
X1821083Y0907349
X1829783Y0907349
X1821083Y0900656
X1829783Y0900656
X1821083Y0890617
X1829783Y0890617
X1821083Y0883924
X1829783Y0883924
X1813641Y0977625
X1804941Y0977625
X1813641Y0970932
X1804941Y0970932
X1813641Y0964239
X1804941Y0964239
X1813641Y0954200
X1804941Y0954200
X1813641Y0947507
X1804941Y0947507
X1813641Y0940814
X1804941Y0940814
X1813641Y0930774
X1804941Y0930774
X1813641Y0924081
X1804941Y0924081
X1813641Y0917389
X1804941Y0917389
X1813641Y0910696
X1804941Y0910696
X1813641Y0904003
X1804941Y0904003
X1813641Y0893963
X1804941Y0893963
X1813641Y0887270
X1804941Y0887270
X1800083Y0980971
X1791383Y0980971
X1800083Y0974278
X1791383Y0974278
X1800083Y0967585
X1791383Y0967585
X1800083Y0960892
X1791383Y0960892
X1791383Y0950853
X1800083Y0950853
X1800083Y0944160
X1791383Y0944160
X1800083Y0937467
X1791383Y0937467
X1800083Y0927428
X1791383Y0927428
X1800083Y0920735
X1791383Y0920735
X1800083Y0914042
X1791383Y0914042
X1800083Y0907349
X1791383Y0907349
X1800083Y0900656
X1791383Y0900656
X1800083Y0890617
X1791383Y0890617
X1800083Y0883924
X1791383Y0883924
X1783941Y0977625
X1775241Y0977625
X1783941Y0970932
X1775241Y0970932
X1783941Y0964239
X1775241Y0964239
X1783941Y0954200
X1775241Y0954200
X1783941Y0947507
X1775241Y0947507
X1783941Y0940814
X1775241Y0940814
X1783941Y0930774
X1775241Y0930774
X1783941Y0924081
X1775241Y0924081
X1783941Y0917389
X1775241Y0917389
X1783941Y0910696
X1775241Y0910696
X1783941Y0904003
X1775241Y0904003
X1783941Y0893963
X1775241Y0893963
X1783941Y0887270
X1775241Y0887270
X1791383Y0820341
X1791383Y0857152
X1775241Y0790223
X1775241Y0827034
X1775241Y0863845
X1791383Y0786877
X1791383Y0823688
X1791383Y0860499
X1775241Y0786877
X1775241Y0823688
X1775241Y0860499
X1775241Y0870538
X1775241Y0877231
X1791383Y0880577
X1791383Y0793570
X1791383Y0800263
X1775241Y0796916
X1775241Y0803609
X1791383Y0806955
X1791383Y0813648
X1775241Y0810302
X1775241Y0816995
X1791383Y0830381
X1791383Y0837074
X1775241Y0833727
X1775241Y0840420
X1791383Y0843766
X1791383Y0850459
X1775241Y0847113
X1775241Y0853806
X1791383Y0867192
X1791383Y0873885
X1821083Y0877231
X1829783Y0877231
X1821083Y0870538
X1829783Y0870538
X1821083Y0863845
X1829783Y0863845
X1821083Y0853806
X1829783Y0853806
X1821083Y0840420
X1829783Y0840420
X1829783Y0847113
X1821083Y0847113
X1821083Y0833727
X1829783Y0833727
X1821083Y0827034
X1829783Y0827034
X1821083Y0816995
X1829783Y0816995
X1821083Y0810302
X1829783Y0810302
X1821083Y0803609
X1829783Y0803609
X1821083Y0796916
X1829783Y0796916
X1821083Y0790223
X1829783Y0790223
X1813641Y0880577
X1804941Y0880577
X1813641Y0873885
X1804941Y0873885
X1804941Y0867192
X1813641Y0867192
X1813641Y0857152
X1804941Y0857152
X1813641Y0850459
X1804941Y0850459
X1813641Y0837074
X1804941Y0837074
X1813641Y0843766
X1804941Y0843766
X1813641Y0830381
X1804941Y0830381
X1813641Y0820341
X1804941Y0820341
X1813641Y0813648
X1804941Y0813648
X1813641Y0806955
X1804941Y0806955
X1813641Y0800263
X1804941Y0800263
X1813641Y0793570
X1804941Y0793570
X1800083Y0877231
X1791383Y0877231
X1800083Y0870538
X1791383Y0870538
X1800083Y0863845
X1791383Y0863845
X1800083Y0853806
X1791383Y0853806
X1800083Y0847113
X1791383Y0847113
X1800083Y0840420
X1791383Y0840420
X1791383Y0833727
X1800083Y0833727
X1800083Y0827034
X1791383Y0827034
X1800083Y0816995
X1791383Y0816995
X1800083Y0810302
X1791383Y0810302
X1800083Y0803609
X1791383Y0803609
X1800083Y0796916
X1791383Y0796916
X1800083Y0790223
X1791383Y0790223
X1783941Y0880577
X1775241Y0880577
X1783941Y0873885
X1775241Y0873885
X1783941Y0867192
X1775241Y0867192
X1783941Y0857152
X1775241Y0857152
X1783941Y0850459
X1775241Y0850459
X1783941Y0843766
X1775241Y0843766
X1783941Y0837074
X1775241Y0837074
X1775241Y0830381
X1783941Y0830381
X1783941Y0820341
X1775241Y0820341
X1783941Y0813648
X1775241Y0813648
X1783941Y0806955
X1775241Y0806955
X1783941Y0800263
X1775241Y0800263
X1783941Y0793570
X1775241Y0793570
X1773559Y0767345
X1804841Y0766798
X1791383Y0783530
X1791383Y0770144
X1791383Y0776837
X1775241Y0773491
X1775241Y0780184
X1821083Y0780184
X1829783Y0780184
X1821083Y0773491
X1829783Y0773491
X1821083Y0766798
X1829783Y0766798
X1813641Y0783530
X1804941Y0783530
X1813641Y0776837
X1804941Y0776837
X1813641Y0770144
X1804941Y0770144
X1800083Y0780184
X1791383Y0780184
X1800083Y0773491
X1791383Y0773491
X1800083Y0766798
X1791383Y0766798
X1783941Y0783530
X1775241Y0783530
X1783941Y0776837
X1775241Y0776837
X1783941Y0770144
X1775241Y0770144
M00
X1900275Y-0019342
X1910275Y-0019342
X1931395Y-0019332
X1921395Y-0019332
X1942395Y-0019152
X1952395Y-0019152
X1963362Y-0019190
X1900275Y-0009342
X1910275Y-0009342
X1931395Y-0009332
X1921395Y-0009332
X1942395Y-0009152
X1952395Y-0009152
X1963362Y-0009190
X1879155Y0354948
X1879155Y0344948
X1889155Y0344948
X1889155Y0354948
X1889155Y0458898
X1889155Y0468898
X1879155Y0468898
X1879155Y0458898
X1889155Y0478898
X1889155Y0468898
X1879155Y0468898
X1879155Y0478898
X1879155Y0582848
X1889155Y0582848
X1910275Y0582858
X1900275Y0582858
X1921395Y0582868
X1931395Y0582868
X1952395Y0583048
X1942395Y0583048
X1963362Y0583010
X1879155Y0592848
X1889155Y0592848
X1879155Y0602848
X1879155Y0592848
X1889155Y0592848
X1889155Y0602848
X1910275Y0592858
X1900275Y0592858
X1921395Y0602868
X1921395Y0592868
X1931395Y0592868
X1931395Y0602868
X1921395Y0592868
X1931395Y0592868
X1952395Y0603048
X1952395Y0593048
X1942395Y0593048
X1942395Y0603048
X1952395Y0593048
X1942395Y0593048
X1963362Y0603010
X1963362Y0593010
X1963362Y0593010
X1889155Y0706798
X1889155Y0716798
X1879155Y0716798
X1879155Y0706798
X1889155Y0726798
X1889155Y0716798
X1879155Y0716798
X1879155Y0726798
X1900275Y0726808
X1900275Y0716808
X1910275Y0716808
X1910275Y0726808
X1879155Y0830748
X1879155Y0840748
X1889155Y0840748
X1889155Y0830748
X1910275Y0830758
X1910275Y0840758
X1900275Y0840758
X1900275Y0830758
X1910275Y0850758
X1910275Y0840758
X1900275Y0840758
X1900275Y0850758
X1900275Y0954708
X1900275Y0964708
X1910275Y0964708
X1910275Y0954708
X1931395Y1195068
X1931395Y1205068
X1921395Y1205068
X1921395Y1195068
X1942395Y1195248
X1942395Y1205248
X1952395Y1205248
X1952395Y1195248
X1963362Y1205210
X1963362Y1195210
X2015452Y1195220
X2015452Y1205220
X2005452Y1205220
X2005452Y1195220
X2026452Y1195400
X2026452Y1205400
X2036452Y1205400
X2036452Y1195400
X2057419Y1195362
X2057419Y1205362
X2047419Y1205362
X2047419Y1195362
X2068539Y1195372
X2068539Y1205372
X1973362Y1195210
X1973362Y1205210
X1984482Y1195220
X1984482Y1205220
X1994482Y1205220
X1994482Y1195220
X2005452Y0603020
X2005452Y0593020
X2015452Y0593020
X2015452Y0603020
X2036452Y0603200
X2036452Y0593200
X2026452Y0593200
X2026452Y0603200
X2047419Y0603162
X2047419Y0593162
X2057419Y0593162
X2057419Y0603162
X2068539Y0593172
X2068539Y0603172
X1973362Y0593010
X1973362Y0603010
X1973362Y0593010
X1994482Y0603020
X1994482Y0593020
X1984482Y0593020
X1984482Y0603020
X1994482Y0593020
X1984482Y0593020
X2005452Y0593020
X2015452Y0593020
X2036452Y0593200
X2026452Y0593200
X2047419Y0593162
X2057419Y0593162
X1973362Y0583010
X1994482Y0583020
X1984482Y0583020
X2005452Y0583020
X2015452Y0583020
X2036452Y0583200
X2026452Y0583200
X2047419Y0583162
X2057419Y0583162
X1973362Y-0009190
X1984482Y-0009180
X1994482Y-0009180
X2015452Y-0009180
X2005452Y-0009180
X2026452Y-0009000
X2036452Y-0009000
X2057419Y-0009038
X2047419Y-0009038
X1973362Y-0019190
X1984482Y-0019180
X1994482Y-0019180
X2015452Y-0019180
X2005452Y-0019180
X2026452Y-0019000
X2036452Y-0019000
X2057419Y-0019038
X2047419Y-0019038
X2078539Y0603172
X2078539Y0593172
X2078539Y1205372
X2078539Y1195372
M00
X0058325Y1679275
X0065000Y1681900
X0054535Y1658447
X0048269Y1672771
X0054478Y1663669
X0053333Y1671862
X0069833Y1678582
X0064410Y1599102
X0064410Y1602502
X0065520Y1615972
X0065120Y1609909
X0057833Y1671809
X0050333Y1613359
X0054333Y1613359
X0059833Y1604359
X0044833Y1656759
X0046994Y1663165
X0050900Y1677775
X0044833Y1659909
X0066906Y1603280
X0054333Y1604359
X0066906Y1598324
X0020188Y1599396
X0028601Y1617541
X0028601Y1637541
X0028601Y1657541
X0028601Y1677541
X0056799Y1520094
X0056799Y1560094
X0056799Y1540094
X0056799Y1536094
X0056799Y1556094
X0056799Y1552094
X0056799Y1548094
X0056799Y1544094
X0056799Y1532094
X0056799Y1528094
X0056799Y1524094
X0010884Y1501693
X0010884Y1521693
X0010884Y1541693
X0010884Y1561693
X0010884Y1581693
X0010884Y1401693
X0010884Y1421693
X0010884Y1441693
X0010884Y1461693
X0010884Y1481693
X0056777Y1314165
X0069485Y1310152
X0069485Y1307152
X0069485Y1304152
X0065240Y1326068
X0065600Y1318588
X0069809Y1336418
X0069809Y1331418
X0069809Y1333918
X0055277Y1326068
X0055177Y1322328
X0043841Y1248688
X0027520Y1245162
X0010884Y1201693
X0010884Y1221693
X0010884Y1241693
X0010884Y1101693
X0010884Y1121693
X0010884Y1141693
X0010884Y1161693
X0010884Y1181693
X0010884Y1001693
X0010884Y1021693
X0010884Y1041693
X0010884Y1061693
X0010884Y1081693
X0010884Y0901693
X0010884Y0921693
X0010884Y0941693
X0010884Y0961693
X0010884Y0981693
X0010884Y0801693
X0010884Y0821693
X0010884Y0841693
X0010884Y0861693
X0010884Y0881693
X0059500Y0738700
X0038470Y0685622
X0038470Y0695622
X0038470Y0690622
X0038470Y0693122
X0038470Y0688122
X0063930Y0739300
X0068315Y0765664
X0045800Y0726874
X0045700Y0724100
X0027300Y0764200
X0034899Y0711400
X0024700Y0765600
X0058658Y0754145
X0064325Y0715674
X0010884Y0701693
X0010884Y0721693
X0010884Y0741693
X0010884Y0781693
X0048400Y0586000
X0026500Y0675862
X0026500Y0672862
X0032720Y0598402
X0033020Y0595232
X0038470Y0680622
X0057595Y0603476
X0038470Y0683122
X0038220Y0592862
X0038220Y0589862
X0031390Y0666595
X0034790Y0666595
X0026615Y0670036
X0038220Y0595862
X0010884Y0661693
X0010884Y0681693
X0010884Y0501693
X0010884Y0521693
X0053406Y0402862
X0068020Y0395222
X0041933Y0395652
X0040940Y0387302
X0039320Y0392269
X0045812Y0451602
X0047618Y0415613
X0049212Y0451602
X0047619Y0418655
X0061171Y0428806
X0045960Y0428806
X0064571Y0428806
X0049360Y0428806
X0062813Y0415750
X0062812Y0412708
X0016420Y0420662
X0063540Y0438802
X0049990Y0449106
X0045034Y0449106
X0064150Y0434972
X0068365Y0443677
X0053800Y0435451
X0054762Y0444993
X0030680Y0438142
X0065349Y0426310
X0071772Y0421746
X0060393Y0426310
X0050138Y0426310
X0053825Y0421746
X0062808Y0418425
X0047619Y0421155
X0045182Y0426310
X0062833Y0410047
X0047618Y0413113
X0049400Y0384392
X0049250Y0396332
X0061250Y0396142
X0061340Y0384362
X0022223Y0388057
X0029962Y0401000
X0029509Y0398132
X0039226Y0395346
X0039410Y0384582
X0036524Y0398013
X0010884Y0401693
X0010884Y0421693
X0010884Y0441693
X0010884Y0461693
X0010884Y0481693
X0043020Y0382942
X0067681Y0360702
X0040000Y0293392
X0062020Y0295952
X0036000Y0295952
X0040000Y0298707
X0035740Y0363337
X0063429Y0360702
X0051114Y0360862
X0062731Y0305426
X0033105Y0304972
X0059322Y0360702
X0033020Y0382822
X0055190Y0360862
X0046834Y0360862
X0042809Y0360862
X0065881Y0305426
X0036255Y0304972
X0041492Y0290637
X0014092Y0287115
X0003010Y0303308
X0010884Y0321693
X0010884Y0341693
X0010884Y0361693
X0010884Y0381693
X0030795Y0213358
X0030795Y0227366
X0033670Y0192862
X0033500Y0200862
X0042500Y0224409
X0024720Y0216362
X0024720Y0224362
X0033670Y0232362
X0033670Y0240362
X0024720Y0232362
X0024720Y0240362
X0017061Y0196368
X0016925Y0203366
X0033670Y0208362
X0026054Y0195148
X0025752Y0203274
X0035600Y0227380
X0024754Y0220220
X0024814Y0236472
X0054920Y0185039
X0003010Y0203308
X0003010Y0223308
X0003010Y0243308
X0003010Y0263308
X0003010Y0283308
X0064870Y0084622
X0061470Y0084622
X0054920Y0177165
X0003010Y0123308
X0003010Y0163308
X0003010Y0183308
X0065648Y0087118
X0060692Y0087118
X0065937Y0028403
X0065937Y0048720
X0061157Y0069340
X0064557Y0069340
X0069379Y0075340
X0071379Y0077836
X0071379Y0072844
X0065335Y0071836
X0065335Y0066844
X0067335Y0069340
X0060379Y0071836
X0060379Y0066844
X0058379Y0069340
X0003010Y0063308
X0017371Y0049388
X0037371Y0049388
X0054593Y0019183
X0069058Y0003010
X0147924Y0028258
X0148784Y0048720
X0127157Y0069340
X0141557Y0075340
X0149157Y0069340
X0164761Y0075340
X0075557Y0075340
X0083157Y0069340
X0097557Y0075340
X0105157Y0069340
X0119557Y0075340
X0130557Y0069340
X0138157Y0075340
X0152557Y0069340
X0161361Y0075340
X0072157Y0075340
X0086557Y0069340
X0094157Y0075340
X0108557Y0069340
X0116157Y0075340
X0117389Y0026474
X0124494Y0019538
X0153255Y0026474
X0160360Y0019538
X0167428Y0026474
X0074869Y0026474
X0081974Y0019538
X0089042Y0026474
X0096147Y0019538
X0103215Y0026474
X0110320Y0019538
X0120789Y0026474
X0127894Y0019538
X0156655Y0026474
X0163760Y0019538
X0170828Y0026474
X0078269Y0026474
X0085374Y0019538
X0092442Y0026474
X0099547Y0019538
X0106615Y0026474
X0113720Y0019538
X0167539Y0075340
X0165539Y0077836
X0160583Y0077836
X0160583Y0072844
X0165539Y0072844
X0144335Y0075340
X0158583Y0075340
X0135379Y0075340
X0142335Y0077836
X0142335Y0072844
X0137379Y0077836
X0137379Y0072844
X0113379Y0075340
X0122335Y0075340
X0120335Y0077836
X0120335Y0072844
X0115379Y0077836
X0115379Y0072844
X0100335Y0075340
X0098335Y0077836
X0098335Y0072844
X0093379Y0077836
X0093379Y0072844
X0091379Y0075340
X0078335Y0075340
X0076335Y0077836
X0076335Y0072844
X0171583Y0071836
X0171583Y0066844
X0169583Y0069340
X0153335Y0071836
X0153335Y0066844
X0148379Y0071836
X0148379Y0066844
X0155335Y0069340
X0146379Y0069340
X0131335Y0071836
X0131335Y0066844
X0133335Y0069340
X0126379Y0071836
X0126379Y0066844
X0124379Y0069340
X0109335Y0071836
X0109335Y0066844
X0104379Y0071836
X0104379Y0066844
X0111335Y0069340
X0102379Y0069340
X0087335Y0071836
X0087335Y0066844
X0082379Y0071836
X0082379Y0066844
X0089335Y0069340
X0080379Y0069340
X0165579Y0040020
X0165579Y0048720
X0151405Y0040020
X0151405Y0048720
X0158492Y0040020
X0158492Y0048720
X0129713Y0040020
X0129713Y0048720
X0115539Y0040020
X0115539Y0048720
X0122626Y0040020
X0122626Y0048720
X0101366Y0040020
X0101366Y0048720
X0108453Y0040020
X0108453Y0048720
X0080106Y0040020
X0080106Y0048720
X0087193Y0040020
X0087193Y0048720
X0094279Y0040020
X0094279Y0048720
X0073020Y0040020
X0073020Y0048720
X0165579Y0028406
X0165579Y0037106
X0164650Y0025974
X0171606Y0023978
X0166650Y0023978
X0151405Y0028406
X0151405Y0037106
X0158492Y0028406
X0158492Y0037106
X0159433Y0025974
X0150477Y0025974
X0157433Y0023978
X0152477Y0023978
X0129713Y0028406
X0129713Y0037106
X0115539Y0028406
X0115539Y0037106
X0122626Y0028406
X0122626Y0037106
X0123567Y0025974
X0114611Y0025974
X0116611Y0023978
X0121567Y0023978
X0101366Y0028406
X0101366Y0037106
X0108453Y0028406
X0108453Y0037106
X0109393Y0025974
X0100437Y0025974
X0107393Y0023978
X0102437Y0023978
X0080106Y0028406
X0080106Y0037106
X0087193Y0028406
X0087193Y0037106
X0094279Y0028406
X0094279Y0037106
X0081047Y0025974
X0095220Y0025974
X0086264Y0025974
X0093220Y0023978
X0088264Y0023978
X0073020Y0028406
X0073020Y0037106
X0072091Y0025974
X0074091Y0023978
X0079047Y0023978
X0171755Y0019538
X0166538Y0019538
X0164538Y0022034
X0164538Y0017042
X0157582Y0019538
X0159582Y0022034
X0159582Y0017042
X0130672Y0019538
X0128672Y0022034
X0128672Y0017042
X0121716Y0019538
X0116498Y0019538
X0123716Y0022034
X0123716Y0017042
X0114498Y0022034
X0114498Y0017042
X0107542Y0019538
X0102325Y0019538
X0109542Y0022034
X0109542Y0017042
X0100325Y0022034
X0100325Y0017042
X0093369Y0019538
X0088152Y0019538
X0079196Y0019538
X0095369Y0022034
X0095369Y0017042
X0086152Y0022034
X0086152Y0017042
X0081196Y0022034
X0081196Y0017042
X0089058Y0003010
X0109058Y0003010
X0129058Y0003010
X0149058Y0003010
X0169058Y0003010
X0139720Y0179162
X0141520Y0181462
X0136301Y0179095
X0145720Y0206362
X0145720Y0202862
X0133590Y0212382
X0145720Y0186462
X0143470Y0184012
X0087845Y0278798
X0118920Y0278875
X0116920Y0207462
X0115850Y0186362
X0129375Y0274800
X0129394Y0278875
X0077165Y0278798
X0113490Y0216596
X0113400Y0232128
X0143340Y0204622
X0147901Y0188852
X0090700Y0282762
X0085788Y0240157
X0085960Y0224409
X0086490Y0208661
X0086490Y0200787
X0122000Y0207362
X0161670Y0344542
X0164830Y0344542
X0159170Y0344542
X0156670Y0344542
X0158110Y0376172
X0154220Y0375682
X0119920Y0379362
X0087620Y0285321
X0087845Y0295798
X0087820Y0302821
X0119220Y0306236
X0129394Y0306236
X0110937Y0302854
X0110937Y0285495
X0087520Y0382219
X0077220Y0381522
X0077220Y0379022
X0077165Y0303262
X0077165Y0286262
X0077165Y0295798
X0087654Y0376026
X0114087Y0302854
X0090700Y0300262
X0114087Y0285495
X0081505Y0447377
X0132490Y0420062
X0160090Y0397470
X0160090Y0391170
X0163926Y0435383
X0119457Y0388071
X0152826Y0434362
X0107301Y0388071
X0152826Y0439397
X0119457Y0392071
X0163926Y0439397
X0107200Y0393562
X0163926Y0430883
X0164000Y0415362
X0164000Y0420362
X0163926Y0425383
X0135220Y0397071
X0163926Y0443319
X0085826Y0428319
X0094439Y0450081
X0079400Y0482862
X0132833Y0480238
X0083320Y0445212
X0153360Y0449112
X0138042Y0480238
X0084410Y0438519
X0156306Y0449045
X0087520Y0391391
X0087520Y0395865
X0072610Y0444762
X0072610Y0441262
X0075516Y0424319
X0075516Y0420319
X0072981Y0466385
X0159125Y0448664
X0127206Y0480216
X0082661Y0449604
X0149371Y0443383
X0149371Y0435383
X0149371Y0431383
X0149371Y0439383
X0075490Y0432519
X0075516Y0436519
X0149371Y0427383
X0149371Y0419383
X0149371Y0423383
X0101317Y0431727
X0085826Y0420319
X0085826Y0424319
X0163900Y0409362
X0171180Y0401885
X0140974Y0399385
X0140974Y0401885
X0114507Y0404571
X0101720Y0400862
X0104220Y0400862
X0140974Y0396885
X0125007Y0396071
X0125007Y0384071
X0125007Y0388071
X0125007Y0392071
X0087520Y0386502
X0152470Y0495383
X0074550Y0487812
X0138408Y0507366
X0077000Y0485362
X0132600Y0540472
X0132600Y0537072
X0112393Y0528188
X0115793Y0528188
X0154647Y0521783
X0138878Y0512550
X0160000Y0510052
X0139153Y0516453
X0149504Y0519881
X0116171Y0485041
X0131295Y0487822
X0150113Y0488487
X0135006Y0487753
X0131737Y0496295
X0136982Y0497090
X0141220Y0498810
X0165176Y0500782
X0141329Y0510487
X0153737Y0514893
X0150800Y0512021
X0116411Y0497707
X0105587Y0520727
X0110464Y0505374
X0110689Y0498271
X0141462Y0507600
X0141325Y0503806
X0112480Y0507792
X0099773Y0515606
X0124124Y0495883
X0125013Y0491829
X0110060Y0515279
X0133160Y0532002
X0129762Y0531942
X0112483Y0510637
X0099880Y0526300
X0125070Y0486736
X0118652Y0528860
X0149512Y0514810
X0149472Y0506810
X0149557Y0494353
X0104875Y0490980
X0101983Y0518100
X0107419Y0487807
X0171293Y0577790
X0171293Y0575189
X0171293Y0572689
X0102384Y0505374
X0163132Y0493299
X0102060Y0493578
X0094811Y0510173
X0113597Y0488434
X0102359Y0497374
X0102334Y0500628
X0102152Y0509374
X0111087Y0520052
X0102152Y0513374
X0117597Y0488434
X0120225Y0510368
X0120225Y0504368
X0126225Y0504368
X0120225Y0516368
X0126225Y0516368
X0115060Y0547506
X0119087Y0547506
X0123257Y0547506
X0142166Y0490835
X0132225Y0510368
X0132225Y0504368
X0132401Y0516368
X0152171Y0490615
X0149486Y0498810
X0149472Y0502810
X0149518Y0522810
X0162750Y0512502
X0166986Y0575918
X0161267Y0503143
X0151378Y0526924
X0086459Y0628246
X0089859Y0628246
X0083208Y0646436
X0091078Y0649584
X0083165Y0652564
X0091027Y0643276
X0080300Y0641862
X0074559Y0667814
X0080135Y0667933
X0103397Y0667272
X0099021Y0663732
X0095860Y0659622
X0080123Y0664031
X0118019Y0661371
X0131740Y0640103
X0122575Y0671930
X0131600Y0646861
X0124431Y0649570
X0122280Y0651934
X0122329Y0654660
X0121400Y0638062
X0095725Y0654540
X0125890Y0644163
X0107045Y0661917
X0102269Y0634466
X0082961Y0657111
X0131330Y0665740
X0133467Y0634531
X0084470Y0668702
X0120440Y0633347
X0117750Y0633232
X0114540Y0633032
X0111920Y0632922
X0110374Y0630879
X0107489Y0630917
X0106110Y0633732
X0083250Y0665428
X0129600Y0669400
X0074340Y0663422
X0083100Y0649762
X0080460Y0655672
X0087565Y0670441
X0108909Y0642926
X0102909Y0655102
X0102909Y0642926
X0102909Y0648926
X0108909Y0654926
X0114909Y0642926
X0114909Y0648926
X0114909Y0654926
X0127738Y0659226
X0127313Y0649765
X0118021Y0669409
X0114021Y0669409
X0134205Y0643603
X0130057Y0636103
X0130067Y0650213
X0128275Y0665515
X0128193Y0662015
X0080241Y0659011
X0085877Y0759275
X0081966Y0759246
X0102420Y0697262
X0081285Y0689804
X0082357Y0737803
X0084623Y0741249
X0073759Y0759246
X0073759Y0754726
X0091610Y0721414
X0097295Y0699786
X0095849Y0716358
X0086433Y0688160
X0083004Y0705141
X0102060Y0692100
X0163578Y0706835
X0163626Y0721660
X0161078Y0706835
X0161126Y0721660
X0142826Y0721660
X0140326Y0721660
X0140278Y0706835
X0142778Y0706835
X0140254Y0698811
X0142754Y0698811
X0140460Y0690807
X0142960Y0690807
X0150877Y0757969
X0110527Y0758869
X0124737Y0738726
X0118737Y0738726
X0121737Y0738726
X0121737Y0735726
X0118737Y0735726
X0124737Y0735726
X0096626Y0736187
X0085095Y0722164
X0078080Y0701832
X0102120Y0688650
X0093547Y0692260
X0076365Y0699244
X0072315Y0717414
X0076565Y0717949
X0073865Y0763164
X0079451Y0699517
X0094473Y0698926
X0085835Y0718049
X0079635Y0717949
X0081225Y0715854
X0085165Y0714394
X0087865Y0714394
X0082735Y0717949
X0093295Y0762019
X0098134Y0722501
X0132967Y0760525
X0150155Y0690807
X0149861Y0698831
X0147435Y0690807
X0147141Y0698811
X0147079Y0721660
X0149669Y0721660
X0149621Y0706835
X0147031Y0706835
X0156469Y0721660
X0153879Y0721660
X0153965Y0706816
X0156685Y0706836
X0084035Y0697604
X0120220Y1324662
X0123220Y1324662
X0153817Y1333893
X0151217Y1333893
X0156417Y1333843
X0153817Y1336393
X0151217Y1336393
X0156417Y1336343
X0156477Y1339183
X0153877Y1339183
X0151277Y1339183
X0170907Y1339233
X0170877Y1344383
X0170877Y1346883
X0170877Y1349383
X0170877Y1341883
X0170877Y1336383
X0170877Y1333783
X0153877Y1341883
X0151277Y1341883
X0156477Y1341883
X0153877Y1344383
X0151277Y1344383
X0156477Y1344383
X0156477Y1349383
X0156477Y1346883
X0153877Y1349383
X0151277Y1349383
X0153877Y1346883
X0151277Y1346883
X0102485Y1315652
X0102485Y1313152
X0102485Y1310152
X0102485Y1318152
X0099485Y1315652
X0099485Y1313152
X0099485Y1310152
X0096485Y1313152
X0096485Y1310152
X0096485Y1315652
X0096485Y1318152
X0099485Y1318152
X0105475Y1315722
X0105475Y1313222
X0105475Y1310222
X0105475Y1318222
X0108465Y1315792
X0108465Y1313292
X0108465Y1310292
X0108465Y1318292
X0096485Y1307152
X0099485Y1307152
X0102485Y1307152
X0096485Y1304152
X0099485Y1304152
X0102485Y1304152
X0105475Y1307222
X0105475Y1304222
X0108465Y1307292
X0108465Y1304292
X0093485Y1313152
X0093485Y1310152
X0093485Y1315652
X0093485Y1318152
X0081485Y1304152
X0084485Y1304152
X0093485Y1307152
X0090485Y1304152
X0087485Y1304152
X0093485Y1304152
X0075485Y1310152
X0075485Y1313152
X0072485Y1310152
X0072485Y1313152
X0075485Y1316152
X0075485Y1307152
X0072485Y1307152
X0078485Y1304152
X0075485Y1304152
X0072485Y1304152
X0096809Y1342738
X0096809Y1348238
X0096809Y1345238
X0096809Y1340238
X0090809Y1342738
X0090809Y1345238
X0090809Y1348238
X0094209Y1345238
X0094209Y1348238
X0094209Y1342738
X0087809Y1342738
X0087809Y1345238
X0087809Y1348238
X0084809Y1348238
X0081809Y1345238
X0081809Y1348238
X0084809Y1342738
X0081809Y1342738
X0084809Y1345238
X0094209Y1340238
X0090809Y1340238
X0087809Y1340238
X0084809Y1340238
X0081809Y1340238
X0094209Y1337738
X0075859Y1345138
X0075859Y1348138
X0078977Y1348025
X0079009Y1345238
X0079009Y1342738
X0075909Y1342438
X0072987Y1342535
X0073059Y1345138
X0073027Y1347925
X0075909Y1339938
X0079009Y1340238
X0072909Y1339938
X0075809Y1336418
X0075809Y1331418
X0075809Y1333918
X0072809Y1336418
X0072809Y1331418
X0072809Y1333918
X0120267Y1327697
X0141470Y1359100
X0159898Y1360790
X0154477Y1360797
X0148663Y1381207
X0151163Y1381207
X0151163Y1378607
X0148663Y1378607
X0164898Y1360790
X0162398Y1360790
X0168592Y1400005
X0166262Y1399255
X0170922Y1399255
X0155858Y1409390
X0152684Y1403451
X0162257Y1406594
X0149568Y1397695
X0164000Y1408862
X0149568Y1395145
X0155858Y1406669
X0159858Y1409361
X0147307Y1404745
X0140142Y1396275
X0140142Y1392545
X0165500Y1440362
X0160530Y1437754
X0160530Y1435124
X0160530Y1426624
X0160530Y1429124
X0160530Y1424124
X0160530Y1432124
X0160490Y1421454
X0155030Y1437754
X0157530Y1437754
X0155030Y1435124
X0157530Y1435124
X0157530Y1426624
X0155030Y1429124
X0155030Y1426624
X0157530Y1429124
X0155030Y1424124
X0157530Y1424124
X0155030Y1432124
X0157530Y1432124
X0154990Y1421454
X0157490Y1421454
X0144263Y1412275
X0148663Y1383807
X0151163Y1386407
X0148663Y1386407
X0155718Y1387393
X0158318Y1387393
X0155718Y1384286
X0158318Y1384286
X0151163Y1383807
X0160201Y1394132
X0157731Y1394132
X0157731Y1399732
X0160201Y1399732
X0152806Y1414175
X0166118Y1384286
X0169318Y1384286
X0160918Y1387393
X0163518Y1387393
X0163518Y1384286
X0160918Y1384286
X0162631Y1394132
X0162631Y1399732
X0161118Y1390500
X0163718Y1390500
X0162693Y1411529
X0171262Y1443390
X0153600Y1505600
X0076369Y1507456
X0168110Y1518014
X0079769Y1507456
X0164710Y1518014
X0170666Y1569968
X0074218Y1572504
X0167266Y1569968
X0077618Y1572504
X0149712Y1569525
X0105651Y1576504
X0102251Y1576504
X0146312Y1569525
X0092664Y1507611
X0148938Y1517374
X0089264Y1507611
X0145538Y1517374
X0088520Y1484482
X0088520Y1494982
X0112270Y1518907
X0078120Y1518836
X0078120Y1515436
X0075922Y1562374
X0075922Y1558974
X0099750Y1561978
X0099750Y1565378
X0090998Y1515537
X0090998Y1518937
X0088520Y1487982
X0088520Y1491482
X0170570Y1509250
X0157441Y1581932
X0091500Y1567069
X0076680Y1530482
X0099274Y1529169
X0072774Y1546519
X0096570Y1546187
X0087500Y1567069
X0147067Y1545985
X0129586Y1553759
X0129627Y1556360
X0117707Y1553759
X0112749Y1556594
X0112749Y1552594
X0112749Y1528594
X0112749Y1532594
X0090713Y1581852
X0146390Y1504240
X0092071Y1492888
X0078415Y1570008
X0073429Y1570008
X0100451Y1574704
X0107451Y1574704
X0075922Y1556474
X0075922Y1564874
X0099750Y1559478
X0099716Y1567878
X0171456Y1572464
X0166476Y1572464
X0159107Y1571364
X0145522Y1572021
X0150502Y1572021
X0096251Y1577532
X0084048Y1578008
X0140104Y1560136
X0129670Y1563160
X0112749Y1560594
X0112749Y1564594
X0153138Y1549032
X0161374Y1549073
X0161321Y1540858
X0153271Y1540961
X0112749Y1536594
X0112749Y1548594
X0112749Y1544594
X0112749Y1540594
X0127366Y1547935
X0127366Y1541874
X0091538Y1539399
X0081038Y1536899
X0072774Y1549669
X0163920Y1520510
X0168900Y1520510
X0158570Y1520981
X0154581Y1520981
X0112749Y1524594
X0127366Y1535855
X0099274Y1526019
X0090998Y1521437
X0078120Y1521336
X0149728Y1514878
X0144748Y1514878
X0090998Y1513037
X0088459Y1510107
X0093544Y1510099
X0084274Y1517619
X0080649Y1509944
X0078120Y1512936
X0075564Y1509952
X0074100Y1613300
X0085800Y1613300
X0081900Y1613300
X0086030Y1683092
X0158335Y1614452
X0152026Y1614138
X0128195Y1674362
X0123230Y1597350
X0124795Y1681846
X0104430Y1628012
X0119500Y1622380
X0073833Y1674252
X0155180Y1619872
X0098738Y1605867
X0100620Y1596367
X0116798Y1589352
X0103902Y1584337
X0104318Y1589352
X0100020Y1615821
X0077833Y1678902
X0081833Y1674526
X0099645Y1663217
X0099600Y1668332
X0077040Y1601102
X0088333Y1661334
X0090407Y1656672
X0104400Y1632385
X0104318Y1637862
X0101500Y1604400
X0081008Y1589872
X0129533Y1637862
X0130533Y1622321
X0129813Y1604367
X0117220Y1683437
X0125033Y1589352
X0090698Y1642362
X0090788Y1619821
X0090698Y1630362
X0090788Y1601867
X0090788Y1615821
X0090713Y1597867
X0110200Y1605200
X0127195Y1670362
X0117220Y1680287
X0116798Y1635303
X0104318Y1641075
X0090698Y1634362
X0090698Y1638362
X0104318Y1622380
X0084700Y1627000
X0090788Y1623821
X0116798Y1617262
X0104318Y1603690
X0090788Y1605867
X0090788Y1611821
X0116798Y1598572
X0116798Y1586288
X0104318Y1592304
X0090713Y1593867
X0090713Y1589852
X0090713Y1585852
X0155145Y1713517
X0099980Y1698921
X0099980Y1687921
X0127195Y1704362
X0156070Y1695702
X0127195Y1700362
X0096420Y1693803
X0125720Y1719262
X0148145Y1701862
X0144520Y1717562
X0161310Y1708022
X0137852Y1726572
X0169777Y1726517
X0163060Y1717017
X0164920Y1712017
X0134557Y1722778
X0117426Y1726622
X0145745Y1712362
X0141642Y1717592
X0137420Y1708362
X0123394Y1723472
X0125082Y1727092
X0127195Y1696362
X0114645Y1698862
X0086245Y1694362
X0154803Y1708532
X0166661Y1721211
X0139080Y1731398
X0117255Y1730422
X0144854Y1702389
X0166761Y1732967
X0155100Y1723262
X0138492Y1717592
X0166529Y1707678
X0127195Y1708362
X0127195Y1692362
X0127195Y1688362
X0117795Y1698862
X0099980Y1696052
X0099980Y1685362
X0094220Y1686622
X0081833Y1689162
X0086245Y1690362
X0077833Y1689162
X0073832Y1689362
X0092895Y1737108
X0112895Y1737108
X0132895Y1737108
X0152895Y1737108
X0178142Y1720652
X0188794Y1725092
X0208295Y1703362
X0214120Y1713462
X0196010Y1709017
X0172962Y1721234
X0195590Y1714517
X0178226Y1726517
X0199050Y1726431
X0212120Y1703062
X0210593Y1714017
X0204600Y1733022
X0193293Y1722197
X0187542Y1729092
X0183822Y1720517
X0192529Y1728947
X0205582Y1700867
X0193410Y1711606
X0212684Y1720307
X0196443Y1722197
X0172895Y1737108
X0192895Y1737108
X0212895Y1737108
X0252895Y1737108
X0209820Y1631142
X0208115Y1624217
X0203120Y1624782
X0172099Y1588141
X0269957Y1602380
X0257897Y1602380
X0245837Y1602380
X0233777Y1602380
X0221717Y1602380
X0206257Y1602380
X0197597Y1602380
X0266557Y1602380
X0254497Y1602380
X0242437Y1602380
X0230377Y1602380
X0218317Y1602380
X0209657Y1602380
X0194197Y1602380
X0269957Y1614292
X0257897Y1614292
X0245837Y1614292
X0233777Y1614292
X0221717Y1614292
X0206257Y1614292
X0197597Y1614292
X0266557Y1614292
X0254497Y1614292
X0242437Y1614292
X0230377Y1614292
X0218317Y1614292
X0209657Y1614292
X0194197Y1614292
X0264657Y1590094
X0192297Y1590094
X0204357Y1590094
X0216417Y1590094
X0228477Y1590094
X0240537Y1590094
X0252597Y1590094
X0261257Y1590094
X0188897Y1590094
X0200957Y1590094
X0213017Y1590094
X0225077Y1590094
X0237137Y1590094
X0249197Y1590094
X0207229Y1631181
X0265779Y1611796
X0265779Y1604876
X0270735Y1604876
X0270735Y1611796
X0265779Y1616788
X0270735Y1616788
X0258675Y1616788
X0258675Y1611796
X0258675Y1604876
X0253719Y1616788
X0253719Y1611796
X0253719Y1604876
X0241659Y1611796
X0246615Y1611796
X0241659Y1604876
X0246615Y1604876
X0246615Y1616788
X0241659Y1616788
X0234555Y1616788
X0229599Y1616788
X0234555Y1611796
X0234555Y1604876
X0229599Y1611796
X0229599Y1604876
X0217539Y1611796
X0217539Y1604876
X0222495Y1611796
X0222495Y1604876
X0217539Y1616788
X0222495Y1616788
X0210435Y1616788
X0210435Y1604876
X0210435Y1611796
X0205479Y1616788
X0205479Y1604876
X0205479Y1611796
X0198375Y1616788
X0198375Y1604876
X0193419Y1604876
X0198375Y1611796
X0193419Y1611796
X0193419Y1616788
X0265779Y1599790
X0270735Y1599790
X0258675Y1599884
X0265435Y1587598
X0260479Y1587598
X0265435Y1592590
X0260479Y1592590
X0253719Y1599884
X0241659Y1599884
X0246615Y1599884
X0253375Y1592590
X0248419Y1592590
X0253375Y1587598
X0248419Y1587598
X0234555Y1599884
X0229599Y1599884
X0241315Y1587598
X0241315Y1592590
X0236359Y1587598
X0236359Y1592590
X0229255Y1592590
X0229255Y1587598
X0217539Y1599884
X0222495Y1599884
X0210435Y1599884
X0224299Y1592590
X0224299Y1587598
X0217195Y1592590
X0212239Y1592590
X0217195Y1587598
X0212239Y1587598
X0205479Y1599884
X0193419Y1599884
X0198375Y1599884
X0205135Y1587598
X0200179Y1587598
X0205135Y1592590
X0200179Y1592590
X0193075Y1587598
X0193075Y1592590
X0188119Y1587598
X0188119Y1592590
X0176793Y1585173
X0173331Y1579399
X0187400Y1568132
X0189600Y1566300
X0185895Y1557875
X0264657Y1578182
X0192297Y1578182
X0204357Y1578182
X0216417Y1578182
X0228477Y1578182
X0240537Y1578182
X0252597Y1578182
X0261257Y1578182
X0188897Y1578182
X0200957Y1578182
X0213017Y1578182
X0225077Y1578182
X0237137Y1578182
X0249197Y1578182
X0192600Y1557360
X0195966Y1542863
X0265435Y1575592
X0260479Y1575592
X0265435Y1580678
X0260479Y1580678
X0253375Y1580678
X0248419Y1580678
X0253375Y1575686
X0248419Y1575686
X0241315Y1575686
X0241315Y1580678
X0236359Y1575686
X0236359Y1580678
X0229255Y1580678
X0229255Y1575686
X0224299Y1580678
X0224299Y1575686
X0212239Y1575686
X0217195Y1575686
X0217195Y1580678
X0212239Y1580678
X0205135Y1580678
X0200179Y1580678
X0205135Y1575686
X0200179Y1575686
X0193075Y1575686
X0193075Y1580678
X0188119Y1575686
X0188119Y1580678
X0185895Y1552875
X0185895Y1548487
X0185895Y1544029
X0185895Y1539723
X0185895Y1535462
X0212035Y1405799
X0216554Y1405064
X0216554Y1402164
X0216554Y1399264
X0214101Y1401169
X0212035Y1402899
X0214201Y1404169
X0211395Y1400005
X0204405Y1399255
X0209065Y1399255
X0206735Y1400005
X0186075Y1432924
X0183075Y1432924
X0186075Y1427924
X0186075Y1425424
X0186075Y1430424
X0183075Y1427924
X0183075Y1425424
X0183075Y1430424
X0180510Y1423278
X0177510Y1423278
X0183165Y1422589
X0186135Y1419784
X0177510Y1420258
X0180510Y1420258
X0183135Y1419784
X0186165Y1422589
X0178458Y1405069
X0178458Y1402169
X0178458Y1399269
X0180977Y1396173
X0173252Y1400005
X0173892Y1405649
X0173892Y1402749
X0176258Y1400669
X0176358Y1403669
X0173727Y1448734
X0220869Y1454725
X0193941Y1409750
X0190827Y1403451
X0187711Y1397670
X0200492Y1406686
X0219587Y1439402
X0200797Y1409605
X0219587Y1443402
X0187711Y1395170
X0173727Y1452134
X0217469Y1454725
X0193941Y1407029
X0198001Y1409361
X0219587Y1435402
X0188211Y1406691
X0172262Y1387409
X0172262Y1384302
X0172231Y1390532
X0177421Y1383997
X0183283Y1385387
X0180672Y1385387
X0185633Y1384427
X0180672Y1387987
X0185633Y1387027
X0183283Y1387987
X0188233Y1384427
X0188233Y1387027
X0182653Y1404535
X0185643Y1413945
X0192767Y1413725
X0207461Y1384286
X0204261Y1384286
X0199061Y1387393
X0196461Y1387393
X0193861Y1387393
X0201661Y1387393
X0199061Y1384286
X0196461Y1384286
X0193861Y1384286
X0201661Y1384286
X0200774Y1394132
X0198344Y1394132
X0195874Y1394132
X0200774Y1399732
X0198344Y1399732
X0195874Y1399732
X0199261Y1390500
X0201861Y1390500
X0201071Y1412173
X0214425Y1384058
X0217133Y1384055
X0210405Y1387409
X0210405Y1384302
X0218960Y1388312
X0210374Y1390532
X0219752Y1398599
X0219752Y1401999
X0219752Y1405499
X0224077Y1416975
X0224137Y1414345
X0224350Y1432032
X0173507Y1339233
X0176107Y1339233
X0211607Y1339263
X0214207Y1339263
X0194547Y1339263
X0209007Y1339263
X0189347Y1339263
X0191947Y1339263
X0211577Y1349383
X0211577Y1346883
X0211577Y1344383
X0214177Y1344383
X0214177Y1346883
X0214177Y1349383
X0211577Y1341883
X0214177Y1341883
X0211577Y1333783
X0214177Y1333783
X0211577Y1336383
X0214177Y1336383
X0194577Y1341883
X0208977Y1349383
X0208977Y1346883
X0208977Y1344383
X0194577Y1344383
X0194577Y1346883
X0194577Y1349383
X0208977Y1341883
X0194577Y1336383
X0194577Y1333783
X0208977Y1333783
X0208977Y1336383
X0189377Y1341883
X0191977Y1341883
X0189377Y1344383
X0191977Y1344383
X0191977Y1346883
X0189377Y1346883
X0191977Y1349383
X0189377Y1349383
X0191977Y1336383
X0189377Y1336383
X0191977Y1333783
X0189377Y1333783
X0176077Y1349383
X0176077Y1346883
X0176077Y1344383
X0173477Y1344383
X0173477Y1346883
X0173477Y1349383
X0173477Y1341883
X0176077Y1341883
X0173477Y1336383
X0176077Y1336383
X0173477Y1333783
X0176077Y1333783
X0172807Y1360797
X0174932Y1381397
X0174932Y1378797
X0192620Y1360797
X0181403Y1361115
X0184215Y1361072
X0177532Y1381397
X0183283Y1382787
X0180672Y1382787
X0185633Y1381827
X0177532Y1378797
X0183283Y1380187
X0180672Y1380187
X0185633Y1379227
X0188233Y1381827
X0188233Y1379227
X0200941Y1360790
X0198041Y1360790
X0203441Y1360790
X0211350Y1360797
X0215824Y1361199
X0218175Y1378958
X0215675Y1378958
X0213075Y1378958
X0218175Y1381558
X0215675Y1381558
X0213075Y1381558
X0230864Y1254295
X0251187Y1255025
X0259510Y0757822
X0245487Y0755435
X0197086Y0686326
X0200735Y0696469
X0200735Y0698969
X0198235Y0696469
X0198235Y0698969
X0195735Y0696469
X0207140Y0693636
X0203179Y0693626
X0203199Y0690006
X0207129Y0690027
X0271057Y0762425
X0271057Y0765525
X0238940Y0716652
X0242460Y0716652
X0216842Y0756865
X0265997Y0747535
X0269600Y0715792
X0211602Y0756855
X0220033Y0756844
X0203602Y0756855
X0195602Y0756839
X0191602Y0756839
X0188978Y0756855
X0185835Y0757057
X0271570Y0746422
X0266700Y0730962
X0264000Y0726262
X0270100Y0727262
X0194196Y0687061
X0259449Y0696277
X0259389Y0698827
X0259419Y0693767
X0248300Y0703862
X0254219Y0693767
X0254249Y0696277
X0256819Y0693767
X0256789Y0698827
X0256849Y0696277
X0251619Y0693767
X0254189Y0698827
X0251649Y0696277
X0251589Y0698827
X0249019Y0693767
X0248989Y0698827
X0253057Y0755345
X0268331Y0738029
X0186720Y0734862
X0180720Y0734862
X0183720Y0734862
X0183720Y0737862
X0180720Y0737862
X0186720Y0737862
X0227430Y0719772
X0270322Y0740207
X0191976Y0684326
X0189800Y0705062
X0207834Y0684006
X0203044Y0684036
X0203043Y0686483
X0207856Y0686443
X0194858Y0684348
X0206720Y0731862
X0199720Y0732862
X0199220Y0739362
X0199602Y0756855
X0207602Y0756855
X0214100Y0684376
X0214100Y0690376
X0214100Y0687376
X0211348Y0685287
X0211348Y0688087
X0219306Y0698138
X0219306Y0700738
X0221906Y0700738
X0221906Y0698138
X0224506Y0700738
X0224506Y0698138
X0214100Y0693576
X0211348Y0693587
X0211348Y0690787
X0211220Y0740362
X0227106Y0700738
X0227106Y0698138
X0224900Y0713293
X0203660Y0731802
X0201220Y0736662
X0205220Y0736562
X0209720Y0731862
X0207140Y0738462
X0204610Y0605097
X0204610Y0639097
X0184151Y0599603
X0186796Y0599635
X0179151Y0599603
X0181651Y0599603
X0173878Y0599747
X0176651Y0599603
X0208292Y0664571
X0203892Y0662471
X0202492Y0664571
X0202262Y0660305
X0206892Y0662371
X0205162Y0660305
X0205392Y0664571
X0208056Y0659665
X0208806Y0652675
X0208806Y0657335
X0208056Y0655005
X0205392Y0630571
X0205162Y0626305
X0206892Y0628371
X0208292Y0630571
X0202262Y0626305
X0202492Y0630571
X0203892Y0628471
X0208056Y0625665
X0208806Y0623335
X0208056Y0621005
X0208806Y0618675
X0205392Y0596571
X0206892Y0594371
X0208292Y0596571
X0202492Y0596571
X0203892Y0594471
X0205162Y0592305
X0202262Y0592305
X0208806Y0584675
X0208056Y0587005
X0208806Y0589335
X0208056Y0591665
X0184151Y0594163
X0181651Y0594163
X0179151Y0594163
X0184151Y0596883
X0186796Y0596915
X0186796Y0594195
X0179151Y0596883
X0181651Y0596883
X0173878Y0594307
X0173878Y0597027
X0176651Y0594163
X0176651Y0596883
X0193332Y0678195
X0198336Y0608271
X0201622Y0615009
X0210391Y0601981
X0200654Y0612271
X0199164Y0616481
X0201392Y0608271
X0202338Y0602746
X0268965Y0626115
X0266465Y0626115
X0261465Y0626115
X0263965Y0626115
X0268995Y0611055
X0269025Y0623565
X0268995Y0621055
X0266495Y0611055
X0266525Y0623565
X0266495Y0621055
X0261495Y0611055
X0263995Y0611055
X0264025Y0623565
X0261525Y0623565
X0263995Y0621055
X0261495Y0621055
X0269025Y0603495
X0268995Y0594625
X0268935Y0597175
X0269055Y0608505
X0269025Y0605995
X0266525Y0603495
X0264025Y0603495
X0261525Y0603495
X0266495Y0594625
X0266435Y0597175
X0266555Y0608505
X0266525Y0605995
X0263935Y0597175
X0263995Y0594625
X0261495Y0594625
X0261435Y0597175
X0261555Y0608505
X0264055Y0608505
X0261525Y0605995
X0264025Y0605995
X0268965Y0592115
X0269025Y0589565
X0266465Y0592115
X0266525Y0589565
X0263965Y0592115
X0264025Y0589565
X0261525Y0589565
X0261465Y0592115
X0257643Y0630820
X0255043Y0630820
X0255043Y0628220
X0257643Y0628220
X0256855Y0623265
X0254355Y0623265
X0251855Y0623265
X0256855Y0603495
X0254385Y0608805
X0256885Y0608805
X0257643Y0596820
X0255043Y0596820
X0255043Y0594220
X0257643Y0594220
X0251885Y0608805
X0256855Y0605995
X0251855Y0589235
X0256855Y0589235
X0254355Y0589235
X0198495Y0669487
X0212891Y0601981
X0198420Y0672662
X0212891Y0635981
X0200018Y0677492
X0196049Y0678195
X0259019Y0675567
X0259049Y0678077
X0248649Y0678077
X0251249Y0678077
X0251219Y0675567
X0256449Y0678077
X0256419Y0675567
X0253849Y0678077
X0253819Y0675567
X0198336Y0642271
X0201622Y0649009
X0210391Y0635981
X0200654Y0646271
X0199164Y0650481
X0201392Y0642271
X0268965Y0660115
X0266465Y0660115
X0263965Y0660115
X0261465Y0660115
X0269055Y0642505
X0268995Y0645055
X0269025Y0657565
X0268995Y0655055
X0266555Y0642505
X0266495Y0645055
X0266525Y0657565
X0266495Y0655055
X0261555Y0642505
X0261495Y0645055
X0264055Y0642505
X0263995Y0645055
X0264025Y0657565
X0261525Y0657565
X0263995Y0655055
X0261495Y0655055
X0269025Y0637495
X0266525Y0637495
X0264025Y0637495
X0269025Y0639995
X0266525Y0639995
X0261525Y0637495
X0264025Y0639995
X0261525Y0639995
X0257643Y0664820
X0255043Y0664820
X0255043Y0662220
X0257643Y0662220
X0256855Y0657265
X0254355Y0657265
X0251885Y0642805
X0251855Y0657265
X0254385Y0642805
X0256885Y0642805
X0256855Y0637495
X0256855Y0639995
X0202338Y0636746
X0207620Y0671262
X0210320Y0671262
X0190977Y0669718
X0190800Y0675662
X0194059Y0604901
X0197423Y0601496
X0208312Y0612605
X0208312Y0610125
X0208312Y0615085
X0194515Y0617433
X0195888Y0615071
X0197423Y0635496
X0194059Y0638901
X0208312Y0646605
X0208312Y0644125
X0208312Y0649085
X0195888Y0649071
X0194515Y0651433
X0205320Y0667562
X0203237Y0681549
X0207824Y0681560
X0223775Y0584531
X0220652Y0590675
X0223759Y0590675
X0223775Y0587731
X0217556Y0590575
X0223403Y0594220
X0223403Y0596820
X0221464Y0602113
X0224064Y0602113
X0223775Y0608131
X0220668Y0608131
X0223775Y0621731
X0220668Y0615931
X0223775Y0610731
X0223775Y0613331
X0223775Y0615931
X0220668Y0613331
X0220668Y0610731
X0223775Y0618531
X0220652Y0624675
X0223759Y0624675
X0217556Y0624575
X0217561Y0613531
X0217561Y0616131
X0213912Y0610125
X0213912Y0615085
X0213912Y0612605
X0221464Y0636113
X0224064Y0636113
X0223403Y0628220
X0223403Y0630820
X0220668Y0649931
X0223775Y0642131
X0223775Y0644731
X0223775Y0647331
X0223775Y0649931
X0220668Y0642131
X0220668Y0647331
X0220668Y0644731
X0223775Y0652531
X0223775Y0655731
X0217561Y0647531
X0217561Y0650131
X0213912Y0644125
X0213912Y0649085
X0213912Y0646605
X0217367Y0672006
X0219967Y0672006
X0222567Y0672006
X0225167Y0672006
X0217510Y0668712
X0220652Y0658675
X0223759Y0658675
X0223403Y0664820
X0217556Y0658575
X0214100Y0678376
X0214100Y0681376
X0238393Y0594220
X0240993Y0594220
X0238393Y0596820
X0240993Y0596820
X0240993Y0604490
X0238393Y0604490
X0231203Y0596820
X0231203Y0594220
X0233803Y0596820
X0233803Y0594220
X0231864Y0602113
X0228603Y0596820
X0228603Y0594220
X0226003Y0596820
X0226003Y0594220
X0226664Y0602113
X0229264Y0602113
X0238393Y0628220
X0240993Y0628220
X0238393Y0630820
X0240993Y0630820
X0240993Y0638490
X0238393Y0638490
X0226664Y0636113
X0229264Y0636113
X0231203Y0630820
X0231203Y0628220
X0233803Y0630820
X0233803Y0628220
X0231864Y0636113
X0228603Y0630820
X0228603Y0628220
X0226003Y0630820
X0226003Y0628220
X0227767Y0672006
X0230367Y0672006
X0226003Y0664820
X0231203Y0664820
X0233803Y0664820
X0228603Y0664820
X0208200Y0493510
X0185191Y0502439
X0204610Y0571097
X0250100Y0521783
X0245700Y0513262
X0254713Y0518465
X0198336Y0574271
X0201622Y0581009
X0210391Y0567981
X0200654Y0578271
X0199164Y0582481
X0201392Y0574271
X0269055Y0566935
X0268995Y0569485
X0269025Y0571995
X0269055Y0574505
X0266555Y0566935
X0266495Y0569485
X0266525Y0571995
X0266555Y0574505
X0261555Y0566935
X0261495Y0569485
X0263995Y0569485
X0264055Y0566935
X0261525Y0571995
X0261555Y0574505
X0264025Y0571995
X0264055Y0574505
X0249800Y0563262
X0251885Y0574805
X0202338Y0568746
X0256855Y0571995
X0254385Y0574805
X0256885Y0574805
X0212891Y0566632
X0178993Y0577790
X0181593Y0577790
X0189293Y0577790
X0184193Y0577790
X0186793Y0577790
X0189293Y0575189
X0178993Y0572689
X0181593Y0572689
X0178993Y0575189
X0181593Y0575189
X0184193Y0572689
X0186793Y0572689
X0184193Y0575189
X0186793Y0575189
X0176393Y0577790
X0173793Y0577790
X0173793Y0572689
X0176393Y0572689
X0173793Y0575189
X0176393Y0575189
X0249860Y0518222
X0253800Y0515362
X0249300Y0510362
X0187490Y0568752
X0196526Y0567825
X0208312Y0576125
X0208312Y0578605
X0208312Y0581085
X0194515Y0583433
X0195888Y0581071
X0221464Y0568113
X0224064Y0568113
X0223775Y0574131
X0220668Y0574131
X0213912Y0576125
X0220668Y0581931
X0223775Y0576731
X0223775Y0579331
X0223775Y0581931
X0220668Y0579331
X0220668Y0576731
X0217561Y0579531
X0217561Y0582131
X0213912Y0581085
X0213912Y0578605
X0240993Y0570490
X0238393Y0570490
X0226664Y0568113
X0229264Y0568113
X0231864Y0568113
X0246400Y0563162
X0181845Y0401071
X0172632Y0454095
X0178375Y0396571
X0252000Y0395400
X0252500Y0415862
X0255810Y0405582
X0195050Y0417465
X0195050Y0412055
X0204699Y0428742
X0204699Y0423242
X0194440Y0439565
X0194440Y0433895
X0187371Y0440742
X0173275Y0393497
X0257750Y0450842
X0263040Y0448752
X0220000Y0448735
X0223664Y0443125
X0263430Y0422235
X0258066Y0426735
X0219995Y0426267
X0224305Y0422977
X0218010Y0432735
X0224210Y0431501
X0218140Y0440735
X0224210Y0436619
X0190880Y0391082
X0172507Y0417205
X0190880Y0387162
X0185211Y0453942
X0180640Y0447172
X0184550Y0435712
X0181994Y0453932
X0180740Y0437562
X0262963Y0443735
X0177871Y0447172
X0178546Y0453806
X0187371Y0447172
X0197650Y0455712
X0217770Y0428262
X0209530Y0426192
X0187371Y0430883
X0230359Y0461683
X0256695Y0461117
X0259869Y0431039
X0259224Y0419532
X0199149Y0447755
X0199149Y0431255
X0199149Y0442255
X0199149Y0436755
X0199149Y0414755
X0199149Y0420255
X0199149Y0425755
X0187532Y0421387
X0199149Y0453255
X0199149Y0468255
X0187371Y0425383
X0187371Y0443383
X0184490Y0402203
X0175640Y0453779
X0199139Y0422882
X0199047Y0428626
X0220843Y0430004
X0223330Y0426467
X0220874Y0442079
X0258746Y0407842
X0260807Y0424403
X0196215Y0447565
X0191305Y0430216
X0184147Y0447078
X0188221Y0454048
X0257434Y0415896
X0259845Y0461117
X0209579Y0462235
X0209579Y0457222
X0177871Y0443383
X0177871Y0430883
X0228550Y0420412
X0177871Y0425383
X0177871Y0421383
X0192220Y0412162
X0192220Y0408662
X0186457Y0405071
X0186457Y0389071
X0186457Y0385071
X0186457Y0393071
X0190880Y0383012
X0226800Y0359464
X0225407Y0321831
X0270240Y0245332
X0267759Y0251962
X0271821Y0251962
X0260500Y0224862
X0260500Y0227362
X0263000Y0227862
X0265500Y0227862
X0174327Y0230928
X0265343Y0244460
X0270745Y0207562
X0263580Y0218627
X0268940Y0217982
X0260700Y0218662
X0253878Y0111771
X0245490Y0159702
X0260100Y0159562
X0238297Y0129703
X0269191Y0121092
X0263550Y0120922
X0265910Y0125492
X0253910Y0115722
X0264578Y0151203
X0260600Y0151062
X0269920Y0097962
X0266420Y0097962
X0262920Y0097962
X0268420Y0100662
X0264920Y0100662
X0261420Y0100662
X0263320Y0087662
X0259933Y0141122
X0234902Y0174047
X0244822Y0111543
X0244822Y0115543
X0266975Y0140107
X0257256Y0156727
X0268985Y0108553
X0268985Y0111053
X0265442Y0108553
X0261899Y0108553
X0261899Y0111053
X0265442Y0111053
X0243892Y0140912
X0247897Y0100543
X0248097Y0092143
X0237539Y0174266
X0264578Y0159203
X0264578Y0155203
X0242255Y0162512
X0233800Y0162692
X0249735Y0152694
X0252195Y0144320
X0242215Y0151788
X0251797Y0100843
X0270364Y0118415
X0258257Y0133783
X0261387Y0133783
X0188620Y0024162
X0186120Y0024162
X0246510Y0020362
X0266990Y0041832
X0246360Y0026852
X0263240Y0038122
X0241310Y0020322
X0235701Y0021582
X0239820Y0054362
X0254050Y0039422
X0250220Y0039362
X0246220Y0039362
X0242220Y0039362
X0235701Y0039570
X0266597Y0080026
X0266597Y0077526
X0264720Y0064362
X0264720Y0060362
X0264720Y0056362
X0266497Y0072036
X0266497Y0069536
X0264740Y0049182
X0261820Y0048962
X0263520Y0051562
X0261020Y0051562
X0259320Y0048962
X0250520Y0051562
X0254020Y0051562
X0257520Y0051562
X0255820Y0048962
X0252320Y0048962
X0248820Y0048962
X0233339Y0017662
X0239720Y0071862
X0245220Y0067862
X0249885Y0069623
X0239010Y0078542
X0238063Y0026232
X0225735Y0026474
X0229135Y0026474
X0225731Y0050646
X0229131Y0050646
X0172361Y0069340
X0186761Y0075340
X0194361Y0069340
X0208895Y0075340
X0216495Y0069340
X0230895Y0075340
X0175761Y0069340
X0183361Y0075340
X0197761Y0069340
X0205495Y0075340
X0219895Y0069340
X0227495Y0075340
X0174533Y0019538
X0197389Y0026474
X0204494Y0019538
X0211562Y0026474
X0218667Y0019538
X0177933Y0019538
X0200789Y0026474
X0207894Y0019538
X0214962Y0026474
X0222067Y0019538
X0233673Y0075340
X0231673Y0077836
X0231673Y0072844
X0226717Y0077836
X0226717Y0072844
X0224717Y0075340
X0211673Y0075340
X0209673Y0077836
X0209673Y0072844
X0202717Y0075340
X0204717Y0077836
X0204717Y0072844
X0180583Y0075340
X0189539Y0075340
X0187539Y0077836
X0187539Y0072844
X0182583Y0077836
X0182583Y0072844
X0244300Y0059762
X0247720Y0071862
X0247720Y0075862
X0222673Y0069340
X0213717Y0069340
X0220673Y0071836
X0220673Y0066844
X0215717Y0071836
X0215717Y0066844
X0198539Y0071836
X0198539Y0066844
X0193583Y0071836
X0193583Y0066844
X0200539Y0069340
X0178539Y0069340
X0191583Y0069340
X0176539Y0071836
X0176539Y0066844
X0271600Y0040162
X0230972Y0040020
X0230972Y0048720
X0209713Y0048720
X0209713Y0040020
X0216799Y0048720
X0216799Y0040020
X0223886Y0048720
X0223886Y0040020
X0195539Y0048720
X0195539Y0040020
X0202626Y0048720
X0202626Y0040020
X0179752Y0040020
X0179752Y0048720
X0172665Y0040020
X0172665Y0048720
X0263280Y0035312
X0249500Y0028362
X0256500Y0028362
X0253000Y0028362
X0260000Y0028362
X0230972Y0037106
X0230972Y0028406
X0238063Y0037162
X0209713Y0037106
X0209713Y0028406
X0216799Y0037106
X0216799Y0028406
X0223886Y0037106
X0223886Y0028406
X0217740Y0025974
X0210784Y0023978
X0215740Y0023978
X0195539Y0037106
X0195539Y0028406
X0202626Y0037106
X0202626Y0028406
X0208784Y0025974
X0203567Y0025974
X0194611Y0025974
X0196611Y0023978
X0201567Y0023978
X0179752Y0028406
X0179752Y0037106
X0172665Y0028406
X0172665Y0037106
X0173606Y0025974
X0243490Y0023002
X0224845Y0019538
X0215889Y0019538
X0210672Y0019538
X0222845Y0022034
X0222845Y0017042
X0217889Y0022034
X0217889Y0017042
X0201716Y0019538
X0208672Y0022034
X0208672Y0017042
X0203716Y0022034
X0203716Y0017042
X0180711Y0019538
X0178711Y0022034
X0178711Y0017042
X0173755Y0022034
X0173755Y0017042
X0189058Y0003010
X0209058Y0003010
X0229058Y0003010
X0249058Y0003010
X0269058Y0003010
X0323040Y0073122
X0275120Y0028562
X0302720Y0038182
X0305247Y0071567
X0302310Y0075673
X0320430Y0078002
X0310459Y0075892
X0301600Y0082457
X0303715Y0050857
X0298550Y0051602
X0301310Y0052482
X0295524Y0052092
X0304972Y0028362
X0304927Y0024654
X0294720Y0040017
X0290720Y0040017
X0295520Y0012762
X0314657Y0068903
X0314657Y0071803
X0305747Y0061113
X0305747Y0064013
X0306570Y0050222
X0299500Y0022862
X0300248Y0028362
X0295520Y0026362
X0293161Y0050522
X0292060Y0024472
X0290799Y0028362
X0287000Y0020862
X0292590Y0053982
X0289400Y0054222
X0275900Y0048872
X0302610Y0026362
X0310400Y0050362
X0280833Y0026474
X0284233Y0026474
X0280830Y0050646
X0284230Y0050646
X0323117Y0076938
X0323117Y0081168
X0292942Y0071499
X0287800Y0060062
X0292942Y0067513
X0299947Y0079273
X0303047Y0079373
X0293452Y0082483
X0293447Y0078573
X0306720Y0039982
X0298720Y0040017
X0278984Y0048720
X0286500Y0052462
X0286071Y0048720
X0287952Y0039984
X0278984Y0028406
X0286071Y0028406
X0285900Y0023962
X0272600Y0027182
X0291660Y0021642
X0291520Y0012762
X0289058Y0003010
X0309058Y0003010
X0318651Y0022921
X0329535Y0049388
X0349535Y0049388
X0326216Y0138787
X0332500Y0150738
X0340440Y0120552
X0307820Y0095724
X0275797Y0120245
X0295357Y0088903
X0316364Y0089212
X0322875Y0084318
X0309756Y0181449
X0296478Y0158703
X0290685Y0165447
X0295685Y0165447
X0276825Y0140462
X0283053Y0139728
X0287000Y0139862
X0272800Y0140162
X0296800Y0139762
X0351100Y0150412
X0308175Y0144202
X0311200Y0165562
X0308500Y0165662
X0309756Y0177449
X0309230Y0173842
X0306730Y0173842
X0306000Y0165662
X0273620Y0096662
X0275797Y0129592
X0366060Y0133912
X0361800Y0122522
X0343450Y0131167
X0355189Y0144267
X0363625Y0127662
X0342700Y0139662
X0326900Y0162287
X0363525Y0158702
X0296478Y0149203
X0311057Y0112803
X0311057Y0110003
X0311057Y0107103
X0313457Y0096803
X0313357Y0089503
X0301183Y0112803
X0301183Y0110003
X0301183Y0107103
X0280857Y0109903
X0282857Y0115603
X0285857Y0115603
X0280857Y0107303
X0288557Y0105003
X0285357Y0105003
X0272529Y0108553
X0272529Y0111053
X0302891Y0141811
X0280687Y0140746
X0366675Y0158702
X0320825Y0159062
X0294553Y0153819
X0299628Y0158703
X0344776Y0148462
X0336240Y0150738
X0324733Y0148598
X0299628Y0149203
X0305025Y0144202
X0283953Y0152503
X0288520Y0157062
X0366775Y0127662
X0343040Y0122522
X0272361Y0120243
X0279277Y0099183
X0289557Y0121803
X0293452Y0085983
X0299657Y0092503
X0301751Y0121466
X0301751Y0124466
X0301751Y0127466
X0320057Y0085803
X0320057Y0088803
X0311758Y0127469
X0311758Y0121469
X0311758Y0124469
X0320270Y0200462
X0357303Y0213159
X0361190Y0210762
X0320940Y0238372
X0345600Y0188162
X0348100Y0185162
X0335412Y0222176
X0319718Y0223750
X0335385Y0235309
X0322658Y0229254
X0323314Y0210645
X0328588Y0209677
X0328939Y0229139
X0308790Y0197622
X0310970Y0195362
X0309910Y0225162
X0306910Y0225162
X0309910Y0228162
X0306910Y0228162
X0316370Y0217492
X0319370Y0217492
X0316370Y0214492
X0319370Y0214492
X0335575Y0214170
X0367306Y0252811
X0354672Y0252693
X0342000Y0252612
X0353145Y0219362
X0329648Y0252202
X0337000Y0219362
X0334500Y0219362
X0337000Y0216862
X0334485Y0216809
X0326168Y0207580
X0323420Y0207549
X0317129Y0251962
X0317981Y0237724
X0291759Y0251962
X0304651Y0251962
X0276491Y0251962
X0281077Y0251962
X0286481Y0251962
X0371551Y0224862
X0345869Y0192716
X0358209Y0208169
X0313995Y0237724
X0282420Y0248652
X0286920Y0248652
X0289920Y0248652
X0276890Y0249022
X0353145Y0228362
X0325855Y0227619
X0338985Y0229509
X0325755Y0230719
X0332465Y0237214
X0328965Y0237214
X0325055Y0237219
X0356250Y0216342
X0332285Y0210609
X0335285Y0210609
X0279740Y0205962
X0282640Y0214102
X0356295Y0219362
X0357660Y0318850
X0364014Y0378649
X0364014Y0366391
X0345411Y0376923
X0345411Y0364702
X0328167Y0379073
X0330674Y0365702
X0354145Y0290591
X0366498Y0290264
X0329002Y0290662
X0316463Y0290662
X0293763Y0290662
X0298184Y0290662
X0302765Y0290662
X0306736Y0290662
X0284515Y0290662
X0289274Y0290662
X0341295Y0290239
X0364014Y0382304
X0371370Y0373622
X0363750Y0369362
X0343411Y0375364
X0330674Y0368261
X0330417Y0380482
X0343411Y0363143
X0357764Y0314234
X0345164Y0314234
X0272500Y0452862
X0272500Y0447735
X0336270Y0402992
X0347340Y0407462
X0343354Y0391643
X0370200Y0409582
X0365771Y0449480
X0365720Y0440562
X0364179Y0392037
X0279500Y0455362
X0274850Y0442562
X0276500Y0444862
X0365970Y0444662
X0369690Y0431812
X0272029Y0443735
X0371066Y0400628
X0343720Y0400628
X0336370Y0406302
X0364179Y0394596
X0343354Y0387988
X0293805Y0565997
X0293805Y0569397
X0284482Y0566022
X0277578Y0509039
X0298587Y0508074
X0319520Y0577658
X0316444Y0559125
X0319520Y0582658
X0317860Y0572322
X0300520Y0552262
X0307987Y0577658
X0284482Y0569548
X0316080Y0578262
X0306087Y0569718
X0296405Y0634132
X0296405Y0630732
X0308605Y0627025
X0308605Y0629525
X0305612Y0627530
X0305612Y0625030
X0305612Y0622530
X0317386Y0623207
X0286582Y0634283
X0286582Y0637809
X0321276Y0599298
X0318560Y0587632
X0329050Y0607402
X0316127Y0592785
X0308447Y0592255
X0306144Y0602225
X0312007Y0588675
X0308417Y0585158
X0294658Y0637809
X0286582Y0630757
X0311820Y0598762
X0320691Y0602448
X0314200Y0585282
X0298000Y0587890
X0295962Y0679374
X0363101Y0693948
X0363101Y0697348
X0294679Y0685046
X0348730Y0731698
X0294679Y0688446
X0348730Y0735098
X0359639Y0690114
X0359669Y0686744
X0285046Y0746702
X0275210Y0738102
X0281046Y0737938
X0281046Y0746702
X0285046Y0737964
X0277046Y0746702
X0336446Y0746486
X0287607Y0754962
X0327096Y0736005
X0319557Y0736225
X0304602Y0727968
X0279507Y0727025
X0297087Y0721249
X0284287Y0716015
X0291600Y0705162
X0358902Y0746405
X0358902Y0739755
X0359790Y0729835
X0355946Y0728800
X0335126Y0728323
X0338097Y0736235
X0298273Y0715400
X0273046Y0735662
X0335467Y0725335
X0335677Y0715215
X0348880Y0703442
X0272208Y0768516
X0327107Y0732665
X0360470Y0705965
X0348037Y0728735
X0338667Y0772452
X0341527Y0778362
X0358902Y0773352
X0358902Y0754945
X0358902Y0736225
X0358902Y0743035
X0289137Y0735275
X0283350Y0728483
X0316397Y0776125
X0360927Y0757665
X0299427Y0768265
X0289047Y0760245
X0348000Y0755362
X0344446Y0739434
X0290680Y0745312
X0290077Y0739735
X0274270Y0746602
X0359930Y0732985
X0278520Y0738072
X0287820Y0727962
X0349187Y0715485
X0331760Y0705882
X0287819Y0691097
X0354100Y0720743
X0352879Y0728657
X0284358Y0732562
X0328120Y0710862
X0317967Y0746985
X0360990Y0726862
X0274247Y0727165
X0331339Y0709313
X0293027Y0755985
X0317967Y0771875
X0277046Y0735442
X0277046Y0725709
X0360120Y1277654
X0357535Y1280218
X0357558Y1277410
X0371230Y1264564
X0371225Y1267188
X0371218Y1261857
X0360128Y1274957
X0357546Y1274903
X0360318Y1267227
X0357768Y1267167
X0360438Y1262057
X0360378Y1264627
X0357888Y1261997
X0357828Y1264567
X0360138Y1272347
X0357546Y1269903
X0357546Y1272403
X0360198Y1269777
X0371278Y1259257
X0371518Y1251537
X0371330Y1256687
X0371458Y1254137
X0371578Y1248967
X0355025Y1280248
X0355048Y1277440
X0341754Y1277485
X0344264Y1277455
X0344115Y1280218
X0341605Y1280248
X0355036Y1274933
X0355258Y1267197
X0355318Y1264597
X0355378Y1262027
X0355036Y1269933
X0355036Y1272433
X0344264Y1274955
X0341754Y1274985
X0341748Y1267147
X0344258Y1267117
X0341742Y1269978
X0344252Y1269948
X0341754Y1272485
X0344264Y1272455
X0339040Y1277594
X0339035Y1280218
X0328168Y1280967
X0339028Y1274887
X0339088Y1272287
X0339148Y1269717
X0302805Y1376541
X0302805Y1379941
X0367647Y1375490
X0370552Y1375573
X0358647Y1378490
X0358647Y1375490
X0361647Y1375490
X0364647Y1375490
X0370552Y1372073
X0367647Y1371990
X0358647Y1371990
X0361647Y1371990
X0364647Y1371990
X0364347Y1340853
X0362147Y1339653
X0360003Y1341147
X0364073Y1334903
X0364269Y1338017
X0360003Y1338247
X0362147Y1336553
X0359363Y1335353
X0357033Y1334603
X0349260Y1379918
X0349260Y1376918
X0354850Y1381408
X0351850Y1381408
X0354850Y1378408
X0351850Y1378408
X0354850Y1375408
X0351850Y1375408
X0349260Y1373418
X0351850Y1371908
X0354850Y1371908
X0354703Y1335353
X0352373Y1334603
X0332475Y1360445
X0332475Y1363345
X0329941Y1359315
X0330041Y1362315
X0327875Y1361045
X0327875Y1363945
X0332475Y1357945
X0327235Y1358151
X0324905Y1357401
X0322575Y1358151
X0320245Y1357401
X0341969Y1345073
X0309841Y1367871
X0306667Y1361597
X0338795Y1338799
X0370923Y1325373
X0303723Y1355853
X0316579Y1364585
X0334973Y1333353
X0348707Y1341787
X0367807Y1319592
X0318051Y1367043
X0350179Y1344245
X0303723Y1353316
X0335679Y1330518
X0367694Y1317092
X0309841Y1364815
X0341969Y1342017
X0345969Y1342755
X0313841Y1365553
X0328070Y1296624
X0328058Y1293917
X0325538Y1295437
X0325538Y1292937
X0325538Y1297937
X0328065Y1299248
X0328018Y1291317
X0328138Y1283567
X0328108Y1286147
X0325748Y1284987
X0323208Y1287617
X0323178Y1290197
X0328078Y1288747
X0325718Y1287587
X0325688Y1290167
X0320428Y1292967
X0323028Y1292967
X0323028Y1295467
X0320428Y1295467
X0320428Y1297967
X0304051Y1365453
X0323028Y1297967
X0320578Y1290197
X0303647Y1307981
X0336179Y1342753
X0368391Y1328161
X0350470Y1349030
X0303831Y1318566
X0303831Y1344866
X0303807Y1342225
X0304047Y1368565
X0313119Y1313108
X0317119Y1313108
X0321119Y1313108
X0317501Y1342432
X0314901Y1342432
X0317501Y1345539
X0314901Y1345539
X0315101Y1348646
X0317701Y1348646
X0320101Y1342432
X0311695Y1352295
X0314175Y1352295
X0316655Y1352295
X0309701Y1342432
X0309701Y1345539
X0312301Y1342432
X0312301Y1345539
X0315221Y1372445
X0317979Y1371248
X0314175Y1357895
X0311695Y1357895
X0316655Y1357895
X0325119Y1313108
X0328915Y1339704
X0331515Y1326704
X0328915Y1326704
X0331515Y1334504
X0328915Y1334504
X0331515Y1329304
X0328915Y1329304
X0331515Y1331904
X0328915Y1331904
X0331515Y1337104
X0328915Y1337104
X0336347Y1348353
X0338917Y1349488
X0323301Y1342432
X0326245Y1342448
X0326245Y1345555
X0326145Y1348651
X0342769Y1299868
X0339769Y1299868
X0355429Y1319634
X0352229Y1319634
X0349629Y1319634
X0349629Y1322741
X0341829Y1319634
X0344429Y1319634
X0347029Y1319634
X0341829Y1322741
X0347029Y1322741
X0344429Y1322741
X0348783Y1335097
X0349829Y1325848
X0348783Y1329497
X0347229Y1325848
X0346303Y1329497
X0343823Y1329497
X0343823Y1335097
X0346303Y1335097
X0348804Y1346877
X0367939Y1308519
X0367939Y1305919
X0367939Y1303319
X0364769Y1300008
X0363643Y1306506
X0361769Y1300008
X0361043Y1306506
X0363643Y1311706
X0363643Y1309106
X0363643Y1314306
X0363643Y1316906
X0361043Y1311706
X0361043Y1309106
X0362393Y1319406
X0361043Y1316906
X0361043Y1314306
X0358373Y1319650
X0358373Y1322757
X0367490Y1332568
X0370874Y1335876
X0358273Y1325853
X0357917Y1408205
X0370717Y1417405
X0370517Y1414615
X0358217Y1411405
X0367703Y1414606
X0367703Y1417386
X0364703Y1417386
X0358703Y1417386
X0361703Y1417386
X0364703Y1414606
X0361703Y1414606
X0358703Y1414606
X0370573Y1405336
X0367573Y1405336
X0364573Y1405336
X0361573Y1405336
X0358573Y1405336
X0358713Y1399336
X0370703Y1402386
X0367703Y1402386
X0364703Y1402386
X0361703Y1402386
X0358703Y1402386
X0370703Y1399386
X0367703Y1399386
X0364703Y1399386
X0361703Y1399386
X0355713Y1399336
X0348903Y1417256
X0352231Y1417332
X0346256Y1417301
X0349073Y1414356
X0349323Y1408406
X0349123Y1411376
X0352401Y1408432
X0355325Y1411386
X0352401Y1411432
X0355325Y1417386
X0355325Y1414386
X0352401Y1414432
X0346426Y1414401
X0355325Y1408386
X0352463Y1405286
X0349463Y1405286
X0355325Y1405386
X0349513Y1402306
X0352513Y1402306
X0355513Y1402306
X0352713Y1399336
X0349636Y1399601
X0368600Y1543200
X0371850Y1534062
X0367948Y1531529
X0276717Y1578182
X0288777Y1578182
X0300837Y1578182
X0312897Y1578182
X0324957Y1578182
X0337017Y1578182
X0349077Y1578182
X0361137Y1578182
X0273317Y1578182
X0285377Y1578182
X0297437Y1578182
X0309497Y1578182
X0321557Y1578182
X0333617Y1578182
X0345677Y1578182
X0357737Y1578182
X0369797Y1578182
X0369019Y1580678
X0369019Y1575686
X0361915Y1575592
X0356959Y1575592
X0361915Y1580678
X0356959Y1580678
X0349855Y1580678
X0344899Y1580678
X0349855Y1575686
X0344899Y1575686
X0337795Y1575686
X0332839Y1575686
X0337795Y1580678
X0332839Y1580678
X0325735Y1580678
X0325735Y1575686
X0320779Y1580678
X0320779Y1575686
X0313675Y1575686
X0308719Y1575686
X0313675Y1580678
X0308719Y1580678
X0301615Y1580678
X0296659Y1580678
X0301615Y1575686
X0296659Y1575686
X0284599Y1575686
X0289555Y1575686
X0289555Y1580678
X0284599Y1580678
X0277495Y1580678
X0277495Y1575686
X0272539Y1580678
X0272539Y1575686
X0369300Y1682900
X0369300Y1680400
X0366700Y1649000
X0367140Y1645390
X0296170Y1622852
X0370635Y1675820
X0370500Y1654362
X0306137Y1602380
X0294077Y1602380
X0282017Y1602380
X0366437Y1602380
X0354377Y1602380
X0342317Y1602380
X0326857Y1602380
X0318197Y1602380
X0302737Y1602380
X0290677Y1602380
X0278617Y1602380
X0363037Y1602380
X0350977Y1602380
X0338917Y1602380
X0330257Y1602380
X0314797Y1602380
X0306137Y1614292
X0294077Y1614292
X0282017Y1614292
X0366437Y1614292
X0354377Y1614292
X0342317Y1614292
X0326857Y1614292
X0318197Y1614292
X0302737Y1614292
X0290677Y1614292
X0278617Y1614292
X0363037Y1614292
X0350977Y1614292
X0338917Y1614292
X0330257Y1614292
X0314797Y1614292
X0276717Y1590094
X0288777Y1590094
X0300837Y1590094
X0312897Y1590094
X0324957Y1590094
X0337017Y1590094
X0349077Y1590094
X0361137Y1590094
X0273317Y1590094
X0285377Y1590094
X0297437Y1590094
X0309497Y1590094
X0321557Y1590094
X0333617Y1590094
X0345677Y1590094
X0357737Y1590094
X0369797Y1590094
X0362259Y1611796
X0362259Y1604876
X0367215Y1611796
X0367215Y1604876
X0362259Y1616788
X0367215Y1616788
X0350199Y1616788
X0355155Y1616788
X0350199Y1611796
X0350199Y1604876
X0355155Y1611796
X0355155Y1604876
X0343095Y1611796
X0343095Y1604876
X0343095Y1616788
X0338139Y1611796
X0338139Y1604876
X0338139Y1616788
X0331035Y1616788
X0326079Y1616788
X0331035Y1611796
X0331035Y1604876
X0326079Y1611796
X0326079Y1604876
X0314019Y1611796
X0314019Y1604876
X0318975Y1611796
X0318975Y1604876
X0314019Y1616788
X0318975Y1616788
X0306915Y1616788
X0306915Y1611796
X0306915Y1604876
X0301959Y1616788
X0301959Y1611796
X0301959Y1604876
X0294855Y1611796
X0294855Y1604876
X0294855Y1616788
X0289899Y1611796
X0289899Y1604876
X0289899Y1616788
X0277839Y1616788
X0282795Y1616788
X0277839Y1604876
X0277839Y1611796
X0282795Y1611796
X0282795Y1604876
X0369019Y1592590
X0369019Y1587598
X0362259Y1599790
X0367215Y1599790
X0361915Y1587598
X0356959Y1587598
X0361915Y1592590
X0356959Y1592590
X0350199Y1599884
X0355155Y1599884
X0343095Y1599884
X0349855Y1592590
X0344899Y1592590
X0349855Y1587598
X0344899Y1587598
X0338139Y1599884
X0331035Y1599884
X0326079Y1599884
X0337795Y1587598
X0332839Y1587598
X0337795Y1592590
X0332839Y1592590
X0325735Y1592590
X0325735Y1587598
X0314019Y1599884
X0318975Y1599884
X0306915Y1599884
X0320779Y1592590
X0320779Y1587598
X0313675Y1587598
X0308719Y1587598
X0313675Y1592590
X0308719Y1592590
X0301959Y1599884
X0294855Y1599884
X0301615Y1592590
X0296659Y1592590
X0301615Y1587598
X0296659Y1587598
X0289899Y1599884
X0277839Y1599884
X0282795Y1599884
X0289555Y1587598
X0284599Y1587598
X0289555Y1592590
X0284599Y1592590
X0277495Y1592590
X0277495Y1587598
X0272539Y1592590
X0272539Y1587598
X0272895Y1737108
X0292895Y1737108
X0332895Y1737108
X0352895Y1737108
X0376610Y1688252
X0372895Y1737108
X0373320Y1688202
X0432895Y1737108
X0452895Y1737108
X0412600Y1601000
X0460200Y1589900
X0469580Y1640272
X0375430Y1676462
X0382220Y1591870
X0394360Y1616380
X0417960Y1650072
X0416020Y1620862
X0412456Y1649838
X0443800Y1610712
X0458978Y1634481
X0463344Y1637622
X0455681Y1622492
X0426728Y1636495
X0448181Y1614401
X0442974Y1615615
X0432500Y1613822
X0444940Y1641842
X0433670Y1639562
X0430015Y1626608
X0460910Y1625772
X0460910Y1629172
X0410249Y1673082
X0396824Y1673662
X0421320Y1671699
X0397400Y1641000
X0384600Y1595100
X0391330Y1585155
X0387930Y1585155
X0402590Y1618952
X0405990Y1618952
X0404030Y1591990
X0423180Y1602802
X0404030Y1595390
X0419780Y1602802
X0380077Y1654049
X0372640Y1662112
X0447090Y1647472
X0466180Y1678392
X0432200Y1607060
X0372009Y1682584
X0441740Y1652266
X0438340Y1652266
X0414406Y1628392
X0414406Y1624992
X0397406Y1636542
X0397406Y1633142
X0457220Y1603562
X0454661Y1609235
X0380170Y1660002
X0449940Y1647412
X0466460Y1672332
X0378497Y1602380
X0375097Y1602380
X0378497Y1614292
X0375097Y1614292
X0373197Y1590094
X0424800Y1616600
X0408600Y1607400
X0409857Y1682767
X0390180Y1668212
X0410700Y1655310
X0391563Y1640244
X0378547Y1639732
X0385123Y1639732
X0374391Y1648476
X0392550Y1618650
X0437383Y1602629
X0444458Y1602654
X0468040Y1651657
X0469488Y1607362
X0457220Y1584020
X0401820Y1645452
X0404320Y1645452
X0404240Y1648082
X0401740Y1648082
X0456510Y1614472
X0410232Y1670244
X0402246Y1671745
X0428941Y1606441
X0408700Y1614300
X0408700Y1603500
X0406526Y1596168
X0406526Y1591212
X0387760Y1671092
X0386824Y1682866
X0381068Y1674824
X0468040Y1654807
X0410700Y1658460
X0375550Y1662052
X0442518Y1649770
X0437562Y1649770
X0451910Y1643282
X0394910Y1637320
X0458414Y1629950
X0458414Y1624994
X0436880Y1622442
X0436840Y1632682
X0447020Y1632632
X0447100Y1622562
X0411910Y1624214
X0411910Y1629170
X0394910Y1632364
X0388220Y1631404
X0374690Y1631700
X0459779Y1609235
X0441308Y1602654
X0433383Y1602629
X0435240Y1609200
X0406768Y1616456
X0401812Y1616456
X0374319Y1616788
X0379275Y1616788
X0374319Y1611796
X0374319Y1604876
X0379275Y1611796
X0379275Y1604876
X0464160Y1587122
X0454661Y1596755
X0428099Y1586282
X0423958Y1600306
X0419002Y1600306
X0374319Y1599884
X0379275Y1599884
X0373975Y1592590
X0373975Y1587598
X0378000Y1546400
X0384000Y1546500
X0381000Y1546500
X0381800Y1539600
X0385100Y1539700
X0381120Y1534102
X0405000Y1566670
X0396946Y1537632
X0431620Y1541362
X0424820Y1552605
X0409140Y1566892
X0433350Y1579509
X0374800Y1546400
X0452520Y1564862
X0434430Y1567562
X0466520Y1574862
X0448740Y1574862
X0374900Y1534102
X0377830Y1534342
X0467400Y1556700
X0404920Y1539362
X0470111Y1548269
X0373197Y1578182
X0459520Y1546962
X0453595Y1551470
X0460020Y1580412
X0452020Y1580412
X0446020Y1570412
X0424570Y1579466
X0396946Y1556810
X0435396Y1551810
X0407625Y1552572
X0396768Y1541810
X0374720Y1539862
X0377720Y1539862
X0463207Y1547543
X0448328Y1582476
X0462079Y1572177
X0464020Y1580412
X0456020Y1580412
X0450020Y1570412
X0442128Y1574879
X0440019Y1576809
X0392108Y1582659
X0373975Y1580678
X0373975Y1575686
X0387152Y1582659
X0456961Y1559697
X0443910Y1555602
X0448079Y1562177
X0432996Y1558322
X0396946Y1560810
X0422566Y1550046
X0436920Y1541562
X0404475Y1552452
X0396921Y1549810
X0384210Y1534152
X0380930Y1531402
X0419820Y1555862
X0466905Y1567847
X0411162Y1414126
X0410933Y1384648
X0414333Y1385292
X0459321Y1396409
X0459321Y1393009
X0448020Y1391862
X0386827Y1429525
X0400926Y1404707
X0411150Y1408163
X0385667Y1433425
X0400924Y1408227
X0408915Y1402606
X0382489Y1428478
X0401079Y1399208
X0394067Y1435323
X0390777Y1435152
X0390687Y1431713
X0410074Y1424993
X0470987Y1409965
X0468880Y1418400
X0448114Y1396812
X0465947Y1398355
X0463140Y1451562
X0408968Y1410427
X0390914Y1412991
X0390934Y1404085
X0392947Y1397827
X0390934Y1407605
X0447110Y1403812
X0443715Y1436052
X0451048Y1404914
X0413599Y1441908
X0424146Y1443411
X0443850Y1423404
X0445294Y1430415
X0433897Y1434670
X0433954Y1439029
X0422708Y1437560
X0425030Y1434292
X0419302Y1434700
X0419861Y1429718
X0412416Y1431645
X0416926Y1426471
X0443842Y1389106
X0436467Y1391687
X0436780Y1387387
X0439030Y1383692
X0430320Y1383862
X0426320Y1383862
X0422320Y1383862
X0418320Y1383862
X0410912Y1418177
X0445723Y1419730
X0445230Y1411719
X0446230Y1407722
X0433539Y1430613
X0437299Y1436774
X0440164Y1433982
X0438645Y1426890
X0416999Y1441908
X0441369Y1394260
X0439391Y1398266
X0438458Y1402169
X0427546Y1443411
X0443424Y1397869
X0414909Y1395658
X0445339Y1415731
X0396822Y1439340
X0401244Y1440773
X0403125Y1425008
X0400991Y1417264
X0392517Y1419015
X0451080Y1433740
X0459550Y1401348
X0458441Y1414893
X0374307Y1408135
X0379825Y1408386
X0376825Y1408386
X0373703Y1417386
X0379825Y1411386
X0376825Y1411386
X0376825Y1417386
X0379825Y1414386
X0376825Y1414386
X0373703Y1414606
X0374027Y1411365
X0373573Y1405336
X0379825Y1405386
X0376825Y1405386
X0373703Y1402386
X0376825Y1402386
X0379825Y1402386
X0373703Y1399386
X0379825Y1399386
X0376825Y1399386
X0456619Y1431189
X0454450Y1433580
X0383127Y1395610
X0381060Y1433622
X0391249Y1401048
X0400926Y1402207
X0400919Y1411231
X0391370Y1424782
X0419974Y1405289
X0412465Y1393878
X0420474Y1420289
X0419974Y1412789
X0407125Y1424978
X0434974Y1405289
X0427474Y1405289
X0434974Y1420289
X0427474Y1420289
X0434974Y1412789
X0449778Y1441606
X0446258Y1441606
X0465749Y1401238
X0455576Y1420625
X0455602Y1412334
X0455576Y1417125
X0455576Y1409125
X0455576Y1424125
X0455576Y1427632
X0400888Y1395508
X0470890Y1435838
X0456387Y1327721
X0460653Y1327491
X0458553Y1326091
X0456387Y1324821
X0460653Y1324591
X0460653Y1321691
X0458453Y1323091
X0455747Y1321927
X0453417Y1321177
X0451087Y1321927
X0448757Y1321177
X0428525Y1327491
X0426425Y1326091
X0424259Y1327721
X0428525Y1324591
X0424259Y1324821
X0426325Y1323091
X0428525Y1321691
X0423619Y1321927
X0421289Y1321177
X0418959Y1321927
X0416629Y1321177
X0396397Y1327491
X0392131Y1327721
X0394297Y1326091
X0396397Y1321691
X0394197Y1323091
X0396397Y1324591
X0392131Y1324821
X0391491Y1321927
X0389161Y1321177
X0380025Y1381490
X0377025Y1381490
X0377025Y1375490
X0380025Y1375490
X0377025Y1378490
X0380025Y1378490
X0373552Y1375573
X0373532Y1378598
X0380025Y1371990
X0377025Y1371990
X0373552Y1372073
X0386831Y1321927
X0384501Y1321177
X0374097Y1331647
X0406225Y1331647
X0438353Y1331647
X0470481Y1331647
X0467307Y1325373
X0435179Y1325373
X0403051Y1325373
X0464191Y1319592
X0432063Y1319592
X0445091Y1328361
X0399935Y1319592
X0412963Y1328361
X0380835Y1328361
X0446563Y1330819
X0414435Y1330819
X0382307Y1330819
X0399935Y1317092
X0432063Y1317092
X0464191Y1317092
X0470481Y1328591
X0438353Y1328591
X0406225Y1328591
X0374097Y1328591
X0442353Y1329329
X0410225Y1329329
X0378097Y1329329
X0400073Y1327653
X0432628Y1327845
X0464191Y1327793
X0386239Y1286578
X0375069Y1286568
X0378069Y1286568
X0383239Y1286578
X0387557Y1306208
X0384357Y1306208
X0376557Y1306208
X0379157Y1306208
X0381757Y1306208
X0373957Y1306208
X0375951Y1316071
X0376557Y1309315
X0379157Y1309315
X0379357Y1312422
X0381757Y1309315
X0381957Y1312422
X0373957Y1309315
X0380911Y1321671
X0378431Y1321671
X0378431Y1316071
X0380911Y1316071
X0375951Y1321671
X0383549Y1333998
X0380842Y1334095
X0399139Y1286708
X0396139Y1286708
X0400067Y1308519
X0400067Y1305919
X0400067Y1298119
X0400067Y1295519
X0400067Y1300719
X0400067Y1303319
X0390501Y1306224
X0394521Y1305980
X0393171Y1298280
X0395771Y1298280
X0393171Y1295680
X0395771Y1295680
X0393171Y1300880
X0395771Y1300880
X0393171Y1303480
X0395771Y1303480
X0390501Y1309331
X0390401Y1312427
X0403130Y1335963
X0399673Y1332653
X0408685Y1306208
X0411285Y1306208
X0406085Y1306208
X0413885Y1306208
X0419685Y1306208
X0416485Y1306208
X0410559Y1321671
X0408079Y1321671
X0413039Y1321671
X0410559Y1316071
X0408079Y1316071
X0413039Y1316071
X0411285Y1309315
X0406085Y1309315
X0408685Y1309315
X0411485Y1312422
X0413885Y1309315
X0414085Y1312422
X0414617Y1333473
X0416099Y1335568
X0433999Y1286758
X0426229Y1286758
X0423229Y1286758
X0430999Y1286758
X0432195Y1308519
X0425299Y1300880
X0427899Y1300880
X0432195Y1300719
X0425299Y1298280
X0427899Y1298280
X0432195Y1298119
X0432195Y1295519
X0427899Y1295680
X0425299Y1295680
X0427899Y1303480
X0426649Y1305980
X0425299Y1303480
X0432195Y1305919
X0432195Y1303319
X0422629Y1306224
X0422629Y1309331
X0422529Y1312427
X0431578Y1332560
X0434983Y1335924
X0451813Y1306208
X0438213Y1306208
X0440813Y1306208
X0443413Y1306208
X0446013Y1306208
X0448613Y1306208
X0442687Y1321671
X0445167Y1321671
X0440207Y1321671
X0442687Y1316071
X0445167Y1316071
X0440207Y1316071
X0446013Y1309315
X0446213Y1312422
X0438213Y1309315
X0440813Y1309315
X0443413Y1309315
X0443613Y1312422
X0445153Y1334095
X0446944Y1335928
X0469019Y1286718
X0463049Y1286978
X0460049Y1286978
X0464423Y1308519
X0460927Y1298780
X0458327Y1298780
X0464427Y1296180
X0460927Y1296180
X0458327Y1296180
X0464427Y1302780
X0464427Y1300180
X0460927Y1301380
X0458327Y1301380
X0458327Y1306580
X0460927Y1306580
X0454757Y1306224
X0464427Y1305380
X0460927Y1303980
X0458327Y1303980
X0454757Y1309331
X0454657Y1312427
X0467644Y1335981
X0464738Y1333085
X0470341Y1306208
X0470341Y1309315
X0470537Y1264403
X0470537Y1261903
X0470415Y1267298
X0470537Y1259403
X0470708Y1251647
X0470648Y1254247
X0470525Y1256896
X0470768Y1249077
X0467898Y1261997
X0467910Y1264704
X0467905Y1267328
X0454164Y1264328
X0454152Y1261821
X0456740Y1264564
X0456748Y1261867
X0454155Y1267128
X0456705Y1267188
X0456938Y1254137
X0454448Y1251477
X0454508Y1248907
X0457058Y1248967
X0467958Y1259397
X0468198Y1251677
X0468138Y1254277
X0468018Y1256827
X0468258Y1249107
X0454152Y1259321
X0456758Y1259257
X0456998Y1251537
X0454152Y1256821
X0454388Y1254077
X0456818Y1256687
X0451645Y1267158
X0451654Y1264358
X0451642Y1261851
X0440775Y1267218
X0438225Y1267158
X0438360Y1264403
X0440870Y1264373
X0440870Y1261873
X0438360Y1261903
X0451998Y1248937
X0451938Y1251507
X0451642Y1259351
X0451878Y1254107
X0451642Y1256851
X0438360Y1259403
X0440870Y1259373
X0441068Y1251567
X0438458Y1254107
X0441008Y1254167
X0438348Y1256896
X0440858Y1256866
X0438518Y1251507
X0438578Y1248937
X0441128Y1248997
X0435708Y1261857
X0435720Y1264564
X0435715Y1267188
X0424388Y1261897
X0424380Y1264594
X0424345Y1267218
X0421795Y1267158
X0421817Y1264328
X0421805Y1261821
X0435768Y1259257
X0436008Y1251537
X0435948Y1254137
X0435828Y1256687
X0436068Y1248967
X0424398Y1259287
X0421805Y1259321
X0424638Y1251567
X0424578Y1254167
X0424458Y1256717
X0422028Y1254107
X0421805Y1256821
X0422088Y1251507
X0424698Y1248997
X0422148Y1248937
X0408445Y1267278
X0405895Y1267218
X0408523Y1261873
X0406013Y1261903
X0406013Y1264403
X0408523Y1264373
X0419285Y1267188
X0419307Y1264358
X0419295Y1261851
X0406013Y1259403
X0408523Y1259373
X0408738Y1251627
X0419295Y1259351
X0419578Y1251537
X0419518Y1254137
X0419295Y1256851
X0419638Y1248967
X0406188Y1251567
X0408678Y1254227
X0406128Y1254167
X0406001Y1256896
X0408511Y1256866
X0408798Y1249057
X0406248Y1248997
X0403390Y1264624
X0403378Y1261917
X0403385Y1267248
X0392185Y1267218
X0389635Y1267158
X0389639Y1264328
X0389627Y1261821
X0392228Y1261897
X0392220Y1264594
X0403438Y1259317
X0389627Y1259321
X0392238Y1259287
X0392478Y1251567
X0389627Y1256821
X0392418Y1254167
X0392298Y1256717
X0389868Y1254107
X0389988Y1248937
X0389928Y1251507
X0392538Y1248997
X0403678Y1251597
X0403498Y1256747
X0403618Y1254197
X0403738Y1249027
X0387125Y1267188
X0387129Y1264358
X0387117Y1261851
X0373735Y1267158
X0376285Y1267218
X0376345Y1264373
X0376345Y1261873
X0373835Y1264403
X0373835Y1261903
X0387117Y1259351
X0387418Y1251537
X0387117Y1256851
X0387358Y1254137
X0387478Y1248967
X0376345Y1259373
X0373835Y1259403
X0373968Y1254107
X0376578Y1251567
X0376518Y1254167
X0376333Y1256866
X0373823Y1256896
X0374028Y1251507
X0374088Y1248937
X0376638Y1248997
X0471198Y1170070
X0471198Y1153370
X0471198Y1161570
X0443276Y1170069
X0445776Y1170069
X0448276Y1170069
X0443276Y1153370
X0448276Y1153370
X0445776Y1153370
X0443276Y1161570
X0445776Y1161570
X0448276Y1161570
X0421960Y1169597
X0421960Y1153370
X0421960Y1161570
X0419460Y1169597
X0419460Y1153370
X0419460Y1161570
X0398796Y1170070
X0398796Y1153070
X0398796Y1161570
X0462196Y1153370
X0457196Y1153370
X0459696Y1153370
X0462196Y1161570
X0459696Y1161570
X0457196Y1161570
X0457196Y1170070
X0462196Y1170070
X0459696Y1170070
X0434272Y1161570
X0434272Y1153370
X0431722Y1161570
X0431722Y1153370
X0436822Y1153370
X0436822Y1161570
X0434272Y1170070
X0431722Y1170070
X0436822Y1170070
X0410532Y1161541
X0407948Y1161570
X0407948Y1153370
X0410532Y1153341
X0410532Y1169597
X0407948Y1169597
X0371970Y0683892
X0381010Y0734732
X0467130Y0600122
X0431220Y0501643
X0431220Y0496362
X0394500Y0522862
X0389020Y0522862
X0431220Y0523362
X0431220Y0518133
X0431220Y0512623
X0431220Y0507143
X0457456Y0522516
X0453680Y0515072
X0434320Y0540153
X0451320Y0533562
X0453727Y0518036
X0387500Y0495362
X0402500Y0495362
X0434343Y0498733
X0434343Y0509733
X0434343Y0504233
X0434343Y0520733
X0434343Y0526233
X0434343Y0515233
X0434343Y0542733
X0434343Y0552769
X0434343Y0547769
X0470880Y0572692
X0455326Y0520389
X0403200Y0572622
X0442853Y0547519
X0442853Y0542519
X0428510Y0515842
X0394860Y0518812
X0460323Y0510183
X0427880Y0506442
X0427790Y0500862
X0402780Y0499372
X0391360Y0495712
X0461520Y0484837
X0456520Y0484837
X0451520Y0484837
X0442520Y0484837
X0447520Y0484837
X0437520Y0484837
X0434620Y0535762
X0400589Y0575236
X0463500Y0383562
X0458600Y0414262
X0453020Y0414262
X0447750Y0414112
X0443300Y0410962
X0390220Y0392062
X0416514Y0407028
X0404291Y0391433
X0400080Y0472652
X0383060Y0403542
X0461520Y0476337
X0456520Y0476337
X0442520Y0476337
X0437520Y0476337
X0395520Y0448362
X0377136Y0390307
X0382220Y0436362
X0403720Y0405552
X0403220Y0436362
X0418520Y0473562
X0433596Y0391163
X0431570Y0435512
X0437720Y0435362
X0417880Y0461942
X0418540Y0392163
X0412720Y0439362
X0376220Y0436362
X0373720Y0431362
X0379220Y0470962
X0379220Y0436362
X0391149Y0404304
X0388720Y0430862
X0389920Y0461362
X0428720Y0439362
X0447490Y0409052
X0451520Y0475837
X0465421Y0428078
X0455720Y0404762
X0449420Y0424162
X0451062Y0397262
X0459220Y0393762
X0415130Y0480202
X0466520Y0475812
X0396570Y0472602
X0382860Y0471122
X0443744Y0452462
X0385730Y0460922
X0424980Y0439462
X0417010Y0439352
X0391150Y0445302
X0403260Y0439352
X0384510Y0438662
X0373190Y0438342
X0465421Y0424928
X0451421Y0429553
X0443744Y0429553
X0385520Y0429262
X0462720Y0404762
X0431462Y0402729
X0418982Y0407847
X0390892Y0406863
X0403700Y0402422
X0431596Y0389604
X0418602Y0394722
X0403570Y0388874
X0390730Y0394852
X0376770Y0387272
X0431920Y0405288
X0461736Y0301098
X0463198Y0311587
X0460800Y0358962
X0443770Y0371042
X0455000Y0340362
X0450500Y0358862
X0465000Y0340362
X0456660Y0359172
X0448220Y0319862
X0439120Y0314562
X0448220Y0323582
X0442220Y0323362
X0425720Y0319492
X0398661Y0323761
X0419920Y0338162
X0422420Y0338162
X0376500Y0378649
X0376500Y0366391
X0404120Y0378439
X0434006Y0365203
X0398720Y0321202
X0385720Y0320902
X0416762Y0367353
X0403875Y0365640
X0390843Y0378439
X0418704Y0379201
X0431781Y0379201
X0442265Y0290939
X0465236Y0296973
X0429702Y0290763
X0416220Y0364062
X0417218Y0291274
X0404215Y0291140
X0392083Y0290954
X0379112Y0290386
X0467211Y0371902
X0432380Y0346522
X0425249Y0338061
X0419023Y0381760
X0446730Y0382432
X0431503Y0376642
X0419012Y0368762
X0403581Y0375880
X0391101Y0380939
X0391195Y0368199
X0469830Y0366158
X0453621Y0359053
X0445944Y0359053
X0432006Y0363644
X0403675Y0363081
X0376500Y0362736
X0468490Y0340572
X0450400Y0338812
X0398720Y0318643
X0385720Y0323761
X0460300Y0303662
X0467736Y0312938
X0445964Y0314234
X0465236Y0293823
X0390876Y0365640
X0446000Y0339362
X0461736Y0306098
X0466300Y0217803
X0466300Y0225480
X0461900Y0215244
X0461900Y0222921
X0452500Y0213362
X0452500Y0222362
X0396294Y0281585
X0470900Y0234787
X0468323Y0254562
X0423145Y0227862
X0404985Y0252162
X0417765Y0252162
X0421200Y0232562
X0392616Y0252162
X0379860Y0252162
X0452071Y0254862
X0433695Y0209862
X0394720Y0206362
X0405139Y0239908
X0420865Y0215067
X0426490Y0244262
X0402700Y0234167
X0388720Y0218362
X0458264Y0254862
X0429395Y0240562
X0429395Y0236562
X0420710Y0242482
X0410090Y0241932
X0405478Y0236726
X0422210Y0221452
X0426295Y0227862
X0429395Y0232562
X0412820Y0231922
X0386120Y0220322
X0376245Y0225362
X0376245Y0221362
X0433695Y0214862
X0407490Y0216912
X0388965Y0209949
X0376245Y0217362
X0376245Y0212862
X0420752Y0239562
X0388965Y0215067
X0410996Y0218834
X0395980Y0148272
X0453028Y0154864
X0446746Y0152662
X0428883Y0131015
X0428889Y0121515
X0379295Y0131002
X0380930Y0122022
X0373200Y0126052
X0372530Y0122972
X0429780Y0153477
X0429780Y0149373
X0429780Y0161466
X0429780Y0157466
X0388735Y0117322
X0383060Y0128491
X0383160Y0124322
X0462320Y0115948
X0453346Y0149864
X0462620Y0120948
X0435340Y0122196
X0408284Y0163662
X0419901Y0117491
X0374981Y0131433
X0411434Y0163662
X0390830Y0155833
X0466992Y0145888
X0443678Y0145710
X0430980Y0132672
X0435340Y0125346
X0413459Y0129061
X0375330Y0121182
X0429050Y0117491
X0383140Y0119822
X0450380Y0104647
X0446640Y0104552
X0428500Y0070016
X0415800Y0067465
X0428500Y0065016
X0415800Y0062665
X0427120Y0059862
X0404910Y0062562
X0407790Y0062652
X0407970Y0059612
X0399240Y0062722
X0402100Y0062632
X0396380Y0062742
X0451418Y0078782
X0454568Y0078782
X0430655Y0058677
X0412930Y0062572
X0403800Y0059662
X0399800Y0059662
X0393830Y0062062
X0409535Y0049388
X0429535Y0049388
X0449535Y0049388
X0469535Y0049388
X0548609Y0048082
X0528590Y0072922
X0527520Y0069633
X0489730Y0076132
X0529078Y0059282
X0523978Y0059074
X0570208Y0047982
X0544402Y0071436
X0541002Y0071436
X0553650Y0048842
X0534720Y0042922
X0534720Y0030792
X0544720Y0042892
X0529720Y0043054
X0529720Y0030792
X0523142Y0071436
X0519742Y0071436
X0523164Y0040328
X0519764Y0040328
X0537315Y0059822
X0533915Y0059822
X0558575Y0071436
X0555175Y0071436
X0551470Y0079372
X0548070Y0079372
X0554983Y0045312
X0567507Y0045869
X0554720Y0032862
X0550971Y0042902
X0499580Y0078442
X0488748Y0072264
X0568500Y0032862
X0558058Y0046352
X0563482Y0040826
X0539720Y0030792
X0539720Y0042862
X0548609Y0032500
X0553320Y0077443
X0546234Y0077443
X0510030Y0078412
X0503100Y0078402
X0553335Y0069508
X0560421Y0069508
X0539161Y0057894
X0539161Y0069508
X0546248Y0069508
X0524988Y0069508
X0532075Y0057894
X0532075Y0069508
X0510815Y0069508
X0517902Y0069508
X0478240Y0061129
X0478240Y0066575
X0564430Y0045132
X0524988Y0049194
X0525000Y0042257
X0510815Y0049194
X0517902Y0049194
X0517914Y0042257
X0478240Y0055935
X0562780Y0032842
X0489535Y0049347
X0518606Y0023797
X0542050Y0047452
X0565184Y0047982
X0561000Y0098862
X0559000Y0102862
X0510900Y0111962
X0498330Y0096112
X0527310Y0094747
X0527310Y0098147
X0517290Y0104252
X0513700Y0117862
X0510600Y0092782
X0518450Y0101602
X0526920Y0161362
X0481880Y0147069
X0551231Y0122671
X0568245Y0167112
X0513586Y0092799
X0518186Y0139821
X0519010Y0147912
X0527160Y0129243
X0555545Y0156462
X0476220Y0158772
X0566500Y0125097
X0543083Y0146338
X0569470Y0171702
X0516236Y0092948
X0515690Y0147852
X0539475Y0118772
X0555195Y0171862
X0555220Y0164787
X0547395Y0147302
X0552395Y0134340
X0507320Y0128592
X0503270Y0128592
X0498730Y0128592
X0481246Y0161364
X0542460Y0099172
X0564890Y0142173
X0534765Y0161067
X0523220Y0170362
X0567865Y0092656
X0570150Y0102862
X0569965Y0161232
X0555220Y0167937
X0527278Y0164726
X0514850Y0168443
X0484396Y0161364
X0565500Y0145252
X0550545Y0147302
X0527823Y0149802
X0507360Y0140492
X0503290Y0140492
X0498630Y0140492
X0567673Y0130542
X0555545Y0134340
X0527823Y0131802
X0564988Y0118670
X0537360Y0120522
X0549610Y0120682
X0528400Y0114275
X0542620Y0103352
X0528400Y0104225
X0529239Y0092911
X0529239Y0099997
X0501540Y0105152
X0504980Y0101752
X0497002Y0088167
X0562461Y0272161
X0557248Y0198909
X0503100Y0222921
X0503100Y0215244
X0559400Y0201162
X0554872Y0196635
X0498700Y0220362
X0498700Y0212685
X0512500Y0209862
X0508500Y0232862
X0537720Y0278212
X0518670Y0219192
X0519236Y0202404
X0522337Y0202404
X0552489Y0212022
X0552089Y0257202
X0539830Y0274912
X0529507Y0202448
X0567730Y0221362
X0567730Y0225362
X0542050Y0231722
X0546390Y0231742
X0548390Y0236512
X0550390Y0231742
X0508000Y0241862
X0500925Y0231262
X0552089Y0253202
X0555195Y0184862
X0539639Y0271972
X0499096Y0252462
X0478500Y0258862
X0496028Y0258590
X0486800Y0259162
X0512500Y0223362
X0564600Y0202662
X0544390Y0236512
X0568149Y0217916
X0569668Y0229812
X0542798Y0202646
X0553657Y0193862
X0564944Y0252173
X0536127Y0247652
X0508000Y0237862
X0489980Y0250512
X0504075Y0231262
X0475500Y0212685
X0529480Y0183921
X0540460Y0200392
X0553402Y0231292
X0486710Y0313582
X0495036Y0310398
X0495136Y0300398
X0558790Y0331846
X0531298Y0284280
X0561290Y0331846
X0492150Y0336810
X0571830Y0348772
X0549220Y0339687
X0567630Y0331958
X0570440Y0331930
X0561324Y0301149
X0563790Y0331846
X0555520Y0309827
X0546758Y0360502
X0544920Y0306862
X0547420Y0306862
X0475508Y0359266
X0490720Y0368862
X0523670Y0368892
X0476585Y0370727
X0506720Y0368862
X0566730Y0300992
X0523682Y0304541
X0523682Y0307541
X0502239Y0315404
X0503040Y0287928
X0486861Y0305398
X0498636Y0296273
X0478995Y0293787
X0535720Y0360862
X0502720Y0360862
X0514720Y0360862
X0482720Y0360862
X0536420Y0309422
X0474736Y0302098
X0479736Y0308598
X0489091Y0293787
X0479736Y0303598
X0508136Y0309398
X0508502Y0298813
X0508500Y0303362
X0571720Y0381862
X0490720Y0360862
X0498720Y0360862
X0526980Y0322582
X0527720Y0360862
X0531720Y0360862
X0486720Y0360862
X0521820Y0336762
X0510720Y0360862
X0507160Y0332452
X0570200Y0372229
X0557701Y0369123
X0550024Y0369123
X0523660Y0323222
X0510740Y0332592
X0569880Y0300992
X0553536Y0307527
X0535630Y0306602
X0505900Y0311562
X0492074Y0300306
X0486861Y0309398
X0501136Y0312238
X0479740Y0300202
X0476740Y0309272
X0484800Y0307362
X0529533Y0299500
X0532533Y0299500
X0498636Y0293123
X0472800Y0299462
X0495136Y0305398
X0571110Y0446706
X0542870Y0438320
X0532650Y0442376
X0532650Y0454270
X0569490Y0437600
X0532650Y0450330
X0492970Y0409252
X0494020Y0414262
X0489520Y0411862
X0485020Y0414162
X0471920Y0416687
X0567320Y0457462
X0559730Y0434772
X0567320Y0459962
X0511320Y0437962
X0548464Y0456534
X0571110Y0442656
X0525820Y0473662
X0513444Y0457522
X0533410Y0475932
X0502260Y0397742
X0567320Y0454962
X0558220Y0459362
X0498169Y0476196
X0493169Y0476196
X0479169Y0476196
X0474169Y0476196
X0521720Y0398362
X0505720Y0398362
X0522805Y0482155
X0557829Y0454479
X0532650Y0446396
X0488169Y0475696
X0521885Y0452442
X0502070Y0427937
X0559300Y0414112
X0529720Y0390362
X0513720Y0390362
X0562200Y0419412
X0549670Y0419892
X0547810Y0414472
X0525720Y0390362
X0472720Y0391362
X0509720Y0390362
X0543035Y0441005
X0570760Y0451710
X0538120Y0463137
X0503169Y0475671
X0513444Y0473281
X0518735Y0452442
X0526941Y0447802
X0479379Y0452445
X0559300Y0422732
X0488070Y0429412
X0502070Y0424787
X0480393Y0429412
X0569080Y0414002
X0550024Y0401023
X0528145Y0408705
X0513173Y0408740
X0497568Y0397632
X0482920Y0398060
X0535220Y0383552
X0548780Y0475932
X0548550Y0480382
X0560640Y0540613
X0563700Y0538477
X0546210Y0519642
X0563281Y0543113
X0524720Y0519743
X0524720Y0525293
X0524220Y0511362
X0524220Y0516862
X0524220Y0500362
X0568520Y0506662
X0524220Y0505862
X0568520Y0504162
X0524820Y0545319
X0524920Y0539819
X0559927Y0548457
X0566140Y0551472
X0566140Y0554972
X0571627Y0548124
X0541722Y0568054
X0541820Y0575130
X0536000Y0520362
X0568840Y0501046
X0491043Y0550447
X0519520Y0484027
X0524425Y0495112
X0524425Y0489112
X0521561Y0511469
X0521561Y0500469
X0521561Y0505969
X0521561Y0522469
X0521561Y0516969
X0521561Y0539819
X0521561Y0527969
X0531472Y0579750
X0550320Y0583362
X0569050Y0578292
X0537730Y0577440
X0556820Y0570462
X0486500Y0556212
X0528500Y0566722
X0527042Y0505830
X0526853Y0516817
X0526852Y0511331
X0571700Y0552200
X0535290Y0572932
X0526280Y0569122
X0474220Y0572782
X0521561Y0550819
X0494193Y0550447
X0509493Y0539819
X0473870Y0506622
X0514425Y0495112
X0514425Y0489112
X0488169Y0484696
X0493169Y0484696
X0498169Y0484696
X0484169Y0484696
X0474169Y0484696
X0479169Y0484696
X0531258Y0505473
X0474044Y0503725
X0523699Y0571545
X0482780Y0607012
X0504135Y0615612
X0472960Y0602152
X0478510Y0602942
X0536626Y0590500
X0557430Y0583572
X0547020Y0590332
X0537560Y0598102
X0516970Y0592942
X0513025Y0615742
X0471940Y0597532
X0543450Y0590262
X0520710Y0592552
X0523890Y0592387
X0473698Y1170070
X0473698Y1153370
X0473698Y1161570
X0483030Y1161570
X0483030Y1153370
X0483030Y1170070
X0530548Y1283377
X0518490Y1277024
X0518500Y1280054
X0521020Y1280974
X0521058Y1278277
X0518490Y1274144
X0521058Y1275667
X0518488Y1271477
X0521118Y1273097
X0515950Y1277024
X0515960Y1280054
X0502680Y1280054
X0505218Y1277024
X0502718Y1276994
X0505220Y1280054
X0515950Y1274144
X0515898Y1271447
X0505218Y1274144
X0502718Y1274114
X0502738Y1264427
X0502798Y1261827
X0502750Y1267134
X0505278Y1264547
X0505338Y1261947
X0505290Y1267254
X0505218Y1271447
X0502718Y1271417
X0502858Y1259257
X0505398Y1259377
X0500150Y1278104
X0500150Y1275224
X0500168Y1261807
X0500198Y1264467
X0500198Y1267037
X0500150Y1272344
X0500138Y1269637
X0486255Y1267188
X0488805Y1267248
X0488848Y1261927
X0488840Y1264624
X0486341Y1264328
X0486329Y1261821
X0500228Y1259237
X0488858Y1259317
X0486329Y1259321
X0489098Y1251597
X0486548Y1251537
X0489038Y1254197
X0488918Y1256747
X0486488Y1254137
X0486329Y1256821
X0489158Y1249027
X0486608Y1248967
X0483745Y1267218
X0483831Y1264358
X0483819Y1261851
X0473047Y1264373
X0473047Y1261873
X0472965Y1267358
X0483819Y1259351
X0484038Y1251567
X0483978Y1254167
X0483819Y1256851
X0484098Y1248997
X0473047Y1259373
X0473258Y1251707
X0473198Y1254307
X0473035Y1256866
X0473318Y1249137
X0552131Y1358151
X0552771Y1363945
X0552771Y1361045
X0554937Y1362315
X0557037Y1360815
X0557037Y1357915
X0557037Y1363715
X0554837Y1359315
X0547471Y1358151
X0549801Y1357401
X0545141Y1357401
X0522818Y1342930
X0524892Y1341462
X0520003Y1335353
X0520643Y1341147
X0522783Y1334882
X0522809Y1339517
X0520643Y1338247
X0525008Y1336287
X0515343Y1335353
X0517673Y1334603
X0513013Y1334603
X0492878Y1328418
X0490778Y1327018
X0488539Y1328672
X0492878Y1325518
X0488539Y1325772
X0490678Y1324018
X0492878Y1322618
X0487875Y1321927
X0483215Y1321927
X0485545Y1321177
X0480885Y1321177
X0502609Y1345073
X0534737Y1367871
X0531563Y1361597
X0499435Y1338799
X0528447Y1355816
X0541475Y1364585
X0496319Y1333043
X0509347Y1341787
X0477219Y1328361
X0542947Y1367043
X0510819Y1344245
X0478691Y1330819
X0496319Y1330493
X0528447Y1353316
X0566510Y1352217
X0534737Y1364815
X0502609Y1342017
X0474481Y1329329
X0506609Y1342755
X0538737Y1365553
X0536020Y1302904
X0540210Y1295584
X0540210Y1298464
X0537650Y1295584
X0537650Y1298464
X0540210Y1292704
X0537650Y1292704
X0535110Y1298464
X0535110Y1295584
X0535110Y1292704
X0538560Y1302934
X0541100Y1302934
X0543660Y1302934
X0535148Y1287397
X0535058Y1290007
X0537648Y1290037
X0532570Y1292674
X0532570Y1298434
X0532570Y1295554
X0530450Y1294134
X0530450Y1297014
X0532678Y1284797
X0532618Y1287367
X0532558Y1289967
X0530410Y1291254
X0530428Y1285947
X0530398Y1288557
X0496319Y1341264
X0528929Y1364212
X0571555Y1352487
X0570645Y1361358
X0484509Y1286848
X0477509Y1286848
X0481509Y1286848
X0474509Y1286848
X0483941Y1306208
X0472941Y1306208
X0475541Y1306208
X0478141Y1306208
X0480741Y1306208
X0474815Y1321671
X0477295Y1321671
X0472335Y1321671
X0474815Y1316071
X0477295Y1316071
X0472335Y1316071
X0475541Y1309315
X0475741Y1312422
X0478341Y1312422
X0478141Y1309315
X0472941Y1309315
X0478909Y1336038
X0477162Y1334095
X0490759Y1291978
X0498309Y1300058
X0495309Y1300058
X0489555Y1300880
X0492155Y1300880
X0490905Y1305980
X0492155Y1303480
X0489555Y1303480
X0496451Y1306345
X0486885Y1306224
X0496451Y1311545
X0496451Y1314145
X0496451Y1308945
X0496451Y1316745
X0496220Y1322440
X0486885Y1309331
X0486785Y1312427
X0499458Y1349468
X0514989Y1300108
X0517989Y1300108
X0510269Y1322741
X0505069Y1322741
X0507669Y1322741
X0505069Y1319634
X0507669Y1319634
X0510269Y1319634
X0512869Y1319634
X0502469Y1322741
X0502469Y1319634
X0516069Y1319634
X0507869Y1325848
X0510469Y1325848
X0506943Y1335097
X0509423Y1335097
X0506943Y1329497
X0509423Y1329497
X0504463Y1335097
X0504463Y1329497
X0511149Y1349468
X0509382Y1347521
X0505055Y1382301
X0519013Y1322757
X0519013Y1319650
X0523033Y1319406
X0518913Y1325853
X0528377Y1335982
X0528579Y1329143
X0527645Y1326076
X0534597Y1342432
X0534597Y1345539
X0528579Y1344743
X0528579Y1342143
X0528975Y1369724
X0535693Y1322668
X0538293Y1322668
X0542213Y1322668
X0544813Y1322668
X0541551Y1352295
X0536591Y1352295
X0539071Y1352295
X0539797Y1345539
X0537197Y1345539
X0544997Y1342432
X0542397Y1342432
X0539797Y1342432
X0537197Y1342432
X0542597Y1348646
X0542397Y1345539
X0539997Y1348646
X0548197Y1342432
X0539071Y1357895
X0536591Y1357895
X0542256Y1369935
X0541551Y1357895
X0555313Y1340418
X0553963Y1332718
X0553963Y1335318
X0558933Y1331538
X0556563Y1332718
X0556563Y1335318
X0558933Y1328938
X0553963Y1337918
X0556563Y1337918
X0565849Y1346968
X0561070Y1346174
X0555372Y1343037
X0551141Y1342448
X0551041Y1348651
X0551141Y1345555
X0569849Y1346968
X0558933Y1323658
X0558933Y1326258
X0561034Y1334315
X0563634Y1334315
X0484921Y1413246
X0481997Y1409955
X0505777Y1425579
X0485141Y1405430
X0482633Y1446091
X0482633Y1449091
X0478449Y1448158
X0499489Y1446091
X0499489Y1449091
X0491089Y1449091
X0491089Y1446091
X0507964Y1445979
X0507964Y1448979
X0571620Y1424492
X0509246Y1420002
X0555057Y1449395
X0474983Y1400385
X0475285Y1395402
X0485236Y1417844
X0482741Y1438698
X0482742Y1441312
X0478308Y1439986
X0499818Y1385027
X0499859Y1393027
X0490307Y1421499
X0499541Y1438698
X0491156Y1438713
X0499542Y1441312
X0491142Y1441312
X0502418Y1385027
X0505018Y1385027
X0505055Y1387601
X0503559Y1405025
X0502459Y1393027
X0505059Y1393027
X0506181Y1404880
X0508881Y1404880
X0505055Y1390201
X0505055Y1398601
X0505055Y1396001
X0503572Y1410039
X0506102Y1412420
X0503572Y1412539
X0503572Y1415039
X0503572Y1407539
X0506128Y1407385
X0506075Y1409889
X0508802Y1412420
X0508828Y1407385
X0508775Y1409889
X0508001Y1438669
X0507942Y1441312
X0483560Y1401712
X0486210Y1547960
X0480848Y1548120
X0477968Y1548122
X0475110Y1548112
X0483348Y1548062
X0482400Y1558320
X0545411Y1578182
X0557471Y1578182
X0569531Y1578182
X0473051Y1578182
X0485111Y1578182
X0497171Y1578182
X0509231Y1578182
X0521291Y1578182
X0533351Y1578182
X0548811Y1578182
X0560871Y1578182
X0476451Y1578182
X0488511Y1578182
X0500571Y1578182
X0512631Y1578182
X0524691Y1578182
X0536751Y1578182
X0568753Y1575686
X0568753Y1580678
X0561649Y1580678
X0556693Y1580678
X0561649Y1575686
X0556693Y1575686
X0537529Y1580678
X0537529Y1575686
X0544633Y1575592
X0549589Y1575592
X0544633Y1580678
X0549589Y1580678
X0525469Y1575686
X0520513Y1575686
X0525469Y1580678
X0520513Y1580678
X0532573Y1580678
X0532573Y1575686
X0513409Y1580678
X0508453Y1580678
X0513409Y1575686
X0508453Y1575686
X0489289Y1580678
X0489289Y1575686
X0501349Y1575686
X0496393Y1575686
X0496393Y1580678
X0501349Y1580678
X0477229Y1575686
X0472273Y1575686
X0472273Y1580678
X0477229Y1580678
X0484333Y1580678
X0484333Y1575686
X0475150Y1654302
X0477905Y1659242
X0554111Y1602380
X0566171Y1602380
X0481751Y1602380
X0493811Y1602380
X0505871Y1602380
X0517931Y1602380
X0529991Y1602380
X0542051Y1602380
X0550711Y1602380
X0562771Y1602380
X0478351Y1602380
X0490411Y1602380
X0502471Y1602380
X0514531Y1602380
X0526591Y1602380
X0538651Y1602380
X0554111Y1614292
X0566171Y1614292
X0481751Y1614292
X0493811Y1614292
X0505871Y1614292
X0517931Y1614292
X0529991Y1614292
X0542051Y1614292
X0550711Y1614292
X0562771Y1614292
X0478351Y1614292
X0490411Y1614292
X0502471Y1614292
X0514531Y1614292
X0526591Y1614292
X0538651Y1614292
X0545411Y1590094
X0557471Y1590094
X0569531Y1590094
X0473051Y1590094
X0485111Y1590094
X0497171Y1590094
X0509231Y1590094
X0521291Y1590094
X0533351Y1590094
X0548811Y1590094
X0560871Y1590094
X0476451Y1590094
X0488511Y1590094
X0500571Y1590094
X0512631Y1590094
X0524691Y1590094
X0536751Y1590094
X0489230Y1643592
X0477835Y1677462
X0477905Y1663242
X0472210Y1622735
X0477905Y1667242
X0477835Y1673462
X0487340Y1641352
X0485150Y1624942
X0472210Y1618626
X0566949Y1611796
X0566949Y1604876
X0566949Y1616788
X0554889Y1616788
X0554889Y1604876
X0554889Y1611796
X0561993Y1611796
X0561993Y1604876
X0561993Y1616788
X0542829Y1611796
X0537873Y1611796
X0542829Y1604876
X0537873Y1604876
X0537873Y1616788
X0542829Y1616788
X0549933Y1616788
X0549933Y1604876
X0549933Y1611796
X0518709Y1611796
X0518709Y1604876
X0518709Y1616788
X0525813Y1616788
X0530769Y1616788
X0530769Y1604876
X0525813Y1604876
X0530769Y1611796
X0525813Y1611796
X0506649Y1616788
X0506649Y1604876
X0506649Y1611796
X0513753Y1611796
X0513753Y1604876
X0513753Y1616788
X0494589Y1616788
X0489633Y1616788
X0494589Y1611796
X0489633Y1604876
X0494589Y1604876
X0489633Y1611796
X0501693Y1616788
X0501693Y1604876
X0501693Y1611796
X0482529Y1604876
X0477573Y1604876
X0482529Y1611796
X0477573Y1611796
X0477573Y1616788
X0482529Y1616788
X0568753Y1587598
X0568753Y1592590
X0566949Y1599884
X0556693Y1592590
X0561649Y1592590
X0561649Y1587598
X0556693Y1587598
X0554889Y1599790
X0561993Y1599884
X0537529Y1592590
X0537529Y1587598
X0544633Y1587598
X0549589Y1587598
X0544633Y1592590
X0549589Y1592590
X0542829Y1599884
X0537873Y1599884
X0549933Y1599790
X0525469Y1587598
X0520513Y1587598
X0520513Y1592590
X0525469Y1592590
X0532573Y1592590
X0532573Y1587598
X0518709Y1599884
X0530769Y1599884
X0525813Y1599884
X0513409Y1592590
X0508453Y1592590
X0513409Y1587598
X0508453Y1587598
X0506649Y1599884
X0513753Y1599884
X0489289Y1592590
X0489289Y1587598
X0496393Y1587598
X0501349Y1587598
X0496393Y1592590
X0501349Y1592590
X0489633Y1599884
X0494589Y1599884
X0501693Y1599884
X0472273Y1587598
X0477229Y1587598
X0477229Y1592590
X0472273Y1592590
X0484333Y1592590
X0484333Y1587598
X0477573Y1599884
X0482529Y1599884
X0472220Y1626732
X0477835Y1685462
X0472895Y1737108
X0492895Y1737108
X0512895Y1737108
X0532895Y1737108
X0552895Y1737108
X0653420Y1698662
X0636160Y1710662
X0648220Y1722921
X0648220Y1716912
X0650725Y1690682
X0642225Y1708457
X0640725Y1691452
X0645725Y1691182
X0663645Y1722862
X0639745Y1718362
X0639745Y1722362
X0646225Y1708169
X0652712Y1686275
X0656973Y1698727
X0669120Y1718862
X0639745Y1726362
X0648290Y1720052
X0639745Y1714362
X0641386Y1687283
X0572895Y1737108
X0612895Y1737108
X0632895Y1737108
X0652895Y1737108
X0666700Y1588500
X0666600Y1584900
X0666700Y1591900
X0666700Y1595500
X0636702Y1677610
X0651725Y1643397
X0664590Y1631620
X0635410Y1664220
X0671290Y1646320
X0637540Y1669480
X0628970Y1670880
X0668695Y1662235
X0671620Y1668303
X0643725Y1643467
X0642725Y1658562
X0648225Y1658482
X0671610Y1673792
X0578231Y1602380
X0590291Y1602380
X0602351Y1602380
X0614411Y1602380
X0626471Y1602380
X0638531Y1602380
X0650591Y1602380
X0659251Y1602380
X0574831Y1602380
X0586891Y1602380
X0598951Y1602380
X0611011Y1602380
X0623071Y1602380
X0635131Y1602380
X0647191Y1602380
X0662651Y1602380
X0578231Y1614292
X0590291Y1614292
X0602351Y1614292
X0614411Y1614292
X0626471Y1614292
X0638531Y1614292
X0650591Y1614292
X0659251Y1614292
X0574831Y1614292
X0586891Y1614292
X0598951Y1614292
X0611011Y1614292
X0623071Y1614292
X0635131Y1614292
X0647191Y1614292
X0662651Y1614292
X0581591Y1590094
X0593651Y1590094
X0605711Y1590094
X0617771Y1590094
X0629831Y1590094
X0641891Y1590094
X0653951Y1590094
X0572931Y1590094
X0584991Y1590094
X0597051Y1590094
X0609111Y1590094
X0621171Y1590094
X0633231Y1590094
X0645291Y1590094
X0657351Y1590094
X0663145Y1668862
X0663145Y1672862
X0663097Y1642667
X0663043Y1651557
X0663118Y1655557
X0656725Y1660769
X0647725Y1643719
X0645407Y1660425
X0641057Y1648659
X0655307Y1647436
X0671620Y1670862
X0663145Y1676862
X0656725Y1657619
X0663145Y1664862
X0663118Y1659557
X0671112Y1639962
X0663043Y1647557
X0651369Y1604876
X0651369Y1611796
X0651369Y1616788
X0663429Y1616788
X0658473Y1616788
X0658473Y1611796
X0663429Y1611796
X0658473Y1604876
X0663429Y1604876
X0639309Y1616788
X0634353Y1616788
X0634353Y1611796
X0639309Y1611796
X0634353Y1604876
X0639309Y1604876
X0646413Y1604876
X0646413Y1611796
X0646413Y1616788
X0627249Y1604876
X0622293Y1604876
X0627249Y1611796
X0622293Y1611796
X0622293Y1616788
X0627249Y1616788
X0603129Y1604876
X0603129Y1611796
X0603129Y1616788
X0610233Y1616788
X0615189Y1616788
X0610233Y1611796
X0615189Y1611796
X0610233Y1604876
X0615189Y1604876
X0586113Y1616788
X0591069Y1616788
X0591069Y1611796
X0586113Y1611796
X0591069Y1604876
X0586113Y1604876
X0598173Y1604876
X0598173Y1611796
X0598173Y1616788
X0574053Y1604876
X0579009Y1604876
X0574053Y1611796
X0579009Y1611796
X0579009Y1616788
X0574053Y1616788
X0658129Y1592590
X0653173Y1592590
X0658129Y1587598
X0653173Y1587598
X0651369Y1599790
X0658473Y1599884
X0663429Y1599884
X0634009Y1592590
X0634009Y1587598
X0641113Y1587598
X0646069Y1587598
X0641113Y1592590
X0646069Y1592590
X0634353Y1599884
X0639309Y1599884
X0646413Y1599790
X0616993Y1587598
X0621949Y1587598
X0616993Y1592590
X0621949Y1592590
X0629053Y1592590
X0629053Y1587598
X0627249Y1599884
X0622293Y1599884
X0604933Y1592590
X0609889Y1592590
X0604933Y1587598
X0609889Y1587598
X0603129Y1599884
X0610233Y1599884
X0615189Y1599884
X0585769Y1592590
X0585769Y1587598
X0592873Y1587598
X0597829Y1587598
X0592873Y1592590
X0597829Y1592590
X0591069Y1599884
X0586113Y1599884
X0598173Y1599884
X0573709Y1587598
X0573709Y1592590
X0580813Y1592590
X0580813Y1587598
X0574053Y1599884
X0579009Y1599884
X0665410Y1548180
X0662660Y1548120
X0663410Y1553982
X0581591Y1578182
X0593651Y1578182
X0605711Y1578182
X0617771Y1578182
X0629831Y1578182
X0641891Y1578182
X0653951Y1578182
X0572931Y1578182
X0584991Y1578182
X0597051Y1578182
X0609111Y1578182
X0621171Y1578182
X0633231Y1578182
X0645291Y1578182
X0657351Y1578182
X0667926Y1547018
X0658129Y1580678
X0653173Y1580678
X0658129Y1575686
X0653173Y1575686
X0634009Y1580678
X0634009Y1575686
X0641113Y1575592
X0646069Y1575592
X0641113Y1580678
X0646069Y1580678
X0616993Y1575686
X0621949Y1575686
X0616993Y1580678
X0621949Y1580678
X0629053Y1580678
X0629053Y1575686
X0604933Y1580678
X0609889Y1580678
X0604933Y1575686
X0609889Y1575686
X0585769Y1580678
X0585769Y1575686
X0592873Y1575686
X0597829Y1575686
X0592873Y1580678
X0597829Y1580678
X0573709Y1575686
X0573709Y1580678
X0580813Y1580678
X0580813Y1575686
X0666560Y1581000
X0654540Y1424205
X0654540Y1427605
X0669477Y1409415
X0666303Y1403476
X0663187Y1397720
X0663187Y1395170
X0669477Y1406694
X0663687Y1407279
X0661100Y1451012
X0653761Y1396300
X0653690Y1392362
X0576220Y1423862
X0671149Y1428649
X0668649Y1431149
X0668649Y1428649
X0671149Y1431149
X0668649Y1426149
X0671149Y1426149
X0668649Y1434149
X0671149Y1434149
X0654606Y1431203
X0662282Y1386432
X0664782Y1386432
X0664782Y1383832
X0669337Y1387418
X0669337Y1384311
X0671350Y1394157
X0671350Y1399757
X0666425Y1414200
X0670037Y1348896
X0670037Y1346396
X0670037Y1343896
X0670037Y1341396
X0667487Y1343896
X0667487Y1341396
X0664987Y1341396
X0664987Y1343896
X0667487Y1346396
X0664987Y1346396
X0667487Y1348896
X0664987Y1348896
X0667487Y1333896
X0664987Y1333896
X0670037Y1333896
X0670037Y1338896
X0667487Y1338896
X0664987Y1338896
X0667487Y1336396
X0664987Y1336396
X0670037Y1336396
X0573849Y1346968
X0668096Y1360822
X0664782Y1378632
X0664782Y1381232
X0666741Y1255381
X0618114Y1258470
X0652577Y1000775
X0669700Y0746626
X0633147Y0758595
X0630417Y0757135
X0617940Y0763552
X0613047Y0741492
X0600460Y0744912
X0598693Y0742072
X0669778Y0759929
X0620870Y0762072
X0603276Y0741375
X0592340Y0744624
X0602768Y0758385
X0626017Y0745083
X0623497Y0748235
X0612407Y0769485
X0602027Y0761445
X0671607Y0742835
X0626207Y0747585
X0614660Y0739553
X0589989Y0745475
X0603317Y0738415
X0617252Y0739354
X0613220Y0654662
X0626720Y0643462
X0629220Y0643462
X0610797Y0537528
X0607328Y0537481
X0577470Y0505592
X0633000Y0508700
X0623000Y0546900
X0640130Y0517870
X0642630Y0517870
X0596880Y0534812
X0670720Y0516862
X0606220Y0517762
X0572057Y0577242
X0587100Y0493842
X0587100Y0496342
X0610720Y0550862
X0598661Y0486922
X0622860Y0487310
X0601220Y0486922
X0606200Y0510862
X0600645Y0504362
X0645220Y0504362
X0607720Y0550862
X0642580Y0508172
X0650794Y0515039
X0661220Y0526862
X0665990Y0517131
X0584173Y0498422
X0583220Y0493212
X0655220Y0486862
X0663014Y0493860
X0591500Y0516862
X0670720Y0521862
X0629480Y0508862
X0611870Y0512560
X0623670Y0507862
X0591425Y0522337
X0578925Y0516846
X0637020Y0522362
X0594090Y0501957
X0583045Y0488212
X0648296Y0528255
X0646815Y0517974
X0614086Y0537624
X0593675Y0534702
X0614000Y0550800
X0657734Y0528255
X0661743Y0521166
X0656877Y0514716
X0636960Y0516002
X0609520Y0515162
X0606200Y0514862
X0594240Y0511953
X0589260Y0519421
X0653800Y0498740
X0649218Y0504277
X0594090Y0505107
X0571990Y0501046
X0603779Y0486922
X0593545Y0488212
X0590210Y0484132
X0629220Y0487310
X0670220Y0503837
X0663000Y0489500
X0663720Y0523806
X0661865Y0505334
X0591070Y0504900
X0629920Y0516652
X0671479Y0443211
X0667677Y0441636
X0626720Y0482880
X0604360Y0452120
X0595380Y0416660
X0671479Y0474707
X0667350Y0470680
X0577220Y0449462
X0668329Y0421163
X0592400Y0479162
X0671479Y0481006
X0665870Y0433942
X0609690Y0402812
X0652195Y0457862
X0637195Y0457862
X0617220Y0436362
X0595520Y0439762
X0637220Y0431362
X0668695Y0404262
X0668695Y0408362
X0670720Y0399862
X0644220Y0447862
X0640920Y0447862
X0638250Y0439250
X0622220Y0442862
X0614220Y0442862
X0629220Y0442862
X0640820Y0467862
X0629220Y0447862
X0625620Y0452862
X0591839Y0426112
X0610720Y0452862
X0640720Y0452862
X0629220Y0452862
X0637220Y0452862
X0622220Y0457862
X0614220Y0457862
X0625620Y0442862
X0610720Y0442862
X0625620Y0457862
X0610720Y0457862
X0578920Y0466462
X0637220Y0411362
X0622520Y0467862
X0614220Y0436362
X0668329Y0465258
X0622220Y0462862
X0655820Y0467662
X0599080Y0448062
X0637220Y0462862
X0614220Y0462862
X0640798Y0472934
X0637195Y0421362
X0605220Y0416362
X0637220Y0426362
X0629220Y0426362
X0671479Y0455809
X0637220Y0416362
X0629220Y0411362
X0625900Y0431050
X0629220Y0421362
X0643940Y0411482
X0641235Y0477377
X0640620Y0483422
X0644220Y0431362
X0624220Y0411362
X0644220Y0421362
X0671479Y0414864
X0625500Y0421362
X0640720Y0418862
X0668067Y0462090
X0671479Y0465258
X0645925Y0389937
X0632620Y0389862
X0643500Y0400962
X0628500Y0402362
X0610720Y0462862
X0649075Y0389937
X0653100Y0407862
X0626400Y0462812
X0652000Y0402362
X0647700Y0399162
X0636075Y0389862
X0638700Y0400962
X0668329Y0458959
X0655800Y0461432
X0671479Y0458959
X0600800Y0430900
X0592520Y0467662
X0668329Y0455809
X0671479Y0452659
X0668329Y0452659
X0610720Y0436362
X0605469Y0467562
X0655820Y0452662
X0602910Y0461862
X0640820Y0457902
X0622490Y0402162
X0580370Y0383670
X0625620Y0447862
X0597220Y0458688
X0599645Y0479862
X0644220Y0462862
X0644220Y0477862
X0629220Y0462862
X0644220Y0452862
X0629220Y0457862
X0614220Y0447862
X0644000Y0438862
X0628900Y0431050
X0591720Y0433937
X0658720Y0399862
X0622220Y0447862
X0640720Y0431362
X0622220Y0452862
X0668329Y0436911
X0671479Y0436911
X0575050Y0383602
X0571930Y0421232
X0643736Y0457214
X0614220Y0452862
X0668329Y0481006
X0644245Y0482862
X0629220Y0482862
X0644220Y0467862
X0644245Y0472862
X0629220Y0467862
X0629220Y0477862
X0629220Y0472862
X0610820Y0472862
X0671479Y0462108
X0600351Y0461862
X0671479Y0430612
X0629248Y0436972
X0599220Y0444362
X0604779Y0423862
X0591720Y0430787
X0668329Y0411714
X0660720Y0404362
X0660690Y0408162
X0605830Y0402782
X0644220Y0426362
X0581090Y0426970
X0626310Y0472902
X0637220Y0477862
X0614220Y0477862
X0626210Y0478002
X0637220Y0472862
X0614220Y0472862
X0626390Y0467882
X0637220Y0467862
X0614220Y0467862
X0584100Y0477952
X0667660Y0429037
X0671479Y0421163
X0647420Y0434162
X0623220Y0426362
X0574800Y0322462
X0630220Y0314362
X0633350Y0314362
X0586070Y0352302
X0572360Y0351962
X0605870Y0298172
X0615180Y0336812
X0605350Y0293092
X0619474Y0331162
X0607590Y0314732
X0605305Y0331162
X0605560Y0303372
X0614130Y0328762
X0590470Y0319192
X0583820Y0314662
X0590720Y0324582
X0590720Y0327862
X0577676Y0300268
X0662680Y0354362
X0590820Y0330962
X0588850Y0291622
X0593763Y0293999
X0632143Y0306575
X0643800Y0310962
X0627600Y0309134
X0645990Y0314482
X0627950Y0298897
X0643800Y0298297
X0633150Y0301457
X0643800Y0302247
X0586185Y0363271
X0583685Y0363271
X0595520Y0314862
X0599620Y0314762
X0651520Y0378662
X0621720Y0373362
X0619100Y0374638
X0662891Y0357442
X0647100Y0357372
X0631146Y0317768
X0643800Y0306547
X0643800Y0294327
X0623365Y0316742
X0615635Y0317637
X0609040Y0317282
X0591727Y0285862
X0582510Y0311571
X0582510Y0304052
X0582510Y0296657
X0574491Y0376549
X0577480Y0303822
X0577720Y0381862
X0605898Y0372984
X0609844Y0330407
X0623580Y0336429
X0582436Y0361032
X0633138Y0296766
X0645807Y0304291
X0645876Y0296231
X0645528Y0308623
X0628294Y0317007
X0647200Y0354300
X0608830Y0374302
X0592920Y0326362
X0597820Y0317062
X0625800Y0311912
X0586820Y0314662
X0580400Y0302402
X0590350Y0294402
X0588577Y0285862
X0593120Y0342782
X0595415Y0246515
X0626640Y0188752
X0613970Y0188752
X0630040Y0188752
X0617370Y0188752
X0592220Y0249362
X0593220Y0184887
X0599720Y0184887
X0659880Y0208262
X0659880Y0205762
X0659880Y0210762
X0662780Y0207862
X0662780Y0205362
X0662780Y0210362
X0591310Y0219582
X0579481Y0194378
X0662560Y0214152
X0650705Y0270947
X0622730Y0230362
X0578450Y0218562
X0578390Y0225362
X0640295Y0234237
X0645109Y0260202
X0645109Y0249202
X0621060Y0271066
X0629564Y0253127
X0630795Y0236862
X0611381Y0200378
X0575359Y0265132
X0579481Y0206378
X0579170Y0190092
X0579481Y0198378
X0631730Y0216472
X0628730Y0216472
X0631730Y0224472
X0631730Y0220472
X0628730Y0224472
X0628730Y0220472
X0611381Y0209878
X0584795Y0233362
X0579245Y0221362
X0581755Y0236978
X0618470Y0265732
X0614200Y0265792
X0578711Y0230109
X0580712Y0215877
X0596581Y0184849
X0623150Y0273172
X0621740Y0265952
X0629564Y0256277
X0611310Y0266272
X0606719Y0254966
X0592039Y0252202
X0578509Y0265132
X0627645Y0236862
X0667020Y0225762
X0593966Y0229965
X0581645Y0233362
X0609456Y0204994
X0614531Y0209878
X0598760Y0203712
X0603340Y0208142
X0579481Y0210378
X0620030Y0188782
X0625862Y0191248
X0630818Y0191248
X0611030Y0188372
X0614531Y0200378
X0579481Y0202378
X0642480Y0184862
X0645263Y0235689
X0668300Y0132400
X0603019Y0146399
X0602580Y0151052
X0615572Y0176442
X0615573Y0179484
X0615970Y0161522
X0630951Y0119182
X0631290Y0153702
X0606190Y0144002
X0606040Y0153432
X0632300Y0104472
X0639901Y0103462
X0639970Y0113892
X0640000Y0108542
X0590680Y0083591
X0590281Y0180698
X0596795Y0179287
X0665650Y0147692
X0662880Y0146912
X0662880Y0149912
X0634690Y0085542
X0640220Y0085542
X0573360Y0140532
X0598390Y0126802
X0581120Y0155062
X0589690Y0161732
X0598410Y0124102
X0662498Y0124960
X0628194Y0172872
X0628195Y0175914
X0670800Y0085932
X0671320Y0091192
X0594720Y0097220
X0600220Y0096862
X0651730Y0177212
X0649870Y0181942
X0603880Y0093902
X0617409Y0094162
X0613020Y0094162
X0620540Y0100112
X0606020Y0084562
X0617585Y0097257
X0608620Y0094162
X0623300Y0095762
X0647220Y0096929
X0603720Y0098362
X0643170Y0171362
X0650790Y0140699
X0650790Y0149871
X0626699Y0119182
X0614384Y0119342
X0592220Y0173862
X0588245Y0132142
X0573115Y0161232
X0597287Y0094262
X0592307Y0094262
X0640130Y0166362
X0590337Y0177604
X0601050Y0100008
X0631546Y0085024
X0628194Y0170372
X0628195Y0178414
X0615573Y0181984
X0615572Y0173942
X0631300Y0167872
X0606260Y0161652
X0598295Y0171862
X0593248Y0159480
X0581175Y0164717
X0650790Y0144982
X0612670Y0142872
X0612520Y0154812
X0624610Y0142842
X0624520Y0154622
X0588000Y0140922
X0595220Y0140922
X0592710Y0156342
X0602306Y0143077
X0602430Y0153862
X0651980Y0133822
X0591395Y0132142
X0637500Y0110362
X0632640Y0107532
X0618460Y0119342
X0610104Y0119342
X0659000Y0089262
X0651579Y0102703
X0652680Y0089712
X0652153Y0098105
X0579080Y0119402
X0652320Y0123362
X0586600Y0060602
X0641200Y0046762
X0647447Y0046322
X0634500Y0073422
X0637000Y0068142
X0720308Y-0026403
X0714030Y-0025097
X0714015Y-0027612
X0717298Y-0025111
X0717313Y-0027626
X0714015Y-0017583
X0717313Y-0017597
X0717313Y-0021471
X0714015Y-0021457
X0725537Y-0019022
X0725537Y-0023978
X0575330Y0047672
X0601220Y0076862
X0601220Y0073862
X0622271Y0044782
X0624140Y0046672
X0670612Y0047264
X0667940Y0080142
X0635000Y0057362
X0638500Y0057362
X0593369Y0045682
X0597955Y0048047
X0599800Y0043152
X0603063Y0048023
X0614400Y0046012
X0615170Y0073812
X0619562Y0049193
X0615220Y0076862
X0629820Y0045062
X0643880Y0042142
X0611810Y0034400
X0629820Y0042562
X0622271Y0057952
X0624633Y0049193
X0645330Y0072972
X0645330Y0077132
X0661587Y0069662
X0656426Y0075431
X0657165Y0079131
X0656500Y0069662
X0651680Y0073812
X0586260Y0052222
X0573190Y0042912
X0577300Y0066682
X0628590Y0058622
X0651943Y0033535
X0616675Y0031777
X0629000Y0067362
X0666943Y0043328
X0663543Y0043328
X0659839Y0047264
X0656439Y0047264
X0572500Y0032862
X0606880Y0044682
X0612822Y0043232
X0581500Y0041862
X0637220Y0031462
X0632463Y0043302
X0607890Y0034389
X0666406Y0069508
X0645350Y0060612
X0645150Y0069508
X0603374Y0069508
X0615185Y0069508
X0668768Y0049193
X0668800Y0045262
X0669004Y0041698
X0654595Y0049193
X0661681Y0049193
X0654464Y0045133
X0661550Y0045133
X0661534Y0041748
X0646440Y0043632
X0615185Y0049193
X0605060Y0042402
X0615420Y0042342
X0593925Y0049193
X0596840Y0045152
X0578620Y0045112
X0577880Y0075442
X0584950Y0054842
X0656950Y0059012
X0579930Y0072052
X0723041Y-0023200
X0723041Y-0019800
X0661600Y0075562
X0728591Y0071960
X0727700Y0060562
X0728090Y0075132
X0720308Y-0006345
X0720308Y-0016374
X0717313Y-0011442
X0714015Y-0011428
X0714030Y-0015068
X0717298Y-0015082
X0714030Y-0005039
X0714015Y-0007554
X0717298Y-0005053
X0717313Y-0007568
X0725537Y-0009022
X0725537Y-0013978
X0740819Y0082362
X0696727Y0081552
X0696370Y0078512
X0690510Y0059132
X0703100Y0058157
X0706867Y0058197
X0735880Y0060662
X0742620Y0071762
X0672250Y0040812
X0678050Y0058157
X0677560Y0040572
X0681980Y0058157
X0701838Y0047940
X0718900Y0069662
X0701838Y0042202
X0721990Y0069762
X0680200Y0039062
X0689940Y0038952
X0674012Y0047264
X0717320Y0044062
X0736193Y0071436
X0732793Y0071436
X0725740Y0069580
X0674035Y0074522
X0674540Y0080652
X0680578Y0075992
X0692389Y0046439
X0692289Y0040633
X0687344Y0046940
X0700500Y0074862
X0694400Y0058157
X0687120Y0039632
X0710200Y0069662
X0697720Y0058162
X0682290Y0046822
X0683440Y0042832
X0718425Y0077882
X0722415Y0077862
X0696838Y0047940
X0713000Y0069662
X0710486Y0077695
X0715990Y0069662
X0696800Y0042108
X0747487Y0071429
X0712500Y0079862
X0706370Y0046782
X0685968Y0058157
X0760700Y0062442
X0760700Y0059942
X0758200Y0062442
X0758200Y0059942
X0755700Y0062442
X0755700Y0059942
X0758620Y0051602
X0754620Y0051602
X0699475Y0069982
X0719949Y0058862
X0724644Y0058362
X0719820Y0045862
X0724620Y0040062
X0737595Y0057932
X0741377Y0057932
X0736620Y0045262
X0740100Y0041162
X0729293Y0058062
X0733642Y0058062
X0728720Y0043562
X0733314Y0040862
X0745474Y0057932
X0749477Y0057932
X0745900Y0040362
X0746100Y0046262
X0700741Y0083050
X0675225Y0058108
X0682890Y0072642
X0673750Y0077692
X0683820Y0079192
X0685230Y0076952
X0687050Y0079212
X0754219Y0075707
X0769474Y0075360
X0752720Y0059002
X0731330Y0060712
X0730957Y0069508
X0738043Y0069508
X0745130Y0069508
X0700610Y0057782
X0682941Y0069982
X0747487Y0049062
X0736790Y0039832
X0742840Y0039832
X0744987Y0049062
X0728980Y0039872
X0722580Y0049182
X0701838Y0045112
X0692380Y0043532
X0686854Y0043701
X0696838Y0045112
X0672005Y0044119
X0675854Y0049193
X0765606Y0044894
X0758606Y0023797
X0685780Y0070022
X0687664Y0073202
X0690027Y0070142
X0692389Y0072692
X0694751Y0070212
X0701400Y0072112
X0703900Y0072112
X0696700Y0072462
X0723041Y-0009800
X0723041Y-0013200
X0675560Y0117120
X0738600Y0136600
X0760390Y0111810
X0687034Y0115896
X0687030Y0113090
X0677790Y0104880
X0757340Y0092562
X0703000Y0084862
X0705390Y0085792
X0719100Y0085262
X0741308Y0108742
X0720633Y0160788
X0739823Y0091052
X0707008Y0125804
X0697615Y0123697
X0729933Y0108388
X0735770Y0094988
X0750033Y0089988
X0750033Y0092888
X0697720Y0104862
X0701220Y0104862
X0702720Y0102162
X0699220Y0102162
X0706720Y0100462
X0696727Y0084052
X0698710Y0086035
X0694220Y0104862
X0695720Y0102162
X0754800Y0097082
X0688019Y0109845
X0745035Y0094632
X0700600Y0125309
X0750700Y0106642
X0712340Y0128093
X0736720Y0101662
X0740220Y0145362
X0718213Y0159241
X0687238Y0171071
X0771426Y0158026
X0677820Y0089462
X0673987Y0087662
X0751220Y0137864
X0757693Y0096423
X0757693Y0100653
X0715940Y0157362
X0712290Y0106722
X0677978Y0115668
X0677978Y0119668
X0674145Y0113487
X0716698Y0177087
X0716698Y0173687
X0704770Y0179599
X0704770Y0182999
X0747230Y0108572
X0748033Y0116288
X0745725Y0167537
X0723133Y0124488
X0719933Y0124488
X0728733Y0126388
X0717433Y0135088
X0720433Y0135088
X0728733Y0129288
X0728733Y0132088
X0715933Y0114588
X0715933Y0117488
X0727518Y0090984
X0702141Y0112678
X0705685Y0112678
X0698598Y0112678
X0702141Y0115178
X0705685Y0115178
X0698598Y0115178
X0712733Y0114588
X0712733Y0117488
X0695055Y0115178
X0695055Y0112678
X0681053Y0104668
X0762368Y0084088
X0765858Y0087340
X0767028Y0091490
X0767045Y0095960
X0767061Y0099959
X0769284Y0103895
X0769775Y0107977
X0771131Y0111788
X0758110Y0172636
X0714202Y0177865
X0719194Y0177865
X0714202Y0172909
X0719194Y0172909
X0701926Y0172441
X0701926Y0178346
X0771774Y0167518
X0701926Y0166535
X0766769Y0140138
X0724133Y0141288
X0692520Y0152482
X0688520Y0152482
X0684520Y0152482
X0684953Y0104968
X0694390Y0133682
X0712433Y0103308
X0704880Y0133643
X0703520Y0122540
X0706673Y0122762
X0728023Y0098058
X0728028Y0101968
X0728028Y0105468
X0730820Y0084062
X0734523Y0098758
X0737623Y0098858
X0735733Y0111988
X0754633Y0105288
X0754633Y0108288
X0762172Y0123898
X0762198Y0126684
X0762198Y0129684
X0736060Y0145532
X0673720Y0110362
X0705800Y0167788
X0705800Y0171188
X0747200Y0251500
X0734220Y0238362
X0771630Y0258102
X0763320Y0264892
X0766320Y0264892
X0719720Y0220142
X0732720Y0231362
X0717020Y0220862
X0759920Y0280562
X0758720Y0283262
X0757150Y0280592
X0762420Y0280562
X0716698Y0189087
X0716698Y0200587
X0716698Y0212421
X0716698Y0185687
X0716698Y0197187
X0716698Y0209021
X0704770Y0191410
X0704770Y0203221
X0704770Y0215032
X0704770Y0194810
X0704770Y0206621
X0704770Y0218432
X0758360Y0276122
X0748085Y0278942
X0761720Y0283262
X0745685Y0269322
X0745685Y0265322
X0764850Y0249792
X0701926Y0219685
X0686760Y0222912
X0714202Y0213199
X0719194Y0213199
X0714202Y0208243
X0719194Y0208243
X0701926Y0213779
X0701926Y0207874
X0714202Y0201365
X0719194Y0201365
X0714202Y0196409
X0719194Y0196409
X0714202Y0189865
X0719194Y0189865
X0701926Y0201968
X0701926Y0196063
X0701926Y0190157
X0673690Y0200672
X0673300Y0211332
X0714202Y0184909
X0719194Y0184909
X0701926Y0184252
X0673713Y0237725
X0732700Y0351500
X0731400Y0375000
X0731400Y0365500
X0727000Y0374100
X0735800Y0375000
X0722500Y0374100
X0758390Y0295450
X0727000Y0365500
X0735800Y0365500
X0765000Y0354862
X0683500Y0381200
X0705700Y0361400
X0683100Y0369550
X0715600Y0363900
X0721989Y0351234
X0724897Y0353887
X0735600Y0351400
X0722500Y0365500
X0764000Y0369662
X0757936Y0303908
X0709000Y0354000
X0742720Y0380262
X0748820Y0284562
X0736220Y0380787
X0713220Y0378362
X0710600Y0364282
X0705600Y0364282
X0700600Y0364282
X0695600Y0364282
X0690600Y0364282
X0685600Y0364282
X0680600Y0364282
X0760670Y0317432
X0759637Y0311585
X0744247Y0312598
X0755305Y0298847
X0748498Y0309640
X0769789Y0296231
X0758412Y0298790
X0771377Y0314139
X0742090Y0356082
X0718720Y0381892
X0709400Y0378200
X0715600Y0375462
X0725220Y0380787
X0705600Y0375462
X0700600Y0375462
X0695600Y0375462
X0690600Y0375462
X0685600Y0375462
X0680600Y0375462
X0727720Y0356362
X0755200Y0296062
X0754290Y0286632
X0740200Y0375100
X0741800Y0363200
X0674731Y0359924
X0768490Y0354942
X0767960Y0369662
X0771490Y0354942
X0769860Y0302462
X0677778Y0427462
X0680928Y0430612
X0712424Y0471557
X0718723Y0477856
X0693526Y0477856
X0699825Y0424313
X0696676Y0418013
X0696676Y0424313
X0768910Y0403260
X0696676Y0421163
X0699825Y0430612
X0699826Y0414864
X0725022Y0465258
X0731322Y0440061
X0718723Y0462108
X0699825Y0427462
X0684077Y0458959
X0721873Y0462108
X0728172Y0471557
X0687227Y0433761
X0699825Y0462108
X0699825Y0465258
X0734471Y0458959
X0734471Y0481006
X0728172Y0474707
X0721873Y0468407
X0721873Y0474707
X0690376Y0424313
X0693526Y0424313
X0693526Y0421163
X0696676Y0430612
X0707400Y0396200
X0696676Y0427462
X0728172Y0468407
X0740740Y0473822
X0731322Y0471557
X0731321Y0474707
X0687227Y0458959
X0677778Y0468407
X0696676Y0471557
X0728172Y0424313
X0728172Y0440061
X0718723Y0458959
X0731322Y0468407
X0734471Y0468407
X0692402Y0391250
X0715574Y0418013
X0715574Y0421163
X0715574Y0424313
X0685220Y0391652
X0712770Y0406822
X0705780Y0411022
X0692330Y0388751
X0692400Y0404682
X0713220Y0388362
X0706125Y0477856
X0706125Y0481006
X0731322Y0449510
X0731322Y0443210
X0725022Y0449510
X0725022Y0443210
X0721873Y0449510
X0737621Y0443210
X0734471Y0443210
X0718723Y0449510
X0721873Y0443210
X0718723Y0443210
X0737621Y0471557
X0731322Y0436911
X0690376Y0430612
X0687227Y0427462
X0684077Y0424313
X0680928Y0421163
X0687227Y0430612
X0684077Y0427462
X0677778Y0421163
X0677778Y0418013
X0712424Y0424313
X0738220Y0383862
X0718723Y0421163
X0718723Y0424313
X0718723Y0427462
X0731322Y0414864
X0699825Y0474707
X0699825Y0471557
X0693526Y0474707
X0709160Y0386730
X0725022Y0440061
X0696676Y0468407
X0696676Y0474707
X0696676Y0462108
X0696676Y0465258
X0684077Y0433761
X0696676Y0433761
X0693526Y0433761
X0684077Y0418013
X0685270Y0404262
X0685270Y0408362
X0687500Y0399402
X0706125Y0433761
X0699825Y0433761
X0706125Y0418013
X0705195Y0404262
X0705195Y0408362
X0707220Y0399362
X0725022Y0418013
X0725220Y0399862
X0723195Y0404262
X0723195Y0408362
X0712424Y0433761
X0709274Y0433761
X0733720Y0399862
X0735745Y0404262
X0735745Y0408362
X0728172Y0462108
X0715574Y0455809
X0715574Y0452659
X0715574Y0449510
X0728172Y0430612
X0728172Y0443210
X0715574Y0443210
X0715574Y0440061
X0715574Y0436911
X0725022Y0474707
X0706125Y0468407
X0712424Y0458959
X0709274Y0458959
X0706125Y0458959
X0699825Y0458959
X0686120Y0481862
X0694510Y0482942
X0690580Y0482992
X0684077Y0474707
X0696676Y0458959
X0693526Y0458959
X0687227Y0452659
X0690376Y0455809
X0690376Y0449510
X0687227Y0440061
X0690376Y0443210
X0690376Y0436911
X0674628Y0462108
X0674628Y0449510
X0674628Y0430612
X0680928Y0443210
X0680928Y0440061
X0731322Y0477856
X0684077Y0436911
X0684077Y0443210
X0677778Y0443210
X0687227Y0443210
X0687227Y0436911
X0684077Y0440061
X0673220Y0388362
X0680928Y0427462
X0684077Y0430612
X0728172Y0465258
X0674628Y0418013
X0709274Y0452659
X0706125Y0449510
X0699825Y0449510
X0709274Y0449510
X0699825Y0443210
X0706125Y0443210
X0709274Y0443210
X0709274Y0440061
X0696676Y0452659
X0696676Y0449510
X0696676Y0443210
X0696676Y0440061
X0677778Y0465258
X0680928Y0462108
X0680928Y0458959
X0718723Y0465258
X0674628Y0421163
X0725022Y0471557
X0731322Y0421163
X0757430Y0408212
X0731322Y0452659
X0757365Y0459862
X0721873Y0471557
X0728172Y0477856
X0677778Y0424313
X0747554Y0384962
X0728172Y0436911
X0677778Y0462108
X0674628Y0465258
X0684077Y0455809
X0674628Y0455809
X0687227Y0455809
X0677778Y0455809
X0677778Y0458959
X0674628Y0458959
X0768701Y0418662
X0718723Y0452659
X0725022Y0462108
X0731322Y0465258
X0684077Y0421163
X0680928Y0418013
X0680928Y0414864
X0690376Y0427462
X0687227Y0424313
X0677778Y0414864
X0725022Y0430612
X0728172Y0427462
X0721873Y0455809
X0706125Y0471557
X0725022Y0421163
X0742160Y0396452
X0721873Y0424313
X0735220Y0410842
X0725022Y0458959
X0693526Y0468407
X0677778Y0452659
X0674628Y0452659
X0687227Y0468407
X0684077Y0452659
X0690376Y0474707
X0687227Y0465258
X0690376Y0471557
X0680928Y0452659
X0690376Y0477856
X0690376Y0468407
X0684077Y0449510
X0690376Y0462108
X0737621Y0424313
X0734471Y0424313
X0693526Y0471557
X0677778Y0449510
X0687227Y0449510
X0680928Y0449510
X0693526Y0465258
X0694920Y0388797
X0693526Y0462108
X0718723Y0471557
X0718723Y0474707
X0715574Y0462108
X0715574Y0465258
X0715574Y0468407
X0715574Y0471557
X0715574Y0474707
X0728272Y0481006
X0693526Y0427462
X0693526Y0430612
X0690376Y0414864
X0690376Y0418013
X0690376Y0421163
X0685210Y0388852
X0687227Y0414864
X0728220Y0388362
X0677778Y0436911
X0731322Y0424313
X0765335Y0469552
X0766195Y0428212
X0766195Y0423212
X0766195Y0413212
X0745720Y0399862
X0713220Y0399862
X0695220Y0399862
X0675295Y0399862
X0718723Y0468407
X0674628Y0440061
X0680928Y0433761
X0680928Y0436911
X0677778Y0440061
X0680928Y0455809
X0734471Y0436911
X0677778Y0433761
X0765315Y0459862
X0765315Y0454862
X0734471Y0452659
X0734471Y0421163
X0728172Y0452659
X0768720Y0459862
X0725022Y0452659
X0721873Y0452659
X0738220Y0388362
X0712424Y0430612
X0731322Y0418013
X0715574Y0430612
X0725022Y0424313
X0718723Y0414864
X0728172Y0421163
X0715574Y0427462
X0718723Y0418013
X0711200Y0396500
X0718723Y0430612
X0702975Y0414864
X0737621Y0481006
X0765315Y0464862
X0725022Y0477856
X0699825Y0468407
X0709274Y0477856
X0680928Y0468407
X0684077Y0477856
X0696676Y0477856
X0731322Y0462108
X0728172Y0449510
X0715574Y0458959
X0690376Y0458959
X0690376Y0452659
X0758420Y0447662
X0759940Y0438232
X0731322Y0430612
X0715574Y0433761
X0690376Y0433761
X0690376Y0440061
X0693526Y0436911
X0693526Y0440061
X0693526Y0443210
X0696676Y0436911
X0693526Y0455809
X0696676Y0455809
X0693526Y0449510
X0693526Y0452659
X0712424Y0436911
X0712424Y0440061
X0712424Y0443210
X0699825Y0436911
X0699825Y0440061
X0706125Y0436911
X0706125Y0440061
X0709274Y0436911
X0712424Y0449510
X0712424Y0452659
X0699825Y0452659
X0699825Y0455809
X0706125Y0452659
X0706125Y0455809
X0709274Y0455809
X0712424Y0455809
X0674628Y0443210
X0766195Y0418212
X0725022Y0414864
X0706125Y0421163
X0680928Y0424313
X0684077Y0414864
X0674628Y0414864
X0743820Y0408262
X0743720Y0404362
X0737621Y0411714
X0715120Y0408262
X0715220Y0404362
X0697120Y0408262
X0697220Y0404362
X0677195Y0408262
X0677295Y0404362
X0733220Y0388362
X0718220Y0388362
X0688220Y0388362
X0731322Y0458959
X0728172Y0418013
X0750290Y0462162
X0737621Y0458959
X0674628Y0436911
X0721873Y0477856
X0721873Y0458959
X0677778Y0430612
X0674628Y0427462
X0728172Y0433761
X0712424Y0465258
X0712424Y0468407
X0725022Y0433761
X0680928Y0477856
X0680928Y0474707
X0680928Y0471557
X0677778Y0474707
X0677778Y0471557
X0677778Y0477856
X0687227Y0462108
X0684077Y0465258
X0725022Y0436911
X0725132Y0481116
X0718723Y0440061
X0718723Y0433761
X0771050Y0416940
X0721873Y0430612
X0690376Y0465258
X0684077Y0471557
X0765360Y0475412
X0687227Y0477856
X0687227Y0474707
X0731322Y0455809
X0718723Y0455809
X0731322Y0433761
X0721873Y0465258
X0731322Y0427462
X0721873Y0440061
X0687227Y0471557
X0728172Y0458959
X0712424Y0462108
X0709274Y0462108
X0712424Y0474707
X0706125Y0462108
X0709274Y0468407
X0709274Y0465258
X0709274Y0471557
X0709274Y0474707
X0674628Y0424313
X0721873Y0436911
X0765315Y0479862
X0721873Y0433761
X0725022Y0468407
X0718723Y0436911
X0728172Y0455809
X0684077Y0468407
X0725022Y0427462
X0766195Y0403212
X0734471Y0418013
X0721873Y0427462
X0766195Y0393212
X0743980Y0443482
X0760469Y0442647
X0729212Y0531700
X0695257Y0503847
X0765386Y0483572
X0757238Y0483862
X0690330Y0503530
X0754220Y0530462
X0690220Y0495887
X0695220Y0495887
X0761710Y0517651
X0756650Y0526072
X0755940Y0516862
X0752500Y0495762
X0733117Y0582571
X0769745Y0502600
X0733117Y0580071
X0765810Y0506342
X0695220Y0530662
X0735173Y0521362
X0695220Y0519662
X0766510Y0493452
X0705720Y0484862
X0703220Y0490362
X0705720Y0488862
X0756642Y0501744
X0673340Y0530922
X0680220Y0530362
X0698602Y0580536
X0765521Y0525364
X0711220Y0508882
X0705220Y0508862
X0759820Y0530462
X0689720Y0530862
X0690220Y0519662
X0680220Y0508862
X0690220Y0508882
X0685220Y0495887
X0685220Y0503837
X0722707Y0579371
X0733922Y0531712
X0725207Y0579371
X0738980Y0531722
X0736480Y0531722
X0740840Y0521982
X0735220Y0503842
X0759790Y0525522
X0717220Y0516852
X0705220Y0503842
X0711220Y0503842
X0714000Y0496132
X0717220Y0503842
X0723220Y0503842
X0729220Y0503842
X0685220Y0516852
X0729220Y0516852
X0723220Y0516852
X0730220Y0523362
X0745220Y0516852
X0751220Y0516852
X0683320Y0490662
X0756642Y0496522
X0717296Y0525407
X0741420Y0494162
X0729328Y0583076
X0757020Y0530462
X0698600Y0530700
X0751220Y0530362
X0745220Y0530362
X0722720Y0521362
X0705220Y0516852
X0711220Y0516852
X0690220Y0516852
X0675220Y0516852
X0744630Y0506529
X0730070Y0506212
X0680220Y0503837
X0675220Y0503837
X0765315Y0488862
X0713820Y0484662
X0713820Y0488762
X0690720Y0491962
X0694720Y0491962
X0751220Y0522362
X0745220Y0522362
X0690220Y0506362
X0675220Y0521862
X0674628Y0484006
X0735430Y0516862
X0685220Y0508862
X0680220Y0495887
X0745220Y0503842
X0701757Y0521324
X0705220Y0530362
X0765720Y0530362
X0717220Y0521362
X0705220Y0521362
X0729220Y0508882
X0710720Y0521362
X0728220Y0521362
X0695220Y0508862
X0695220Y0516852
X0769220Y0530362
X0735220Y0508862
X0747600Y0506592
X0723120Y0525362
X0717220Y0508882
X0723220Y0508882
X0675220Y0508862
X0735620Y0613862
X0702740Y0594020
X0705240Y0594020
X0733134Y0585672
X0723340Y0642922
X0715220Y0643262
X0717720Y0643262
X0715860Y0585540
X0715420Y0639162
X0708680Y0638812
X0704320Y0645262
X0712060Y0638542
X0708310Y0646032
X0720240Y0598292
X0730690Y0655532
X0723450Y0597072
X0719190Y0646642
X0729295Y0586113
X0739206Y0603064
X0739206Y0608020
X0729200Y0588952
X0714320Y0597462
X0710940Y0591172
X0736710Y0607242
X0736710Y0603842
X0764921Y0742095
X0767421Y0742095
X0769921Y0742095
X0677887Y0742121
X0703545Y0745907
X0700500Y0745862
X0683457Y0745175
X0673617Y0744735
X0740820Y0741762
X0762617Y0758885
X0762562Y0746444
X0730889Y0746834
X0704000Y0740862
X0737609Y0744282
X0744538Y0746524
X0769337Y0760775
X0714087Y0745865
X0737299Y0766887
X0753137Y0766625
X0763747Y0764335
X0701917Y0742865
X0684357Y0742345
X0720697Y0765862
X0726141Y1255381
X0723460Y1245632
X0707320Y1301162
X0704795Y1294559
X0705720Y1286662
X0707720Y1290162
X0692280Y1302532
X0696810Y1300162
X0714720Y1286162
X0711720Y1286162
X0768520Y1375462
X0723054Y1341396
X0723054Y1343896
X0723054Y1346396
X0723054Y1348896
X0728104Y1341396
X0728104Y1343896
X0725604Y1341396
X0725604Y1343896
X0728104Y1348896
X0725604Y1348896
X0728104Y1346396
X0725604Y1346396
X0723054Y1338896
X0728104Y1336396
X0728104Y1338896
X0725604Y1336396
X0723054Y1336396
X0725604Y1338896
X0728104Y1333896
X0725604Y1333896
X0723054Y1333896
X0708137Y1346396
X0708137Y1348896
X0705587Y1343896
X0703087Y1343896
X0703087Y1341396
X0705587Y1341396
X0708137Y1343896
X0708137Y1341396
X0705587Y1348896
X0703087Y1348896
X0705587Y1346396
X0703087Y1346396
X0703087Y1333896
X0705587Y1333896
X0708137Y1333896
X0703087Y1338896
X0705587Y1338896
X0705587Y1336396
X0703087Y1336396
X0708137Y1338896
X0708137Y1336396
X0687105Y1343896
X0687105Y1341396
X0689605Y1343896
X0689605Y1341396
X0684555Y1348896
X0684555Y1346396
X0684555Y1343896
X0684555Y1341396
X0687105Y1346396
X0689605Y1346396
X0687105Y1348896
X0689605Y1348896
X0684555Y1333896
X0687105Y1333896
X0689605Y1333896
X0687105Y1338896
X0684555Y1336396
X0687105Y1336396
X0689605Y1338896
X0689605Y1336396
X0684555Y1338896
X0757720Y1375462
X0768195Y1293342
X0765205Y1293272
X0768335Y1290612
X0768335Y1287612
X0765345Y1290542
X0765345Y1287542
X0768335Y1284612
X0765345Y1284542
X0762205Y1293272
X0762345Y1290542
X0762345Y1287542
X0762345Y1284542
X0703755Y1290545
X0713836Y1283689
X0708795Y1303701
X0692784Y1298845
X0768520Y1379962
X0678517Y1360815
X0676017Y1360815
X0673517Y1360815
X0695022Y1361990
X0686426Y1360822
X0696462Y1380922
X0696462Y1383522
X0696462Y1378322
X0688751Y1378322
X0691351Y1378322
X0693851Y1380922
X0693851Y1378322
X0693851Y1383522
X0691240Y1383522
X0688751Y1380922
X0691351Y1380922
X0712060Y1360815
X0706239Y1360822
X0698094Y1361947
X0701662Y1378322
X0701662Y1383522
X0701662Y1380922
X0699062Y1378322
X0699062Y1383522
X0699062Y1380922
X0729443Y1361224
X0717060Y1360815
X0714560Y1360815
X0724969Y1360822
X0729294Y1378983
X0729294Y1381583
X0726694Y1378983
X0726694Y1381583
X0737784Y1360017
X0731794Y1378983
X0731794Y1381583
X0729920Y1402694
X0729920Y1399794
X0732226Y1396212
X0729920Y1405594
X0725014Y1400030
X0720354Y1400030
X0722684Y1399280
X0718024Y1399280
X0727820Y1404194
X0727720Y1401194
X0725654Y1402924
X0725654Y1405824
X0699784Y1422614
X0699694Y1430449
X0699694Y1425449
X0699694Y1427949
X0699754Y1419809
X0696784Y1422614
X0696694Y1430449
X0696694Y1425449
X0696694Y1427949
X0691129Y1423303
X0694129Y1423303
X0691129Y1420283
X0696754Y1419809
X0694129Y1420283
X0694596Y1396198
X0687511Y1405824
X0689677Y1404194
X0691777Y1402694
X0687511Y1402924
X0689577Y1401194
X0691777Y1399794
X0691777Y1405594
X0686871Y1400030
X0682211Y1400030
X0684541Y1399280
X0679881Y1399280
X0755420Y1422862
X0755420Y1426262
X0707620Y1409660
X0704446Y1403476
X0714019Y1406619
X0701330Y1397695
X0675876Y1406619
X0715762Y1408887
X0677619Y1408887
X0701330Y1395195
X0707620Y1406694
X0673477Y1409386
X0711620Y1409386
X0701830Y1407326
X0758420Y1406862
X0758020Y1397862
X0757720Y1384062
X0758120Y1414762
X0768620Y1397262
X0768520Y1384062
X0767820Y1414762
X0681899Y1428549
X0681899Y1431049
X0681899Y1426049
X0681899Y1434049
X0677319Y1430859
X0677319Y1433359
X0677319Y1428359
X0674149Y1428649
X0674149Y1431149
X0674149Y1426149
X0674149Y1434149
X0757779Y1390645
X0757542Y1420684
X0767820Y1410262
X0768620Y1392762
X0679737Y1384311
X0671937Y1387418
X0674537Y1387418
X0677137Y1387418
X0671937Y1384311
X0674537Y1384311
X0677137Y1384311
X0673820Y1394157
X0676250Y1394157
X0673820Y1399757
X0676250Y1399757
X0674737Y1390525
X0677337Y1390525
X0676312Y1411554
X0693851Y1386122
X0685881Y1387434
X0685881Y1384327
X0682937Y1384311
X0696462Y1386122
X0685850Y1390557
X0696272Y1404560
X0696940Y1437955
X0685015Y1438475
X0712680Y1387418
X0712680Y1384311
X0701662Y1386122
X0699062Y1386122
X0710080Y1387418
X0707480Y1387418
X0710080Y1384311
X0707480Y1384311
X0711963Y1394157
X0711963Y1399757
X0712880Y1390525
X0709493Y1394157
X0709493Y1399757
X0704568Y1414119
X0699262Y1413970
X0711440Y1436905
X0701730Y1437855
X0706680Y1437535
X0728044Y1384083
X0724024Y1387434
X0724024Y1384327
X0721080Y1384311
X0715280Y1387418
X0717880Y1384311
X0715280Y1384311
X0714393Y1394157
X0714393Y1399757
X0723993Y1390557
X0715480Y1390525
X0714455Y1411554
X0732238Y1388343
X0730752Y1384080
X0741670Y1405675
X0739170Y1405655
X0741540Y1396585
X0738810Y1396665
X0740760Y1414165
X0738170Y1414185
X0692026Y1580490
X0678621Y1571072
X0678619Y1579070
X0723942Y1574123
X0726465Y1582092
X0722465Y1582092
X0724465Y1580092
X0713052Y1579683
X0724712Y1566820
X0749612Y1583023
X0760152Y1583183
X0717402Y1574433
X0768714Y1571203
X0714162Y1574333
X0728977Y1574453
X0723520Y1561604
X0749612Y1579023
X0760112Y1579183
X0711102Y1575683
X0712222Y1570703
X0717300Y1547370
X0692100Y1567190
X0678877Y1566798
X0735882Y1580391
X0741382Y1580121
X0730282Y1580391
X0720370Y1566910
X0763152Y1573793
X0763152Y1577893
X0763152Y1581893
X0717152Y1570093
X0702112Y1579683
X0702112Y1575683
X0702112Y1571683
X0679207Y1560482
X0683930Y1557562
X0683930Y1552562
X0715792Y1567461
X0682160Y1548040
X0751336Y1562341
X0751336Y1559341
X0751336Y1565341
X0751336Y1568341
X0736336Y1574341
X0736336Y1571341
X0739336Y1571341
X0739336Y1574341
X0742336Y1571341
X0742336Y1574341
X0745336Y1571341
X0745336Y1574341
X0748336Y1571341
X0748336Y1574341
X0736336Y1562341
X0736336Y1559341
X0736336Y1565341
X0736336Y1568341
X0739336Y1568341
X0739336Y1565341
X0739336Y1559341
X0739336Y1562341
X0742336Y1568341
X0742336Y1565341
X0742336Y1559341
X0742336Y1562341
X0745336Y1568341
X0745336Y1565341
X0745336Y1559341
X0745336Y1562341
X0748336Y1568341
X0748336Y1565341
X0748336Y1559341
X0748336Y1562341
X0733336Y1571341
X0733336Y1574341
X0730336Y1562341
X0730336Y1559341
X0733336Y1562341
X0733336Y1559341
X0733336Y1565341
X0733336Y1568341
X0689875Y1577913
X0678515Y1573910
X0679192Y1564252
X0683930Y1555062
X0678610Y1582154
X0678900Y1592600
X0678900Y1589800
X0761716Y1661194
X0719168Y1612016
X0722630Y1655740
X0718758Y1673800
X0705516Y1620296
X0716688Y1610055
X0726810Y1652430
X0735300Y1648760
X0679270Y1604040
X0740840Y1655590
X0735080Y1662980
X0678771Y1585945
X0751620Y1674312
X0720987Y1599568
X0726092Y1598483
X0711350Y1590720
X0729052Y1602518
X0712512Y1596338
X0769452Y1584393
X0712582Y1584843
X0702112Y1595683
X0758360Y1589661
X0714380Y1589960
X0763152Y1594893
X0749612Y1594683
X0749662Y1590733
X0749652Y1586407
X0737080Y1655820
X0708830Y1623115
X0697595Y1666862
X0678900Y1595400
X0732705Y1669450
X0686220Y1640667
X0673420Y1650057
X0708857Y1613462
X0706103Y1617107
X0715775Y1599024
X0703719Y1646768
X0704759Y1677001
X0677940Y1670110
X0708999Y1646762
X0709678Y1658485
X0710570Y1629890
X0700460Y1660918
X0747504Y1606321
X0747504Y1603321
X0750504Y1609521
X0750504Y1612521
X0747504Y1612521
X0747504Y1609521
X0747504Y1600321
X0735504Y1606321
X0738504Y1606321
X0735504Y1603321
X0738504Y1603321
X0741504Y1606321
X0741504Y1603321
X0744504Y1606321
X0744504Y1603321
X0732504Y1606321
X0732504Y1603321
X0735504Y1612521
X0738504Y1612521
X0741504Y1612521
X0735504Y1609521
X0738504Y1609521
X0741504Y1609521
X0744504Y1612521
X0744504Y1609521
X0738504Y1600321
X0738504Y1597321
X0735504Y1600321
X0735504Y1597321
X0741504Y1600321
X0741504Y1597321
X0744504Y1600321
X0744504Y1597321
X0732504Y1597321
X0732504Y1600321
X0741382Y1590691
X0735882Y1590651
X0741382Y1585251
X0730282Y1585521
X0730282Y1590651
X0713102Y1601307
X0760112Y1587183
X0675710Y1620320
X0725910Y1611900
X0704370Y1604580
X0763152Y1590893
X0760112Y1592183
X0770252Y1587268
X0716612Y1584635
X0726465Y1588950
X0722465Y1588950
X0724465Y1590950
X0702112Y1591683
X0702112Y1587683
X0729150Y1641690
X0711780Y1614590
X0724500Y1680400
X0679640Y1614000
X0679640Y1617520
X0697730Y1677460
X0687045Y1673362
X0714071Y1663842
X0697595Y1662862
X0714203Y1642926
X0710540Y1636070
X0689200Y1648843
X0697122Y1636667
X0697197Y1640667
X0721488Y1610945
X0704497Y1598927
X0718195Y1647300
X0723542Y1612702
X0709111Y1618842
X0718230Y1600372
X0713791Y1629816
X0704433Y1657964
X0716140Y1649895
X0726830Y1655380
X0715780Y1614590
X0719770Y1614590
X0722040Y1623970
X0721345Y1647300
X0724500Y1676500
X0758830Y1674823
X0742655Y1678362
X0742655Y1682362
X0702462Y1673258
X0697770Y1680810
X0692595Y1670862
X0744800Y1664840
X0697595Y1658862
X0689128Y1652262
X0676648Y1657380
X0714203Y1639776
X0697197Y1644667
X0683592Y1634844
X0697122Y1632667
X0725378Y1614503
X0702112Y1583683
X0678490Y1695660
X0752875Y1726670
X0675120Y1716242
X0672270Y1721612
X0766880Y1689020
X0766603Y1721797
X0759359Y1729520
X0764920Y1695347
X0759859Y1686090
X0674195Y1728362
X0674195Y1712362
X0674195Y1732362
X0763359Y1729520
X0755183Y1709850
X0674195Y1708362
X0755859Y1686090
X0761770Y1695347
X0672895Y1737108
X0732895Y1737108
X0752895Y1737108
X0772208Y1731911
X0792208Y1731911
X0812208Y1731911
X0832208Y1731911
X0852208Y1731911
X0854777Y1586968
X0860652Y1590444
X0818652Y1590444
X0776922Y1590444
X0812698Y1587047
X0804652Y1589793
X0846652Y1589793
X0857551Y1593793
X0815551Y1593793
X0774052Y1590293
X0846652Y1609793
X0804652Y1609793
X0801652Y1584539
X0843652Y1584539
X0812652Y1601793
X0854652Y1601793
X0799152Y1586507
X0841152Y1586507
X0791052Y1603693
X0788052Y1603693
X0794052Y1603693
X0791052Y1597693
X0788052Y1597693
X0794052Y1597693
X0791052Y1600693
X0788052Y1600693
X0794052Y1600693
X0782052Y1603693
X0785052Y1603693
X0782052Y1600693
X0782052Y1597693
X0785052Y1597693
X0785052Y1600693
X0791052Y1611893
X0788052Y1611893
X0794052Y1611893
X0797052Y1611893
X0797052Y1607793
X0788052Y1607793
X0791052Y1607793
X0794052Y1607793
X0779052Y1611893
X0776052Y1611893
X0782052Y1611893
X0785052Y1611893
X0779052Y1607793
X0782052Y1607793
X0785052Y1607793
X0818052Y1611893
X0821052Y1607793
X0839052Y1607793
X0860052Y1611893
X0863052Y1607793
X0821052Y1611893
X0830052Y1603693
X0830052Y1607793
X0830052Y1611893
X0827052Y1603693
X0827052Y1607793
X0827052Y1611893
X0824052Y1603693
X0824052Y1607793
X0824052Y1611893
X0830052Y1597693
X0830052Y1600693
X0827052Y1597693
X0827052Y1600693
X0824052Y1600693
X0824052Y1597693
X0793579Y1585523
X0793579Y1590653
X0782479Y1585523
X0782479Y1590653
X0788079Y1590653
X0866479Y1585523
X0866052Y1600693
X0869052Y1600693
X0866479Y1590653
X0869052Y1597693
X0866052Y1597693
X0866052Y1611893
X0863052Y1611893
X0866052Y1607793
X0869052Y1611893
X0869052Y1607793
X0866052Y1603693
X0869052Y1603693
X0835579Y1585523
X0836052Y1600693
X0833052Y1600693
X0835579Y1590653
X0830079Y1590653
X0824479Y1585523
X0824479Y1590653
X0836052Y1597693
X0833052Y1597693
X0836052Y1611893
X0836052Y1607793
X0833052Y1611893
X0833052Y1607793
X0839052Y1611893
X0836052Y1603693
X0833052Y1603693
X0854652Y1605793
X0812652Y1605793
X0846652Y1585993
X0854652Y1593793
X0855352Y1590893
X0804652Y1585993
X0812652Y1593793
X0813352Y1590893
X0846652Y1597793
X0804652Y1597793
X0857652Y1573793
X0815652Y1573793
X0773952Y1580493
X0815652Y1582570
X0857652Y1582570
X0812652Y1577793
X0854652Y1577793
X0793579Y1580393
X0782479Y1580393
X0788079Y1580393
X0866479Y1580393
X0835579Y1580393
X0830079Y1580393
X0824479Y1580393
X0846652Y1573793
X0846652Y1581793
X0804652Y1573793
X0804652Y1581793
X0787352Y1574293
X0787352Y1571293
X0790352Y1571293
X0790352Y1574293
X0793352Y1571293
X0793352Y1574293
X0796352Y1571293
X0796352Y1574293
X0799352Y1571293
X0799352Y1574293
X0787352Y1562293
X0787352Y1559293
X0787352Y1565293
X0787352Y1568293
X0790352Y1568293
X0790352Y1565293
X0790352Y1559293
X0790352Y1562293
X0793352Y1568293
X0793352Y1565293
X0793352Y1559293
X0793352Y1562293
X0796352Y1568293
X0796352Y1565293
X0796352Y1559293
X0796352Y1562293
X0799352Y1568293
X0799352Y1565293
X0799352Y1559293
X0799352Y1562293
X0781352Y1571293
X0781352Y1574293
X0784352Y1571293
X0784352Y1574293
X0781352Y1562293
X0781352Y1559293
X0781352Y1565293
X0781352Y1568293
X0784352Y1562293
X0784352Y1559293
X0784352Y1565293
X0784352Y1568293
X0871352Y1574293
X0871352Y1571293
X0871352Y1562293
X0871352Y1559293
X0871352Y1565293
X0871352Y1568293
X0865352Y1571293
X0865352Y1574293
X0868352Y1571293
X0868352Y1574293
X0865352Y1562293
X0865352Y1559293
X0865352Y1565293
X0865352Y1568293
X0868352Y1562293
X0868352Y1559293
X0868352Y1565293
X0868352Y1568293
X0841352Y1574293
X0841352Y1571293
X0841352Y1562293
X0841352Y1559293
X0841352Y1565293
X0841352Y1568293
X0838352Y1574293
X0838352Y1571293
X0838352Y1562293
X0838352Y1559293
X0838352Y1565293
X0838352Y1568293
X0835352Y1574293
X0835352Y1571293
X0835352Y1562293
X0835352Y1559293
X0835352Y1565293
X0835352Y1568293
X0832352Y1574293
X0832352Y1571293
X0832352Y1562293
X0832352Y1559293
X0832352Y1565293
X0832352Y1568293
X0826352Y1568293
X0826352Y1559293
X0826352Y1562293
X0826352Y1565293
X0829352Y1568293
X0829352Y1559293
X0829352Y1562293
X0829352Y1571293
X0826352Y1574293
X0826352Y1571293
X0829352Y1574293
X0823352Y1568293
X0823352Y1559293
X0823352Y1562293
X0823352Y1565293
X0823352Y1574293
X0823352Y1571293
X0829352Y1565293
X0800000Y1431100
X0791260Y1388662
X0790380Y1432132
X0804100Y1435010
X0775375Y1403561
X0788225Y1388683
X0832090Y1341862
X0832090Y1336862
X0826090Y1329362
X0818420Y1344342
X0820920Y1344342
X0812130Y1343022
X0809210Y1343062
X0806323Y1343076
X0826090Y1344362
X0832090Y1326862
X0826090Y1339362
X0826090Y1334362
X0832090Y1331862
X0794905Y1293272
X0797895Y1293342
X0795045Y1287542
X0795045Y1290542
X0798035Y1287612
X0798035Y1290612
X0795045Y1284542
X0798035Y1284612
X0791905Y1293272
X0792045Y1287542
X0792045Y1290542
X0792045Y1284542
X0778005Y1294092
X0828910Y1331756
X0828799Y1336870
X0828910Y1341725
X0814234Y1340465
X0815241Y1255381
X0785541Y1255381
X0854620Y1242125
X0854237Y1250358
X0838020Y1232432
X0815789Y1008845
X0864700Y0778300
X0833120Y0743392
X0830587Y0741205
X0823589Y0746924
X0820613Y0744641
X0829420Y0758422
X0841997Y0773085
X0791140Y0761693
X0807000Y0757562
X0799577Y0760985
X0844957Y0763065
X0814770Y0763874
X0822374Y0757039
X0837127Y0758976
X0841827Y0766795
X0864680Y0751582
X0859450Y0750462
X0854687Y0761685
X0775317Y0764025
X0799637Y0763625
X0822442Y0762369
X0814800Y0760922
X0836847Y0762495
X0853200Y0751062
X0774384Y0744088
X0863925Y0737697
X0866820Y0736562
X0782515Y0766702
X0838587Y0766825
X0794157Y0761295
X0783507Y0761875
X0810850Y0770272
X0796702Y0761195
X0772020Y0746562
X0856520Y0751262
X0794720Y0617862
X0859054Y0583752
X0831530Y0651932
X0797200Y0599883
X0810720Y0586862
X0815120Y0593582
X0803220Y0594362
X0820470Y0595112
X0820220Y0586862
X0831705Y0593877
X0859888Y0593970
X0823720Y0594862
X0791969Y0618384
X0807945Y0594362
X0795720Y0614862
X0797720Y0617862
X0856698Y0594011
X0831700Y0596962
X0808860Y0603802
X0798220Y0597362
X0783100Y0593582
X0815040Y0590772
X0798720Y0585362
X0792720Y0589862
X0828009Y0587913
X0805445Y0587582
X0789720Y0587362
X0789720Y0589862
X0793720Y0595862
X0791720Y0593862
X0811143Y0605265
X0808100Y0509900
X0829230Y0582772
X0812510Y0486422
X0783600Y0502462
X0799230Y0485922
X0809510Y0486122
X0804510Y0486122
X0775378Y0502502
X0845523Y0582126
X0807640Y0506672
X0805470Y0510522
X0777020Y0530362
X0802790Y0495652
X0848620Y0509752
X0865290Y0499032
X0868110Y0499142
X0778670Y0493422
X0776170Y0493422
X0781170Y0493422
X0783400Y0511902
X0801940Y0485932
X0793220Y0493362
X0819320Y0502347
X0814305Y0499503
X0829745Y0502082
X0814220Y0582530
X0807220Y0493362
X0870360Y0493042
X0858600Y0511130
X0841461Y0525849
X0857620Y0492862
X0797420Y0512503
X0862620Y0507162
X0857195Y0522162
X0821720Y0523082
X0838645Y0492862
X0772365Y0488862
X0840990Y0529786
X0821720Y0515082
X0815650Y0516807
X0783450Y0522462
X0830480Y0527817
X0789720Y0581862
X0772220Y0530362
X0860345Y0513062
X0860345Y0522162
X0834635Y0515447
X0821720Y0519082
X0801567Y0512942
X0793673Y0512862
X0862620Y0499062
X0862620Y0503162
X0848710Y0505641
X0829745Y0498082
X0841795Y0492862
X0829720Y0494862
X0820720Y0493862
X0773530Y0507062
X0832720Y0494862
X0782690Y0488862
X0865810Y0521862
X0821720Y0527082
X0785220Y0581362
X0853070Y0515447
X0843287Y0527817
X0821720Y0511082
X0832590Y0512888
X0832370Y0525849
X0795320Y0444862
X0810860Y0449862
X0795320Y0459862
X0801750Y0444330
X0855200Y0476900
X0830870Y0480010
X0816400Y0472900
X0797720Y0428412
X0859740Y0399081
X0844210Y0455902
X0800352Y0408389
X0861080Y0459742
X0805720Y0432902
X0791582Y0435352
X0781320Y0398212
X0810815Y0469862
X0787320Y0459862
X0787320Y0439862
X0795320Y0439862
X0802810Y0459862
X0810860Y0459862
X0802810Y0449862
X0802810Y0464862
X0810860Y0464862
X0787320Y0449862
X0795320Y0449862
X0787320Y0444862
X0816810Y0464862
X0824860Y0464862
X0787320Y0454862
X0795320Y0454862
X0802810Y0454862
X0810860Y0454862
X0840400Y0418900
X0789230Y0414942
X0785720Y0427862
X0810815Y0474862
X0793875Y0483262
X0785800Y0482762
X0793660Y0422842
X0791040Y0422892
X0851606Y0447927
X0783340Y0474802
X0841200Y0456500
X0819220Y0412264
X0772365Y0459862
X0780315Y0459862
X0819220Y0397664
X0772365Y0469862
X0772364Y0475062
X0780315Y0464862
X0795320Y0464862
X0773245Y0408212
X0773245Y0403212
X0802865Y0474862
X0781195Y0413212
X0838220Y0459562
X0798990Y0474862
X0868113Y0409372
X0802790Y0433832
X0784730Y0432682
X0795520Y0398212
X0774982Y0446908
X0870700Y0402581
X0824980Y0413260
X0832400Y0427100
X0830600Y0449200
X0802010Y0439940
X0825100Y0468900
X0846700Y0476900
X0822415Y0479600
X0796315Y0469290
X0781205Y0454402
X0862320Y0431462
X0780020Y0445287
X0780020Y0441437
X0788120Y0422942
X0825003Y0397276
X0781195Y0393212
X0870700Y0398620
X0870700Y0386476
X0832700Y0446800
X0836300Y0418800
X0825003Y0389012
X0870513Y0414276
X0791075Y0388000
X0815310Y0440100
X0786220Y0464862
X0839640Y0449612
X0831720Y0457700
X0787720Y0408362
X0772365Y0454862
X0773245Y0398212
X0795520Y0393462
X0799458Y0431217
X0870700Y0394620
X0870700Y0390620
X0824980Y0409260
X0824980Y0405260
X0844200Y0418800
X0839200Y0434300
X0841300Y0446800
X0818500Y0451700
X0787925Y0387900
X0791590Y0417050
X0842341Y0474241
X0842600Y0477200
X0846700Y0473000
X0816500Y0476800
X0795600Y0402500
X0795370Y0474862
X0780340Y0474862
X0780340Y0468982
X0843810Y0453322
X0847830Y0443892
X0781410Y0431822
X0780020Y0438287
X0871320Y0416752
X0857560Y0417762
X0821720Y0428437
X0781195Y0418212
X0856842Y0410760
X0803150Y0408512
X0838784Y0392880
X0833300Y0386500
X0802220Y0393727
X0846040Y0399210
X0785560Y0417902
X0846490Y0422131
X0781195Y0423212
X0823600Y0421194
X0803120Y0428762
X0798370Y0439932
X0787360Y0469862
X0850610Y0444352
X0860574Y0445404
X0863415Y0445829
X0797900Y0354800
X0815710Y0374292
X0868552Y0285537
X0856243Y0286447
X0823800Y0311962
X0826300Y0311962
X0776000Y0369662
X0795920Y0312662
X0799720Y0300462
X0805870Y0304812
X0830417Y0311865
X0803620Y0302962
X0785220Y0284762
X0827620Y0302962
X0774490Y0354942
X0813210Y0374292
X0787600Y0354900
X0805910Y0355012
X0777420Y0354962
X0779120Y0308755
X0859920Y0308852
X0779120Y0303410
X0855480Y0299692
X0777467Y0296315
X0797924Y0298358
X0839860Y0294702
X0813293Y0287062
X0792620Y0354862
X0790120Y0354862
X0798400Y0360600
X0818000Y0378800
X0860531Y0375826
X0864820Y0304936
X0867320Y0304936
X0869820Y0304936
X0806450Y0310362
X0806000Y0360600
X0850093Y0286625
X0829720Y0292762
X0793820Y0304962
X0794220Y0296062
X0840063Y0285022
X0793896Y0309026
X0794057Y0301569
X0782420Y0354962
X0795220Y0354862
X0779920Y0354962
X0785000Y0355000
X0867922Y0376450
X0859734Y0373032
X0851396Y0369614
X0843133Y0366158
X0835471Y0363003
X0828222Y0359960
X0820936Y0356956
X0813855Y0354008
X0806588Y0351097
X0810781Y0372615
X0821164Y0372312
X0870700Y0382415
X0799800Y0368700
X0794600Y0360600
X0802200Y0360600
X0809800Y0360600
X0776100Y0375100
X0848000Y0374622
X0777283Y0320892
X0856700Y0304862
X0798620Y0312773
X0779120Y0306162
X0772866Y0311558
X0853200Y0297462
X0834900Y0293462
X0834400Y0283862
X0829320Y0296762
X0816420Y0287062
X0827403Y0286625
X0795190Y0298572
X0780617Y0296345
X0773220Y0296262
X0852800Y0288562
X0862043Y0290047
X0784415Y0313734
X0800646Y0354921
X0803280Y0354982
X0771960Y0375162
X0792943Y0312642
X0860050Y0215310
X0867237Y0273325
X0867700Y0268262
X0861865Y0273730
X0863747Y0280870
X0785200Y0271400
X0867528Y0231788
X0855933Y0215375
X0847580Y0232222
X0785135Y0274822
X0838820Y0206872
X0844526Y0204968
X0837160Y0213207
X0837160Y0218212
X0780820Y0278262
X0777420Y0277962
X0840850Y0278948
X0798204Y0279146
X0829820Y0275045
X0810920Y0280062
X0829620Y0280345
X0837500Y0229642
X0855858Y0212425
X0864859Y0187110
X0835400Y0268800
X0808800Y0267900
X0850133Y0271049
X0853828Y0269043
X0839450Y0272662
X0816220Y0277162
X0813490Y0273862
X0815060Y0280072
X0837975Y0210064
X0813900Y0269698
X0829680Y0264580
X0854338Y0283527
X0854338Y0280027
X0854333Y0276117
X0863933Y0276917
X0860833Y0276817
X0829800Y0271562
X0829720Y0277562
X0836210Y0272452
X0809700Y0273562
X0806300Y0279662
X0797443Y0271469
X0785135Y0267822
X0785135Y0281822
X0853828Y0265057
X0852206Y0229878
X0854706Y0229878
X0830339Y0228143
X0845220Y0216532
X0849710Y0212062
X0820900Y0147112
X0779893Y0150021
X0779893Y0147521
X0782553Y0152531
X0782553Y0150031
X0835220Y0163862
X0838220Y0163862
X0871145Y0163862
X0814531Y0139851
X0814570Y0145952
X0845220Y0129362
X0845220Y0135862
X0854220Y0129362
X0842720Y0181360
X0854220Y0135862
X0845720Y0181362
X0848360Y0182872
X0835114Y0115223
X0837320Y0175112
X0854100Y0132972
X0773420Y0143462
X0867620Y0154362
X0862452Y0151590
X0854200Y0138562
X0848709Y0156752
X0848745Y0160187
X0843855Y0087711
X0828145Y0160362
X0829114Y0147123
X0839360Y0114862
X0823114Y0115223
X0827114Y0115223
X0871580Y0183370
X0772328Y0153728
X0781440Y0118637
X0788940Y0118637
X0786440Y0118637
X0783940Y0118637
X0787680Y0120947
X0790180Y0120947
X0792680Y0120947
X0785180Y0120947
X0853100Y0113762
X0847660Y0113962
X0773943Y0114633
X0776730Y0117479
X0846846Y0127064
X0856776Y0129268
X0836502Y0161553
X0863488Y0176332
X0851895Y0160262
X0829114Y0150273
X0824498Y0145198
X0821118Y0134632
X0825698Y0139062
X0850280Y0113852
X0831114Y0115223
X0819114Y0115223
X0837791Y0085186
X0831297Y0104206
X0842864Y0110296
X0854107Y0091232
X0854577Y0099651
X0850015Y0087341
X0837250Y0093221
X0847472Y0094754
X0841584Y0094181
X0839898Y0087248
X0837268Y0023655
X0837268Y0003597
X0837268Y0013626
X0830990Y0004903
X0830975Y0002388
X0834258Y0004889
X0834273Y0002374
X0834273Y0018558
X0830975Y0018572
X0830990Y0014932
X0830975Y0012417
X0834258Y0014918
X0834273Y0012403
X0834273Y0008529
X0830975Y0008543
X0830990Y0024961
X0830975Y0022446
X0834258Y0024947
X0834273Y0022432
X0842497Y0010978
X0842497Y0006022
X0842497Y0020978
X0842497Y0016022
X0858629Y0060293
X0828600Y0061752
X0774059Y0068912
X0861350Y0061672
X0860937Y0071877
X0868187Y0072006
X0836126Y0062681
X0785095Y0049388
X0805095Y0049388
X0825095Y0049388
X0845095Y0049388
X0865095Y0049388
X0840001Y0010200
X0840001Y0006800
X0840001Y0016800
X0840001Y0020200
X0836779Y0068008
X0866330Y0070072
X0862930Y0070072
X0876124Y0066072
X0887520Y0176862
X0887520Y0171362
X0922100Y0181791
X0922726Y0176302
X0876695Y0176862
X0876695Y0171362
X0878327Y0183169
X0962458Y0162398
X0962604Y0165313
X0948400Y0176499
X0943220Y0176389
X0945720Y0176389
X0943220Y0173389
X0945720Y0173389
X0940720Y0176389
X0935550Y0176329
X0938160Y0176389
X0940720Y0173389
X0935550Y0173329
X0938160Y0173389
X0886280Y0174085
X0917680Y0171999
X0917680Y0177999
X0917680Y0174999
X0874295Y0163862
X0957420Y0153699
X0960420Y0153699
X0876124Y0086072
X0876124Y0106072
X0876124Y0126072
X0892214Y0141891
X0912214Y0141891
X0932214Y0141891
X0952214Y0141891
X0965884Y0242051
X0935454Y0241154
X0877971Y0196652
X0883870Y0272652
X0879587Y0270004
X0883909Y0281862
X0917386Y0184114
X0940410Y0188852
X0949550Y0192819
X0875543Y0266447
X0875543Y0269347
X0947496Y0229535
X0957156Y0230563
X0947496Y0211997
X0953970Y0204875
X0947496Y0226135
X0957156Y0227163
X0947496Y0215397
X0953970Y0208275
X0907470Y0229554
X0902350Y0222468
X0907470Y0215380
X0902350Y0204894
X0907470Y0226154
X0902350Y0219068
X0907470Y0211980
X0902350Y0208294
X0936424Y0184190
X0940424Y0184190
X0871890Y0196740
X0878220Y0187449
X0949120Y0184912
X0939270Y0191419
X0935770Y0191419
X0896620Y0207162
X0894120Y0207162
X0894120Y0209662
X0896620Y0209662
X0891620Y0207162
X0888929Y0206723
X0891620Y0209662
X0888929Y0209223
X0961120Y0193299
X0970720Y0198099
X0966720Y0198099
X0965150Y0193412
X0957020Y0193299
X0923836Y0193563
X0877724Y0200837
X0875169Y0185113
X0908620Y0188899
X0944250Y0197889
X0944250Y0194489
X0933686Y0242922
X0894770Y0283062
X0933122Y0246115
X0873200Y0194262
X0968384Y0242051
X0957020Y0264862
X0962570Y0282812
X0906120Y0261252
X0924920Y0196199
X0883870Y0275802
X0884003Y0278712
X0938603Y0240063
X0963020Y0264862
X0960020Y0264862
X0920246Y0184138
X0971471Y0242358
X0871980Y0199500
X0880943Y0283347
X0914550Y0239924
X0954904Y0225741
X0954874Y0232071
X0944880Y0225097
X0944880Y0230697
X0935496Y0231358
X0935496Y0224272
X0909386Y0231358
X0909386Y0224271
X0903980Y0224529
X0944880Y0216559
X0944880Y0210959
X0935496Y0217185
X0935496Y0210098
X0925320Y0203399
X0935496Y0203012
X0909386Y0217185
X0909386Y0210098
X0909386Y0203011
X0903930Y0217059
X0903980Y0210355
X0903930Y0202885
X0941634Y0193451
X0941634Y0199051
X0935496Y0195925
X0927133Y0189386
X0909386Y0195925
X0878220Y0192055
X0951354Y0203837
X0949710Y0198289
X0951354Y0209437
X0960703Y0212668
X0963520Y0214699
X0930472Y0246093
X0896540Y0341132
X0887520Y0327562
X0885020Y0327562
X0882520Y0327562
X0970730Y0377872
X0877322Y0296051
X0893440Y0336232
X0962623Y0350642
X0933217Y0380693
X0874243Y0287047
X0872320Y0304936
X0890422Y0333879
X0887338Y0296760
X0963854Y0320113
X0967239Y0320073
X0883472Y0382910
X0875922Y0379793
X0880473Y0329370
X0965792Y0350959
X0965420Y0365719
X0893500Y0339062
X0880943Y0286347
X0962882Y0314512
X0963300Y0347962
X0961320Y0476242
X0900020Y0470672
X0890920Y0386352
X0963720Y0439862
X0912288Y0472430
X0909190Y0473392
X0887590Y0471552
X0968286Y0480541
X0942047Y0463012
X0945447Y0463012
X0934047Y0457862
X0937447Y0457862
X0921047Y0463012
X0924447Y0463012
X0927034Y0445594
X0890820Y0389362
X0965890Y0405967
X0956487Y0394831
X0949920Y0404602
X0950660Y0399472
X0928394Y0474701
X0928394Y0472201
X0951181Y0391916
X0953046Y0390103
X0963856Y0398302
X0933217Y0384693
X0889453Y0458926
X0903124Y0470797
X0902260Y0475653
X0902260Y0473153
X0887869Y0386618
X0942646Y0400793
X0893321Y0480293
X0970054Y0478773
X0899625Y0473856
X0946492Y0460410
X0926215Y0461244
X0932724Y0455538
X0938437Y0455454
X0940709Y0460438
X0919279Y0461244
X0913913Y0455396
X0908675Y0455386
X0945800Y0439399
X0945800Y0432463
X0942827Y0429679
X0942827Y0422743
X0960059Y0387004
X0963856Y0394202
X0923897Y0445545
X0944032Y0434231
X0944032Y0437631
X0941059Y0424511
X0941059Y0427911
X0909584Y0458135
X0912984Y0458135
X0896060Y0481222
X0959351Y0533566
X0956518Y0531567
X0942610Y0515350
X0941740Y0512922
X0948415Y0534313
X0944261Y0517871
X0955123Y0533642
X0881680Y0508142
X0881680Y0504742
X0887810Y0582442
X0957220Y0582862
X0945100Y0534464
X0882410Y0526132
X0884512Y0523800
X0893450Y0516862
X0921189Y0492086
X0918078Y0495177
X0968286Y0483941
X0929281Y0506086
X0926637Y0506069
X0940140Y0514925
X0945524Y0515483
X0940550Y0517400
X0969351Y0512416
X0924623Y0492097
X0964347Y0501262
X0929654Y0492103
X0970788Y0501230
X0932289Y0502986
X0927154Y0492103
X0932089Y0505986
X0932089Y0492691
X0918532Y0492445
X0907678Y0488177
X0939872Y0495813
X0964347Y0509462
X0932218Y0499314
X0947190Y0527330
X0969098Y0535130
X0962162Y0535130
X0959558Y0529364
X0952622Y0529364
X0939282Y0534020
X0936273Y0530478
X0928231Y0530479
X0924647Y0533744
X0906398Y0533380
X0899462Y0533380
X0893298Y0534380
X0886362Y0534380
X0956188Y0516420
X0939097Y0527257
X0924647Y0526808
X0918562Y0523430
X0911626Y0523430
X0911720Y0511662
X0900061Y0517898
X0960620Y0509462
X0966720Y0511362
X0956188Y0509484
X0948693Y0509497
X0948495Y0502784
X0956188Y0502320
X0956188Y0495384
X0940596Y0498648
X0906127Y0496343
X0900061Y0510962
X0893572Y0496114
X0893572Y0503050
X0878941Y0503813
X0878931Y0509051
X0970054Y0485709
X0938588Y0485197
X0920682Y0494586
X0920980Y0503393
X0929234Y0494915
X0929698Y0503595
X0893311Y0485531
X0887671Y0494767
X0887671Y0487831
X0909600Y0521162
X0931720Y0524862
X0932373Y0495175
X0926173Y0512391
X0909984Y0496330
X0918212Y0500777
X0923783Y0506076
X0921060Y0506086
X0918131Y0503330
X0918212Y0497677
X0941050Y0528852
X0941050Y0532252
X0930731Y0530479
X0933773Y0530479
X0922879Y0528576
X0922879Y0531976
X0896060Y0484622
X0889439Y0492999
X0889439Y0489599
X0895340Y0501282
X0895340Y0497882
X0954420Y0497152
X0954420Y0500552
X0901829Y0516130
X0901829Y0512730
X0891530Y0532612
X0888130Y0532612
X0916794Y0521662
X0913394Y0521662
X0904630Y0531612
X0901230Y0531612
X0957790Y0527596
X0954390Y0527596
X0967330Y0533362
X0963930Y0533362
X0954420Y0511252
X0954420Y0514652
X0946727Y0504552
X0946727Y0507952
X0963720Y0652262
X0963720Y0657262
X0963720Y0647262
X0960920Y0654762
X0960920Y0649762
X0963720Y0662262
X0960920Y0659762
X0960920Y0644762
X0960820Y0665062
X0958755Y0657078
X0958866Y0662378
X0963520Y0665062
X0885310Y0736442
X0886720Y0741902
X0889000Y0737562
X0886500Y0739162
X0874155Y0756993
X0947921Y0799761
X0946786Y0795287
X0926469Y0826612
X0925220Y0817862
X0928237Y0824844
X0930786Y0811785
X0938371Y0809311
X0934260Y0808312
X0935052Y0812630
X0943366Y0798707
X0914152Y0803294
X0913720Y0799362
X0909720Y0794862
X0944272Y0803410
X0884747Y0871745
X0878192Y0879910
X0894897Y0871745
X0938742Y0803831
X0950190Y0791382
X0878152Y0876760
X0924600Y0824262
X0941400Y0810062
X0927200Y0811462
X0959100Y0789862
X0956700Y0786862
X0927470Y0815112
X0931573Y0816109
X0953594Y0787477
X0951043Y0796140
X0909720Y0798861
X0954447Y0791735
X0918420Y0804062
X0949560Y0981392
X0917980Y0974952
X0923930Y0976652
X0916974Y0962108
X0899830Y0974884
X0899830Y0971484
X0892317Y0915872
X0884619Y0916477
X0879100Y0912608
X0894965Y0917422
X0880102Y0923235
X0921757Y0962082
X0944170Y0962842
X0940170Y0962842
X0926823Y0962082
X0923403Y0983327
X0930233Y0983298
X0953235Y0972642
X0946865Y0974077
X0963610Y0981292
X0898062Y0969716
X0898062Y0976652
X0931496Y0962082
X0881372Y0920655
X0894375Y0913692
X0897000Y0891895
X0907770Y1045242
X0914838Y0985989
X0932310Y0996812
X0936998Y0985750
X0924440Y0996852
X0931220Y1012362
X0939740Y0987762
X0918720Y1009937
X0927220Y1012362
X0951560Y0997422
X0929221Y1014664
X0963780Y0997496
X0943720Y0985772
X0923322Y0990227
X0930274Y0990237
X0946938Y0991162
X0959535Y0990477
X0967750Y1376460
X0891560Y1435510
X0894830Y1435970
X0889439Y1437938
X0965622Y1573240
X0965622Y1576240
X0965622Y1579240
X0960904Y1554364
X0965904Y1554364
X0899652Y1573793
X0899652Y1582570
X0896652Y1577793
X0938652Y1581393
X0914079Y1580393
X0919579Y1580393
X0908479Y1580393
X0872079Y1580393
X0877579Y1580393
X0888652Y1573793
X0888652Y1581793
X0944980Y1539260
X0947980Y1539260
X0950980Y1539260
X0953980Y1539260
X0956980Y1539260
X0944980Y1536260
X0947980Y1536260
X0950980Y1536260
X0953980Y1536260
X0956980Y1536260
X0969000Y1539262
X0971700Y1539262
X0971700Y1536262
X0969000Y1536262
X0969000Y1542262
X0971700Y1542262
X0956980Y1542260
X0953980Y1542260
X0950980Y1542260
X0947980Y1542260
X0944980Y1542260
X0956980Y1545260
X0953980Y1545260
X0950980Y1545260
X0947980Y1545260
X0944980Y1545260
X0956980Y1548260
X0953980Y1548260
X0950980Y1548260
X0947980Y1548260
X0944980Y1548260
X0956980Y1551260
X0953980Y1551260
X0950980Y1551260
X0947980Y1551260
X0944980Y1551260
X0956980Y1554260
X0953980Y1554260
X0950980Y1554260
X0947980Y1554260
X0944980Y1554260
X0913352Y1574293
X0913352Y1571293
X0916352Y1571293
X0916352Y1574293
X0919352Y1571293
X0919352Y1574293
X0922352Y1571293
X0922352Y1574293
X0925352Y1571293
X0925352Y1574293
X0913352Y1562293
X0913352Y1559293
X0913352Y1565293
X0913352Y1568293
X0916352Y1568293
X0916352Y1565293
X0916352Y1559293
X0916352Y1562293
X0919352Y1568293
X0919352Y1565293
X0919352Y1559293
X0919352Y1562293
X0922352Y1568293
X0922352Y1565293
X0922352Y1559293
X0922352Y1562293
X0925352Y1568293
X0925352Y1565293
X0925352Y1559293
X0925352Y1562293
X0907352Y1571293
X0907352Y1574293
X0910352Y1571293
X0910352Y1574293
X0907352Y1562293
X0907352Y1559293
X0907352Y1565293
X0907352Y1568293
X0910352Y1562293
X0910352Y1559293
X0910352Y1565293
X0910352Y1568293
X0874352Y1571293
X0874352Y1574293
X0877352Y1571293
X0877352Y1574293
X0880352Y1571293
X0880352Y1574293
X0883352Y1571293
X0883352Y1574293
X0874352Y1568293
X0874352Y1565293
X0874352Y1559293
X0874352Y1562293
X0877352Y1568293
X0877352Y1565293
X0877352Y1559293
X0877352Y1562293
X0880352Y1568293
X0880352Y1565293
X0880352Y1559293
X0880352Y1562293
X0883352Y1568293
X0883352Y1565293
X0883352Y1559293
X0883352Y1562293
X0971700Y1551262
X0969000Y1551262
X0971700Y1554262
X0969000Y1554262
X0971700Y1545262
X0969000Y1545262
X0971700Y1548262
X0969000Y1548262
X0939380Y1527610
X0936880Y1527610
X0934380Y1527610
X0931880Y1527610
X0929380Y1527610
X0926880Y1527610
X0924380Y1527610
X0921880Y1527610
X0936880Y1525110
X0934380Y1525110
X0931880Y1525110
X0929380Y1525110
X0926880Y1525110
X0924380Y1525110
X0921880Y1525110
X0939380Y1525110
X0919488Y1660733
X0914500Y1671400
X0957852Y1585920
X0963852Y1585920
X0960852Y1585920
X0969852Y1585920
X0966852Y1585920
X0962086Y1603984
X0965086Y1603984
X0929979Y1661352
X0918020Y1672860
X0896672Y1587073
X0902652Y1590444
X0888652Y1589793
X0899551Y1593793
X0888652Y1609793
X0885652Y1584539
X0928152Y1584539
X0896652Y1601793
X0938652Y1589393
X0883152Y1586507
X0925152Y1586507
X0942100Y1671100
X0920052Y1603693
X0920052Y1597693
X0920052Y1600693
X0911052Y1603693
X0908052Y1603693
X0914052Y1603693
X0917052Y1603693
X0908052Y1597693
X0911052Y1597693
X0911052Y1600693
X0908052Y1600693
X0914052Y1597693
X0914052Y1600693
X0917052Y1597693
X0917052Y1600693
X0920052Y1607793
X0923052Y1607793
X0923052Y1611893
X0920052Y1611893
X0911052Y1607793
X0905052Y1607793
X0908052Y1607793
X0914052Y1607793
X0917052Y1607793
X0902052Y1611893
X0911052Y1611893
X0905052Y1611893
X0908052Y1611893
X0914052Y1611893
X0917052Y1611893
X0881052Y1607793
X0968022Y1632730
X0971022Y1632730
X0971022Y1629730
X0971022Y1623730
X0971022Y1626730
X0968022Y1623730
X0965022Y1623730
X0965022Y1626730
X0968022Y1626730
X0965022Y1629730
X0968022Y1629730
X0965022Y1632730
X0971022Y1620730
X0965022Y1620730
X0968022Y1620730
X0962022Y1623730
X0959022Y1623730
X0959022Y1626730
X0962022Y1626730
X0959022Y1629730
X0962022Y1629730
X0962022Y1632730
X0959022Y1632730
X0956022Y1623730
X0953022Y1623730
X0953022Y1626730
X0956022Y1626730
X0953022Y1629730
X0956022Y1629730
X0956022Y1632730
X0953022Y1632730
X0959022Y1620730
X0962022Y1620730
X0953022Y1620730
X0956022Y1620730
X0908479Y1585523
X0919579Y1585523
X0908479Y1590653
X0914079Y1590653
X0919579Y1590653
X0875052Y1600693
X0875052Y1597693
X0877579Y1590653
X0878052Y1600693
X0878052Y1597693
X0875052Y1611893
X0875052Y1607793
X0875052Y1603693
X0878052Y1611893
X0881052Y1611893
X0878052Y1607793
X0878052Y1603693
X0872052Y1600693
X0872079Y1590653
X0872052Y1597693
X0872052Y1611893
X0872052Y1607793
X0872052Y1603693
X0877579Y1585523
X0933979Y1661327
X0956800Y1663725
X0938652Y1585393
X0938652Y1593393
X0888652Y1585993
X0896652Y1593793
X0897352Y1590893
X0888652Y1597793
X0896652Y1605793
X0956600Y1666875
X0922320Y1660953
X0946100Y1661100
X0938220Y1661062
X0927122Y1661380
X0872208Y1731911
X0892208Y1731911
X0912208Y1731911
X0932208Y1731911
X0952208Y1731911
X0972208Y1731911
X0992208Y1731911
X1012208Y1731911
X1032208Y1731911
X1052208Y1731911
X1059612Y1586010
X1056612Y1586010
X1065612Y1586010
X1062612Y1586010
X1053612Y1586010
X1027942Y1586090
X1024942Y1586090
X1033942Y1586090
X1030942Y1586090
X1021942Y1586090
X0993782Y1585920
X0990782Y1585920
X0996782Y1585920
X0999782Y1585920
X1002782Y1585920
X1025298Y1604000
X1028298Y1604000
X0993698Y1604000
X0996698Y1604000
X1056898Y1604000
X1059898Y1604000
X1056721Y1621043
X1059721Y1621043
X1062721Y1621043
X1065721Y1621043
X1068721Y1621043
X1056721Y1630043
X1059721Y1630043
X1056721Y1627043
X1059721Y1627043
X1059721Y1624043
X1056721Y1624043
X1059721Y1633043
X1056721Y1633043
X1062721Y1630043
X1062721Y1627043
X1062721Y1624043
X1062721Y1633043
X1065721Y1630043
X1065721Y1627043
X1065721Y1624043
X1068721Y1630043
X1068721Y1627043
X1068721Y1624043
X1068721Y1633043
X1065721Y1633043
X1050721Y1621043
X1053721Y1621043
X1050721Y1630043
X1050721Y1627043
X1050721Y1624043
X1053721Y1630043
X1053721Y1627043
X1053721Y1624043
X1053721Y1633043
X1050721Y1633043
X1028252Y1620870
X1034252Y1620870
X1031252Y1620870
X1025252Y1626870
X1028252Y1626870
X1028252Y1623870
X1025252Y1623870
X1031252Y1626870
X1031252Y1623870
X1034252Y1626870
X1034252Y1623870
X1019252Y1626870
X1019252Y1623870
X1022252Y1626870
X1022252Y1623870
X0993662Y1632870
X0990662Y1632870
X0993662Y1623870
X0990662Y1623870
X0990662Y1626870
X0993662Y1626870
X0990662Y1629870
X0993662Y1629870
X0996662Y1632870
X0999662Y1623870
X0996662Y1623870
X0996662Y1626870
X0999662Y1626870
X0996662Y1629870
X1002662Y1623870
X1002662Y1626870
X0987662Y1632870
X0987662Y1623870
X0987662Y1626870
X0987662Y1629870
X1025252Y1620870
X1022252Y1620870
X1019252Y1620870
X1002662Y1620870
X0999662Y1620870
X0996662Y1620870
X0987662Y1620870
X0993662Y1620870
X0990662Y1620870
X1019910Y1665200
X1019910Y1662700
X1027370Y1665200
X1027370Y1662700
X1001810Y1665200
X1001810Y1662700
X1023580Y1665200
X1023580Y1662700
X1044850Y1662550
X1044850Y1665050
X1059086Y1576240
X1059086Y1573240
X1059086Y1579240
X1035720Y1576240
X1035720Y1573240
X1035720Y1579240
X1012354Y1576240
X1012354Y1573240
X1012354Y1579240
X0988988Y1576240
X0988988Y1573240
X0988988Y1579240
X0984270Y1554364
X1054368Y1554364
X1031002Y1554364
X1007636Y1554364
X1059368Y1554364
X1036002Y1554364
X1012636Y1554364
X0989270Y1554364
X1066462Y1520088
X0974700Y1539262
X0980400Y1539262
X0977700Y1539262
X0977700Y1536262
X0980400Y1536262
X0974700Y1536262
X0995066Y1539262
X0992466Y1539262
X1001066Y1539262
X1003766Y1539262
X0998066Y1539262
X0998066Y1536262
X1003766Y1536262
X1001066Y1536262
X0992466Y1536262
X0995066Y1536262
X1018612Y1539262
X1016012Y1539262
X1021612Y1539262
X1018612Y1536262
X1016012Y1536262
X1021612Y1536262
X1024612Y1539262
X1027212Y1539262
X1024612Y1536262
X1027212Y1536262
X1041798Y1539262
X1039298Y1539262
X1047798Y1539262
X1050498Y1539262
X1044798Y1539262
X1039298Y1536262
X1044798Y1536262
X1050498Y1536262
X1047798Y1536262
X1041798Y1536262
X1065164Y1539262
X1062464Y1539262
X1071164Y1539262
X1068164Y1539262
X1068164Y1536262
X1071164Y1536262
X1062464Y1536262
X1065164Y1536262
X1065164Y1542262
X1062464Y1542262
X1071164Y1542262
X1068164Y1542262
X1041798Y1542262
X1047798Y1542262
X1050498Y1542262
X1044798Y1542262
X1039298Y1542262
X1027212Y1542262
X1024612Y1542262
X1021612Y1542262
X1016012Y1542262
X1018612Y1542262
X0995066Y1542262
X0992466Y1542262
X1001066Y1542262
X1003766Y1542262
X0998066Y1542262
X0974700Y1542262
X0980400Y1542262
X0977700Y1542262
X1068164Y1554262
X1071164Y1554262
X1068164Y1548262
X1068164Y1545262
X1068164Y1551262
X1071164Y1548262
X1071164Y1545262
X1071164Y1551262
X1062464Y1554262
X1065164Y1554262
X1062464Y1548262
X1065164Y1548262
X1062464Y1545262
X1065164Y1545262
X1062464Y1551262
X1065164Y1551262
X1044798Y1554262
X1050498Y1554262
X1047798Y1554262
X1044798Y1548262
X1044798Y1545262
X1044798Y1551262
X1050498Y1548262
X1047798Y1548262
X1050498Y1545262
X1047798Y1545262
X1050498Y1551262
X1047798Y1551262
X1039298Y1554262
X1041798Y1554262
X1039298Y1548262
X1041798Y1548262
X1039298Y1545262
X1041798Y1545262
X1039298Y1551262
X1041798Y1551262
X1021612Y1554262
X1027212Y1554262
X1024612Y1554262
X1021612Y1548262
X1021612Y1545262
X1021612Y1551262
X1027212Y1548262
X1024612Y1548262
X1027212Y1545262
X1024612Y1545262
X1027212Y1551262
X1024612Y1551262
X1016012Y1554262
X1018612Y1554262
X1016012Y1548262
X1018612Y1548262
X1016012Y1545262
X1018612Y1545262
X1016012Y1551262
X1018612Y1551262
X0998066Y1554262
X1003766Y1554262
X1001066Y1554262
X0998066Y1548262
X0998066Y1545262
X0998066Y1551262
X1003766Y1548262
X1001066Y1548262
X1003766Y1545262
X1001066Y1545262
X1003766Y1551262
X1001066Y1551262
X0992466Y1554262
X0995066Y1554262
X0992466Y1548262
X0995066Y1548262
X0992466Y1545262
X0995066Y1545262
X0992466Y1551262
X0995066Y1551262
X0977700Y1551262
X0980400Y1551262
X0977700Y1554262
X0980400Y1554262
X0977700Y1545262
X0980400Y1545262
X0977700Y1548262
X0980400Y1548262
X0974700Y1551262
X0974700Y1554262
X0974700Y1545262
X0974700Y1548262
X1007610Y1295040
X1007600Y1298250
X0994574Y1297318
X0985320Y1288762
X0992306Y1295049
X0996320Y1284062
X0979373Y1342724
X1071179Y1294669
X1058290Y1296302
X1063354Y1296714
X1058354Y1291714
X1063354Y1291714
X1058354Y1286714
X1063354Y1286714
X1053354Y1296714
X1044510Y1293155
X1049510Y1293155
X1039510Y1293155
X1044510Y1296655
X1049510Y1296655
X1039510Y1296655
X1053354Y1291714
X1053354Y1286714
X0987920Y1290662
X0996675Y1286985
X0997920Y1278762
X0975900Y1265062
X0996320Y1280683
X1005373Y0748826
X1007873Y0748826
X0994942Y0777055
X0995120Y0773122
X1055205Y0744853
X1010630Y0748741
X1030660Y0735082
X1036954Y0734669
X1053745Y0742341
X1033817Y0735612
X1045720Y0591672
X1061470Y0585862
X1058220Y0585862
X1005960Y0594682
X1048260Y0601272
X1045760Y0596272
X1043260Y0601272
X1051680Y0614772
X1038260Y0601272
X1011160Y0594682
X1016220Y0590862
X1033260Y0601272
X1035760Y0592952
X1026654Y0596152
X1021654Y0606302
X1019000Y0601042
X1029630Y0601252
X1056220Y0605052
X1024154Y0601152
X1008560Y0589682
X1040720Y0591862
X1016360Y0594682
X1053200Y0612162
X1056280Y0601232
X1050390Y0604172
X1050200Y0598062
X1036480Y0596272
X1023740Y0596152
X1030980Y0598722
X1021720Y0601862
X1002640Y0594692
X1043720Y0589362
X1038220Y0589862
X1018720Y0592362
X1011720Y0589362
X0986400Y0503200
X1056190Y0520760
X1053690Y0520760
X1020392Y0521826
X1038130Y0518417
X1033040Y0519852
X1032155Y0509737
X1026370Y0503562
X1005520Y0510932
X1003220Y0512862
X0986418Y0530019
X0980535Y0532643
X0986273Y0532996
X0991237Y0533043
X1025530Y0519627
X1024200Y0510362
X0980720Y0512362
X1018092Y0520212
X1041444Y0506504
X1005720Y0498862
X0991097Y0529902
X0976283Y0534226
X1019145Y0503823
X1029220Y0520032
X0999720Y0512862
X0983720Y0512362
X1027190Y0510672
X1038294Y0506504
X1008720Y0498362
X0972379Y0509303
X1043920Y0443962
X1041420Y0443962
X0983970Y0392562
X0975670Y0392063
X0979559Y0399362
X0997394Y0415578
X0972220Y0390239
X0972220Y0386251
X1050470Y0447062
X0983629Y0397628
X0997225Y0419162
X0997617Y0412383
X0993012Y0421570
X1035920Y0417462
X1035920Y0420062
X0986955Y0391939
X1026548Y0400571
X1015420Y0410862
X1005123Y0414662
X1026820Y0394362
X0994322Y0404090
X0984254Y0418379
X1042720Y0393962
X1040120Y0393962
X1038320Y0404462
X1038320Y0407062
X1021239Y0416974
X1009009Y0419948
X0980856Y0392502
X1059943Y0435314
X1046156Y0442699
X0992608Y0432961
X0985672Y0432961
X1035920Y0428962
X1017511Y0430038
X1011611Y0430038
X1007249Y0422682
X1021259Y0420548
X0993387Y0429827
X0991770Y0418835
X0980092Y0421289
X0983760Y0424292
X1033860Y0400802
X0988159Y0409068
X1049100Y0390162
X1029094Y0387872
X0997612Y0391804
X0997900Y0400720
X1006589Y0392017
X1015637Y0391334
X1015657Y0401013
X1006750Y0401010
X0972986Y0393171
X1062120Y0477462
X0979240Y0425212
X1031153Y0390152
X1010420Y0416062
X0991369Y0408252
X0980916Y0384286
X0977949Y0384205
X0987440Y0431193
X0990840Y0431193
X1031950Y0387171
X1031950Y0383771
X1012861Y0432888
X1016261Y0432888
X1009800Y0343800
X0978000Y0362462
X0996922Y0367764
X0999440Y0371782
X1009883Y0367955
X1017163Y0367963
X1025004Y0374662
X1032317Y0291284
X0979766Y0377507
X0983770Y0373962
X0994743Y0289843
X1036278Y0307393
X1036278Y0303993
X1015520Y0302862
X1029395Y0375844
X1015096Y0373758
X0986400Y0383123
X1044120Y0366362
X1043720Y0363462
X1006710Y0372931
X1006201Y0370004
X1006232Y0343983
X1020720Y0310937
X1054820Y0370162
X1033285Y0353627
X1021695Y0364518
X1001440Y0359702
X0988908Y0373392
X1025862Y0291727
X0979940Y0287262
X0979940Y0284762
X0978012Y0294996
X0975512Y0294996
X0979940Y0289762
X0979940Y0292262
X0994689Y0379348
X1013500Y0344900
X1029094Y0383070
X1006221Y0382945
X0997598Y0382952
X1015638Y0382968
X1043629Y0372578
X1043629Y0375078
X0994553Y0365711
X0979380Y0373082
X0974791Y0339990
X0985016Y0344659
X0986182Y0361062
X0989500Y0376362
X1001065Y0309622
X1001065Y0307122
X1001065Y0304622
X1021419Y0305704
X1010828Y0309822
X1010828Y0307322
X1010828Y0304822
X1036915Y0290969
X1040924Y0286073
X1070618Y0285600
X1067718Y0285600
X1070618Y0288500
X1067718Y0288500
X0991934Y0368443
X1021118Y0294290
X0988818Y0346372
X0988723Y0369650
X0981470Y0268532
X1007820Y0229999
X1011320Y0202169
X1019530Y0226423
X1008120Y0198293
X1010005Y0208424
X1005640Y0210969
X1019802Y0214099
X1019355Y0218423
X1019355Y0222423
X1011720Y0229699
X1005120Y0230399
X1000610Y0211039
X1020645Y0190499
X0990220Y0202699
X0990220Y0199199
X0990220Y0195699
X0986020Y0191099
X0977220Y0201399
X0987320Y0201599
X0987320Y0198099
X0987320Y0194599
X1001195Y0219898
X1031702Y0264130
X1037618Y0261200
X1017800Y0185299
X1014900Y0185299
X1012000Y0185299
X0990195Y0216823
X1000705Y0202821
X0998205Y0202821
X1000705Y0199278
X0998205Y0199278
X1000705Y0192191
X1000705Y0195735
X0998205Y0192191
X0998205Y0195735
X1006220Y0185299
X1002720Y0185299
X0999220Y0185299
X0978012Y0279266
X0975512Y0279266
X0978012Y0282096
X0975512Y0282096
X0978012Y0276436
X0981795Y0216623
X0987259Y0276094
X1002500Y0266862
X1002500Y0269862
X0998500Y0269862
X1014500Y0266862
X1006500Y0266862
X1010500Y0266862
X1022002Y0267342
X1018000Y0266862
X1010500Y0263862
X1014500Y0263862
X1022000Y0264362
X1018000Y0263862
X1010500Y0269862
X1006500Y0269862
X1022002Y0270142
X1018000Y0269862
X1014500Y0269862
X1025102Y0267342
X1028202Y0267342
X1031502Y0267342
X1025000Y0264362
X1025102Y0270142
X1028202Y0270142
X1023633Y0272564
X1026733Y0272564
X1029833Y0272564
X1031502Y0270142
X1033133Y0272564
X1053028Y0246518
X1053428Y0261118
X1055528Y0246518
X1058028Y0246518
X1055928Y0261118
X1058428Y0261118
X1068093Y0265503
X1070718Y0273700
X1067618Y0273800
X0988835Y0185443
X0990495Y0212923
X1008067Y0194356
X1009895Y0192359
X1019935Y0203333
X1019935Y0206463
X1023220Y0187574
X1001101Y0165510
X0985499Y0168753
X1002920Y0174799
X0990115Y0173039
X0986369Y0155358
X1012791Y0157596
X0995180Y0153689
X0996415Y0172579
X0990501Y0152397
X0983811Y0156694
X0975690Y0157220
X1008129Y0150948
X1067220Y0148362
X1032894Y0155185
X1001500Y0150883
X0995000Y0150883
X1022800Y0175799
X1019900Y0175799
X1014300Y0175699
X1017200Y0175699
X1013220Y0160799
X1009720Y0160799
X1002720Y0160799
X1006220Y0160799
X0985431Y0181058
X1067220Y0142862
X1034229Y0128953
X1040970Y0128332
X1026620Y0125662
X1066820Y0151632
X0981445Y0181058
X0999735Y0153943
X1002735Y0153943
X0993305Y0170953
X0993205Y0174053
X0992505Y0180553
X0996415Y0180548
X0999915Y0180548
X1012187Y0148749
X1015300Y0148736
X1006435Y0172843
X0975688Y0149950
X0975688Y0152950
X1037650Y0128842
X1027520Y0122732
X0972214Y0141891
X1021908Y0120392
X1012214Y0141826
X1067220Y0145362
X0983632Y0023990
X0989925Y0019044
X0986627Y0019058
X0989910Y0022684
X0986642Y0022698
X0989895Y0025199
X0986627Y0025213
X0983632Y0013461
X0986627Y0008529
X0989925Y0008515
X0989910Y0012155
X0986642Y0012169
X0989925Y0014670
X0986627Y0014684
X0983632Y0003432
X0989910Y0002126
X0989925Y0004641
X0986642Y0002140
X0986627Y0004655
X0983632Y-0006597
X0989925Y-0011543
X0986627Y-0011529
X0986627Y-0005374
X0986642Y-0007889
X0989925Y-0005388
X0989910Y-0007903
X0986627Y-0015403
X0989925Y-0015417
X1029700Y-0016443
X1023407Y-0011497
X1026705Y-0011511
X1023422Y-0015137
X1026690Y-0015151
X1029700Y-0006414
X1023407Y-0001468
X1026705Y-0001482
X1026705Y-0007637
X1026690Y-0005122
X1023407Y-0007623
X1023422Y-0005108
X1026705Y0002392
X1026690Y0004907
X1023407Y0002406
X1023422Y0004921
X1029700Y0003615
X1029700Y0013644
X1026705Y0012421
X1026690Y0014936
X1023407Y0012435
X1023422Y0014950
X1023407Y0008561
X1026705Y0008547
X1026690Y0024965
X1023422Y0024979
X1029700Y0023673
X1023407Y0018590
X1026705Y0018576
X1026705Y0022450
X1023407Y0022464
X0978403Y0016022
X0978403Y0020978
X0978403Y-0013978
X0978403Y-0009022
X0978403Y0006022
X0978403Y0010978
X1034929Y-0009033
X1034929Y-0013989
X1034929Y0000967
X1034929Y-0003989
X1032433Y-0009811
X1032433Y-0013211
X1021908Y0060392
X1038609Y0049388
X1058609Y0049388
X0980899Y0010200
X0980899Y0006800
X0980899Y0016800
X0980899Y0020200
X0980899Y-0009800
X0980899Y-0013200
X1032433Y0000189
X1032433Y-0003211
X0986642Y-0017918
X0989910Y-0017932
X0983632Y-0016626
X0983632Y-0026655
X0986627Y-0025432
X0986642Y-0027947
X0989925Y-0025446
X0989910Y-0027961
X0989925Y-0021572
X0986627Y-0021558
X1029700Y-0037001
X1023407Y-0032055
X1026705Y-0032069
X1023422Y-0035695
X1026690Y-0035709
X1023437Y-0038210
X1026705Y-0038224
X1029700Y-0026472
X1026705Y-0021540
X1023407Y-0021526
X1023422Y-0025166
X1026690Y-0025180
X1023407Y-0027681
X1026705Y-0027695
X1023407Y-0017652
X1026705Y-0017666
X0978403Y-0023978
X0978403Y-0019022
X1034929Y-0029033
X1034929Y-0033989
X1034929Y-0019033
X1034929Y-0023989
X1129997Y0069864
X1132547Y0064864
X1032433Y-0033211
X1032433Y-0029811
X1113594Y0069862
X1109020Y0080592
X1094644Y0067992
X1079114Y0075775
X1110754Y0060028
X1155703Y0073679
X1110977Y0055505
X1071920Y0053862
X1129948Y0066786
X1145603Y0073679
X1102561Y0078461
X1097794Y0067881
X1084146Y0067102
X1132856Y0052926
X1075100Y0055682
X1078609Y0049388
X1098609Y0049388
X1118609Y0049388
X1138609Y0049388
X1158609Y0049388
X0980899Y-0023200
X0980899Y-0019800
X1032433Y-0019811
X1032433Y-0023211
X1168710Y0176590
X1100630Y0130376
X1105580Y0132822
X1152720Y0180862
X1165440Y0176450
X1140242Y0101135
X1115860Y0113883
X1118309Y0111687
X1120420Y0109829
X1122278Y0107549
X1081282Y0180937
X1170595Y0170056
X1090279Y0126524
X1160720Y0180862
X1102480Y0133722
X1078270Y0093462
X1080168Y0090721
X1133041Y0194137
X1146670Y0230110
X1159460Y0194090
X1118486Y0208942
X1086756Y0187540
X1099030Y0245140
X1109088Y0240668
X1109088Y0237668
X1111918Y0240718
X1111918Y0237718
X1109088Y0234668
X1111918Y0234718
X1087400Y0273762
X1084400Y0273762
X1081400Y0273762
X1078400Y0273762
X1075400Y0273762
X1079853Y0269492
X1082853Y0269492
X1080323Y0265438
X1080883Y0260842
X1083883Y0260842
X1083823Y0265438
X1076823Y0265438
X1077883Y0260842
X1080973Y0246362
X1083973Y0246362
X1077973Y0246362
X1148795Y0213731
X1160630Y0213870
X1158172Y0230157
X1148354Y0222677
X1150914Y0197407
X1164300Y0197262
X1162500Y0190962
X1165000Y0190962
X1160732Y0204887
X1163732Y0204887
X1139457Y0227277
X1120190Y0255652
X1128485Y0198159
X1124858Y0197309
X1124360Y0259712
X1144457Y0227277
X1141957Y0227277
X1161690Y0374110
X1078853Y0363966
X1076353Y0363966
X1147700Y0362731
X1147700Y0368041
X1124985Y0302578
X1122059Y0305673
X1094130Y0298342
X1086630Y0298342
X1091630Y0298342
X1084130Y0298342
X1089130Y0298342
X1156790Y0363231
X1137315Y0379592
X1087330Y0379251
X1087330Y0374131
X1087330Y0369061
X1088018Y0289400
X1085018Y0289400
X1082018Y0289400
X1079018Y0289400
X1076018Y0289400
X1142302Y0366532
X1129995Y0301637
X1120544Y0312200
X1171540Y0310902
X1156790Y0373231
X1140465Y0379592
X1077270Y0379251
X1077270Y0374131
X1077270Y0369061
X1105553Y0356475
X1072310Y0364422
X1159460Y0366025
X1159753Y0361281
X1125409Y0305797
X1089660Y0408560
X1087280Y0435437
X1076820Y0473892
X1079320Y0473892
X1081930Y0477132
X1076598Y0477087
X1095820Y0420762
X1081045Y0435637
X1078545Y0435637
X1078120Y0411262
X1090245Y0435437
X1084245Y0435437
X1156100Y0456342
X1075462Y0386723
X1081906Y0472577
X1073724Y0476867
X1164320Y0451062
X1078151Y0413911
X1127402Y0456174
X1117820Y0456132
X1144720Y0498662
X1144720Y0501362
X1085720Y0522422
X1082220Y0522362
X1136051Y0503324
X1138551Y0503324
X1073589Y0506461
X1073250Y0582332
X1167190Y0526922
X1169690Y0526922
X1077751Y0522235
X1148220Y0501362
X1076739Y0506461
X1153370Y0638192
X1169820Y0636052
X1156770Y0638192
X1165260Y0642112
X1161860Y0642112
X1142127Y0586452
X1144810Y0613762
X1158300Y0585862
X1150140Y0610362
X1140697Y0608762
X1170740Y0602132
X1168402Y0642136
X1158762Y0642266
X1166722Y0636206
X1159912Y0638216
X1150272Y0638346
X1153490Y0610322
X1142790Y0611122
X1170337Y0607327
X1153467Y0586462
X1138500Y0586362
X1142967Y0592097
X1133720Y0642862
X1136720Y0641362
X1124120Y0643762
X1129420Y0644062
X1113207Y0744455
X1093497Y0744655
X1084637Y0744635
X1127972Y0747250
X1155962Y0746193
X1122980Y0741312
X1096477Y0744385
X1088262Y1252293
X1133200Y1255702
X1168483Y1255381
X1138783Y1255381
X1135750Y1255672
X1165279Y1377700
X1162779Y1377700
X1162779Y1380200
X1165279Y1380200
X1162779Y1382700
X1165279Y1382700
X1167829Y1382700
X1167829Y1380200
X1167829Y1377700
X1167829Y1375200
X1165279Y1375200
X1162779Y1375200
X1167829Y1370200
X1165279Y1370200
X1162779Y1370200
X1167829Y1372700
X1162779Y1372700
X1165279Y1372700
X1149297Y1377700
X1149297Y1380200
X1146797Y1377700
X1146797Y1380200
X1149297Y1382700
X1146797Y1382700
X1144247Y1382700
X1144247Y1380200
X1144247Y1377700
X1149297Y1375200
X1146797Y1375200
X1144247Y1375200
X1149297Y1370200
X1146797Y1370200
X1149297Y1372700
X1146797Y1372700
X1144247Y1370200
X1144247Y1372700
X1124679Y1380200
X1124679Y1377700
X1127179Y1377700
X1127179Y1380200
X1124679Y1382700
X1127179Y1382700
X1129729Y1382700
X1129729Y1380200
X1129729Y1377700
X1124679Y1375200
X1127179Y1375200
X1129729Y1375200
X1129729Y1370200
X1129729Y1372700
X1127179Y1370200
X1124679Y1370200
X1124679Y1372700
X1127179Y1372700
X1156609Y1286685
X1142674Y1287608
X1089714Y1285144
X1083714Y1291144
X1074387Y1294652
X1077634Y1294869
X1083714Y1288144
X1083714Y1285144
X1156446Y1456113
X1159446Y1456113
X1156476Y1458918
X1156386Y1461753
X1159476Y1458918
X1159386Y1461753
X1153821Y1456587
X1153821Y1459607
X1156386Y1469253
X1159386Y1469253
X1156386Y1466753
X1156386Y1464253
X1159386Y1466753
X1159386Y1464253
X1154288Y1432502
X1150821Y1456587
X1150821Y1459607
X1151669Y1438598
X1147203Y1439068
X1151669Y1441498
X1149569Y1440098
X1147203Y1441968
X1151669Y1435698
X1149469Y1437098
X1139573Y1435584
X1144233Y1435584
X1141903Y1436334
X1146563Y1436334
X1129169Y1445719
X1167312Y1445964
X1125995Y1439780
X1164138Y1439780
X1135568Y1442923
X1122879Y1434024
X1161022Y1433999
X1137311Y1445191
X1122879Y1431474
X1161022Y1431499
X1129169Y1442998
X1167312Y1442998
X1133169Y1445690
X1171342Y1445650
X1165279Y1385200
X1162779Y1385200
X1167829Y1385200
X1146797Y1385200
X1149297Y1385200
X1144247Y1385200
X1127179Y1385200
X1124679Y1385200
X1129729Y1385200
X1123379Y1443583
X1161522Y1443630
X1115853Y1435532
X1115853Y1426342
X1141591Y1460353
X1141591Y1471353
X1141591Y1468353
X1141591Y1465353
X1141591Y1462853
X1128341Y1471453
X1130841Y1471453
X1133841Y1471453
X1133841Y1460453
X1130841Y1460453
X1128341Y1460453
X1133841Y1468453
X1130841Y1468453
X1128341Y1468453
X1133841Y1465453
X1133841Y1462953
X1130841Y1465453
X1128341Y1462953
X1128341Y1465453
X1130841Y1462953
X1118110Y1398010
X1117574Y1448604
X1133209Y1397119
X1135709Y1397119
X1127788Y1397126
X1121174Y1420136
X1121174Y1417536
X1123674Y1420136
X1123674Y1417536
X1121174Y1414936
X1123674Y1414936
X1134229Y1420615
X1129029Y1420615
X1131629Y1420615
X1134429Y1426829
X1133512Y1430461
X1135942Y1430461
X1131042Y1430461
X1133512Y1436061
X1135942Y1436061
X1131042Y1436061
X1121174Y1422736
X1123674Y1422736
X1134229Y1423722
X1129029Y1423722
X1131629Y1423722
X1126117Y1450504
X1136004Y1447858
X1138209Y1397119
X1146118Y1397126
X1136829Y1420615
X1139429Y1420615
X1145573Y1420631
X1142629Y1420615
X1150732Y1420326
X1148243Y1417726
X1150843Y1417726
X1148243Y1415126
X1150843Y1415126
X1137029Y1426829
X1145542Y1426861
X1136829Y1423722
X1145573Y1423738
X1145108Y1476732
X1157786Y1398252
X1154714Y1398295
X1165931Y1397126
X1156524Y1418006
X1156524Y1420606
X1156524Y1415406
X1161724Y1418006
X1161724Y1420606
X1161724Y1415406
X1159124Y1415406
X1159124Y1420606
X1159124Y1418006
X1153913Y1418006
X1153913Y1415406
X1153913Y1420606
X1167172Y1420615
X1156524Y1423206
X1161724Y1423206
X1159124Y1423206
X1153913Y1423206
X1167172Y1423722
X1158954Y1450274
X1164260Y1450423
X1155964Y1440864
X1171752Y1397119
X1169772Y1420615
X1169185Y1430461
X1171655Y1430461
X1169185Y1436061
X1171655Y1436061
X1169772Y1423722
X1113725Y1530935
X1155187Y1582738
X1152187Y1582738
X1164595Y1582738
X1161595Y1582738
X1145187Y1582738
X1142187Y1582738
X1171595Y1582738
X1145187Y1574738
X1155187Y1574738
X1164595Y1574738
X1161339Y1550301
X1171595Y1574738
X1161595Y1574738
X1142187Y1574738
X1152187Y1574738
X1157402Y1550301
X1135187Y1582738
X1169213Y1550301
X1132187Y1582738
X1165276Y1550301
X1077734Y1554364
X1141690Y1552920
X1082734Y1554364
X1141654Y1550301
X1143060Y1538380
X1145410Y1540640
X1104750Y1549346
X1149528Y1550301
X1153465Y1550301
X1101600Y1554364
X1151497Y1524187
X1155433Y1524187
X1074010Y1510650
X1163308Y1524187
X1159371Y1524187
X1167245Y1524187
X1105480Y1517982
X1110725Y1518046
X1114400Y1518237
X1171182Y1524187
X1073864Y1539262
X1085830Y1539262
X1085830Y1536262
X1073864Y1536262
X1088530Y1539262
X1094530Y1539262
X1091530Y1539262
X1091530Y1536262
X1088530Y1536262
X1088530Y1542262
X1094530Y1542262
X1097230Y1542262
X1091530Y1542262
X1073864Y1542262
X1085830Y1542262
X1091530Y1554262
X1097230Y1554262
X1094530Y1554262
X1091530Y1548262
X1091530Y1545262
X1091530Y1551262
X1097230Y1548262
X1094530Y1548262
X1097230Y1545262
X1094530Y1545262
X1097230Y1551262
X1094530Y1551262
X1085830Y1554262
X1088530Y1554262
X1085830Y1548262
X1088530Y1548262
X1085830Y1545262
X1088530Y1545262
X1085830Y1551262
X1088530Y1551262
X1073864Y1554262
X1073864Y1548262
X1073864Y1545262
X1073864Y1551262
X1137717Y1558020
X1138430Y1524150
X1109118Y1526046
X1132142Y1555301
X1133780Y1550301
X1135748Y1524187
X1127008Y1550285
X1127008Y1524203
X1157700Y1681100
X1162383Y1652505
X1163970Y1620600
X1095302Y1585650
X1098302Y1585650
X1089302Y1585650
X1092302Y1585650
X1150380Y1602590
X1140750Y1604330
X1169460Y1611630
X1169460Y1616630
X1169460Y1606630
X1092436Y1603944
X1095436Y1603944
X1145187Y1590738
X1155187Y1590738
X1164595Y1590738
X1135187Y1590738
X1142187Y1590738
X1152187Y1590738
X1161595Y1590738
X1171595Y1590738
X1132187Y1590738
X1164830Y1628830
X1106480Y1641275
X1113110Y1666460
X1091880Y1673720
X1084000Y1647110
X1115802Y1615010
X1117182Y1625460
X1158030Y1619250
X1158325Y1642600
X1169325Y1642600
X1108320Y1680200
X1113325Y1627975
X1163079Y1601479
X1113990Y1631370
X1090901Y1621203
X1087901Y1621203
X1093901Y1621203
X1096901Y1621203
X1090901Y1630203
X1087901Y1630203
X1090901Y1627203
X1087901Y1627203
X1087901Y1624203
X1090901Y1624203
X1087901Y1633203
X1090901Y1633203
X1093901Y1630203
X1093901Y1627203
X1093901Y1624203
X1096901Y1630203
X1096901Y1627203
X1096901Y1624203
X1096901Y1633203
X1093901Y1633203
X1099901Y1621203
X1099901Y1630203
X1099901Y1627203
X1099901Y1624203
X1099901Y1633203
X1161076Y1680624
X1170930Y1654632
X1159930Y1654632
X1164830Y1654632
X1152257Y1628910
X1146960Y1618960
X1169968Y1602370
X1124862Y1615010
X1141525Y1597630
X1117407Y1628495
X1094225Y1671710
X1088790Y1641830
X1165950Y1617729
X1102930Y1668690
X1099457Y1638875
X1095649Y1638875
X1161613Y1669112
X1104457Y1675490
X1170930Y1645632
X1164830Y1645632
X1159930Y1645632
X1095900Y1646935
X1152930Y1633880
X1139392Y1620851
X1131632Y1625969
X1127377Y1628485
X1152950Y1616470
X1168192Y1604130
X1120472Y1615010
X1119300Y1724100
X1114300Y1722700
X1119200Y1727200
X1119200Y1730300
X1114150Y1715726
X1110663Y1719189
X1112200Y1709000
X1112252Y1706170
X1112130Y1711600
X1116338Y1711380
X1113055Y1718338
X1072208Y1731911
X1092072Y1734244
X1111866Y1737108
X1131866Y1737108
X1207180Y1685680
X1205563Y1698340
X1217210Y1684520
X1201505Y1688435
X1194793Y1698295
X1190735Y1688390
X1216363Y1698605
X1212305Y1688700
X1214834Y1726724
X1203939Y1726459
X1193174Y1726414
X1218810Y1700732
X1203110Y1700467
X1213910Y1700732
X1208010Y1700467
X1197240Y1700422
X1192340Y1700422
X1204793Y1714947
X1215593Y1715212
X1194023Y1714902
X1208010Y1691467
X1203110Y1691467
X1213910Y1691732
X1218810Y1691732
X1197240Y1691422
X1192340Y1691422
X1191866Y1737108
X1211866Y1737108
X1231866Y1737108
X1251866Y1737108
X1199400Y1627800
X1186000Y1640000
X1184383Y1652505
X1183320Y1597080
X1184200Y1602700
X1184200Y1599900
X1178140Y1601100
X1174595Y1590738
X1185030Y1624660
X1178250Y1609100
X1174550Y1615630
X1205820Y1652910
X1173383Y1652505
X1180325Y1642600
X1201600Y1633790
X1190895Y1642910
X1183440Y1591640
X1183410Y1594450
X1260472Y1590094
X1248412Y1590094
X1236352Y1590094
X1224292Y1590094
X1208832Y1590094
X1200172Y1590094
X1269132Y1590094
X1257072Y1590094
X1245012Y1590094
X1232952Y1590094
X1220892Y1590094
X1212232Y1590094
X1196772Y1590094
X1205472Y1602380
X1217532Y1602380
X1229592Y1602380
X1241652Y1602380
X1253712Y1602380
X1265772Y1602380
X1202072Y1602380
X1214132Y1602380
X1226192Y1602380
X1238252Y1602380
X1250312Y1602380
X1262372Y1602380
X1205472Y1614292
X1217532Y1614292
X1229592Y1614292
X1241652Y1614292
X1253712Y1614292
X1265772Y1614292
X1202072Y1614292
X1214132Y1614292
X1226192Y1614292
X1238252Y1614292
X1250312Y1614292
X1262372Y1614292
X1172076Y1680624
X1175830Y1654632
X1210830Y1676500
X1201106Y1677873
X1193646Y1680934
X1183076Y1680624
X1186830Y1654632
X1192500Y1654942
X1197400Y1654942
X1181930Y1654632
X1187600Y1622064
X1184501Y1606521
X1213980Y1676500
X1201110Y1681767
X1194183Y1669422
X1172613Y1669112
X1183613Y1669112
X1210457Y1658415
X1197400Y1645942
X1192500Y1645942
X1175830Y1645632
X1186830Y1645632
X1181930Y1645632
X1176900Y1627510
X1172530Y1623020
X1182470Y1618914
X1185030Y1633010
X1266550Y1604876
X1266550Y1611796
X1266550Y1616788
X1261594Y1604876
X1261594Y1611796
X1261594Y1616788
X1254490Y1616788
X1254490Y1604876
X1254490Y1611796
X1249534Y1616788
X1249534Y1604876
X1249534Y1611796
X1237474Y1604876
X1237474Y1611796
X1242430Y1604876
X1242430Y1611796
X1237474Y1616788
X1242430Y1616788
X1230370Y1616788
X1225414Y1616788
X1230370Y1604876
X1230370Y1611796
X1225414Y1604876
X1225414Y1611796
X1218310Y1611796
X1218310Y1604876
X1218310Y1616788
X1213354Y1611796
X1213354Y1604876
X1213354Y1616788
X1206250Y1616788
X1206250Y1611796
X1206250Y1604876
X1201294Y1616788
X1201294Y1611796
X1201294Y1604876
X1268354Y1587598
X1268354Y1592590
X1266550Y1599884
X1256294Y1592590
X1261250Y1592590
X1256294Y1587598
X1261250Y1587598
X1261594Y1599884
X1254490Y1599884
X1249190Y1587598
X1244234Y1587598
X1244234Y1592590
X1249190Y1592590
X1237130Y1592590
X1237130Y1587598
X1249534Y1599884
X1237474Y1599884
X1242430Y1599884
X1232174Y1592590
X1232174Y1587598
X1220114Y1587598
X1225070Y1587598
X1220114Y1592590
X1225070Y1592590
X1230370Y1599884
X1225414Y1599884
X1218310Y1599884
X1208054Y1592590
X1213010Y1592590
X1208054Y1587598
X1213010Y1587598
X1213354Y1599884
X1206250Y1599884
X1200950Y1587598
X1200950Y1592590
X1195994Y1587598
X1195994Y1592590
X1201294Y1599884
X1174595Y1582738
X1174595Y1574738
X1194510Y1563076
X1187720Y1531862
X1198436Y1529362
X1187720Y1563182
X1184290Y1570080
X1187720Y1558682
X1198436Y1561062
X1198436Y1551192
X1184330Y1573260
X1187720Y1544292
X1198436Y1546492
X1187720Y1548772
X1198485Y1534313
X1187720Y1536362
X1198497Y1539667
X1260472Y1578182
X1248412Y1578182
X1236352Y1578182
X1224292Y1578182
X1208832Y1578182
X1200172Y1578182
X1269132Y1578182
X1257072Y1578182
X1245012Y1578182
X1232952Y1578182
X1220892Y1578182
X1212232Y1578182
X1196772Y1578182
X1198546Y1524688
X1197181Y1563587
X1268354Y1580678
X1268354Y1575592
X1256294Y1580678
X1261250Y1580678
X1256294Y1575686
X1261250Y1575686
X1249190Y1575686
X1244234Y1575686
X1249190Y1580678
X1244234Y1580678
X1237130Y1580678
X1237130Y1575686
X1232174Y1575686
X1232174Y1580678
X1220114Y1580678
X1220114Y1575686
X1225070Y1575686
X1225070Y1580678
X1208054Y1580678
X1213010Y1580678
X1208054Y1575686
X1213010Y1575686
X1200950Y1575686
X1200950Y1580678
X1195994Y1575686
X1195994Y1580678
X1179922Y1524203
X1179922Y1550285
X1198436Y1556192
X1187720Y1553692
X1198546Y1520188
X1187830Y1526688
X1187830Y1522188
X1187720Y1517688
X1189612Y1438998
X1185346Y1439228
X1189612Y1441898
X1187512Y1440498
X1185346Y1442128
X1191918Y1432516
X1189612Y1436098
X1187412Y1437498
X1177716Y1435584
X1182376Y1435584
X1180046Y1436334
X1184706Y1436334
X1173711Y1442923
X1175454Y1445191
X1187797Y1385200
X1185297Y1385200
X1182747Y1385200
X1174252Y1397119
X1176752Y1397119
X1184661Y1397126
X1172372Y1420615
X1177572Y1420615
X1174972Y1420615
X1180772Y1420615
X1183716Y1420631
X1172572Y1426829
X1175172Y1426829
X1183685Y1426861
X1174085Y1430461
X1174085Y1436061
X1172372Y1423722
X1174972Y1423722
X1183716Y1423738
X1174147Y1447858
X1189135Y1397529
X1190444Y1420384
X1191486Y1417887
X1191486Y1415287
X1186386Y1417887
X1186386Y1415287
X1188986Y1417887
X1188986Y1415287
X1187736Y1420387
X1191930Y1424647
X1197700Y1432672
X1194750Y1424672
X1198010Y1441902
X1198880Y1457162
X1269012Y1368293
X1269012Y1371693
X1257672Y1351008
X1187797Y1380200
X1187797Y1377700
X1187797Y1382700
X1187797Y1375200
X1187797Y1370200
X1187797Y1372700
X1185297Y1380200
X1185297Y1377700
X1185297Y1382700
X1182747Y1382700
X1182747Y1377700
X1182747Y1380200
X1185297Y1375200
X1182747Y1375200
X1185297Y1370200
X1182747Y1370200
X1185297Y1372700
X1182747Y1372700
X1172573Y1286765
X1175573Y1286765
X1257586Y1334649
X1253586Y1334649
X1224189Y1259155
X1207607Y0754095
X1202307Y0757082
X1206432Y0758995
X1202300Y0753962
X1210288Y0754081
X1185687Y0744475
X1242260Y0757602
X1228320Y0758598
X1206757Y0744455
X1211277Y0744265
X1263486Y0739949
X1255520Y0747362
X1173020Y0745972
X1258667Y0751405
X1223327Y0757615
X1266727Y0752955
X1215896Y0756942
X1219060Y0757272
X1202600Y0759662
X1256787Y0749605
X1204880Y0754032
X1183230Y0739102
X1173220Y0636052
X1186760Y0642062
X1183360Y0642062
X1200698Y0586172
X1198198Y0586172
X1195698Y0586172
X1207100Y0600882
X1193198Y0586172
X1208980Y0598462
X1214000Y0599262
X1175217Y0595762
X1177570Y0602052
X1189902Y0642086
X1180262Y0642216
X1176362Y0636076
X1173990Y0602192
X1199027Y0588714
X1174880Y0592652
X1174980Y0585632
X1181300Y0584762
X1172310Y0584562
X1255920Y0511362
X1255150Y0520672
X1251650Y0520672
X1234150Y0520672
X1237650Y0520672
X1241150Y0520672
X1244650Y0520672
X1248150Y0520672
X1227150Y0520672
X1230650Y0520672
X1223650Y0520672
X1172720Y0527862
X1218870Y0418082
X1269220Y0477362
X1260220Y0477362
X1267220Y0451362
X1253220Y0451362
X1261220Y0454362
X1256220Y0434362
X1224300Y0380400
X1186280Y0298972
X1181450Y0306052
X1234720Y0380362
X1232720Y0377862
X1221220Y0380362
X1174120Y0355362
X1236720Y0377862
X1243589Y0379595
X1204475Y0350684
X1271150Y0305792
X1255150Y0306211
X1186653Y0302242
X1188810Y0296088
X1180398Y0289814
X1227500Y0380400
X1267150Y0305998
X1252040Y0306480
X1230720Y0380362
X1263150Y0294726
X1258250Y0292986
X1269960Y0294536
X1205165Y0380962
X1210900Y0265300
X1259703Y0209808
X1240500Y0244332
X1240500Y0248332
X1231720Y0209862
X1233282Y0201875
X1231720Y0217862
X1233780Y0214572
X1267773Y0208373
X1265207Y0208442
X1255613Y0209568
X1219220Y0247148
X1200720Y0187862
X1200720Y0184862
X1225320Y0200162
X1223180Y0210552
X1219060Y0213312
X1267593Y0229462
X1203200Y0202514
X1239045Y0224062
X1213540Y0224792
X1215720Y0204862
X1219220Y0243862
X1188600Y0225962
X1206660Y0224742
X1213720Y0195362
X1226093Y0193462
X1194840Y0236592
X1207220Y0243998
X1236593Y0197462
X1245593Y0211762
X1245486Y0203000
X1245593Y0219662
X1256504Y0217462
X1256593Y0225972
X1256593Y0233972
X1256584Y0248002
X1266518Y0237042
X1256574Y0238662
X1256494Y0243177
X1264854Y0256496
X1264854Y0253996
X1187013Y0238972
X1258883Y0280558
X1269904Y0192692
X1267289Y0192167
X1256593Y0221462
X1264584Y0226592
X1246878Y0248615
X1245514Y0224302
X1236220Y0189362
X1188500Y0205772
X1187300Y0217862
X1186340Y0204492
X1188300Y0189062
X1181500Y0215962
X1181500Y0218462
X1181500Y0211962
X1172835Y0218174
X1181369Y0199234
X1172925Y0202174
X1173100Y0186962
X1264874Y0217462
X1200830Y0206002
X1229720Y0197302
X1265065Y0249982
X1228520Y0202162
X1236720Y0257362
X1256070Y0229512
X1244720Y0230362
X1204220Y0189362
X1213720Y0189362
X1208365Y0271151
X1203858Y0185451
X1246444Y0256098
X1245593Y0237462
X1245593Y0241462
X1232000Y0248332
X1232000Y0244332
X1217720Y0249862
X1207220Y0247148
X1194840Y0240672
X1245574Y0234042
X1245614Y0227462
X1210084Y0224362
X1172795Y0222174
X1236520Y0213462
X1236584Y0217462
X1236593Y0209562
X1223720Y0205862
X1223720Y0217862
X1172865Y0210174
X1204420Y0195362
X1193500Y0188962
X1196100Y0188962
X1195100Y0217662
X1195500Y0204486
X1193000Y0204486
X1192600Y0217662
X1173065Y0194174
X1256454Y0252122
X1254370Y0241302
X1266715Y0244692
X1196720Y0252362
X1236620Y0221562
X1199720Y0252362
X1267618Y0225382
X1253950Y0246692
X1253860Y0235622
X1253440Y0230552
X1253624Y0201362
X1267315Y0220701
X1225574Y0188662
X1236584Y0205762
X1213720Y0200309
X1271315Y0220701
X1214054Y0186092
X1181470Y0208802
X1181500Y0222162
X1184510Y0188962
X1236410Y0201462
X1200963Y0212648
X1223134Y0190802
X1181700Y0186962
X1183460Y0205342
X1225100Y0091500
X1185400Y0104000
X1222920Y0148909
X1265010Y0162222
X1222920Y0144909
X1271593Y0165962
X1223100Y0130700
X1241035Y0114399
X1257581Y0114579
X1256093Y0149462
X1249362Y0111600
X1187413Y0143132
X1202920Y0117162
X1185420Y0153762
X1250424Y0108943
X1252520Y0092022
X1264220Y0110462
X1229500Y0125100
X1244200Y0112862
X1223500Y0111162
X1243100Y0160181
X1241100Y0145842
X1246272Y0164889
X1214415Y0153962
X1180676Y0106858
X1193532Y0132644
X1271284Y0108971
X1222100Y0091600
X1228425Y0091500
X1250010Y0117121
X1258539Y0100900
X1266722Y0101005
X1226093Y0172962
X1201700Y0110000
X1214534Y0157462
X1219534Y0116492
X1224614Y0116962
X1232182Y0110659
X1226093Y0134262
X1226400Y0125200
X1222593Y0140962
X1226093Y0140962
X1222720Y0163362
X1225874Y0163462
X1226093Y0168162
X1222594Y0154242
X1226093Y0156962
X1222724Y0176102
X1238604Y0150062
X1240904Y0151592
X1254994Y0157382
X1264663Y0158946
X1239874Y0182322
X1243184Y0182422
X1222890Y0157002
X1214134Y0180972
X1214693Y0174962
X1181476Y0172247
X1240728Y0136198
X1188700Y0100700
X1215800Y0111300
X1194800Y0143112
X1206694Y0139512
X1234093Y0144962
X1206434Y0129492
X1206114Y0132962
X1234746Y0136040
X1244120Y0167462
X1261899Y0174648
X1243808Y0116832
X1252961Y0111903
X1230250Y0089450
X1190700Y0099000
X1185500Y0101400
X1201800Y0094600
X1206900Y0115900
X1204800Y0108900
X1264685Y0175506
X1208518Y0174162
X1242520Y0165362
X1214593Y0168962
X1256093Y0143462
X1226093Y0152792
X1214573Y0148909
X1266093Y0129962
X1247333Y0121999
X1223100Y0127300
X1197627Y0132859
X1228704Y0112122
X1206093Y0120362
X1264620Y0092724
X1262800Y0101100
X1239907Y0095008
X1215763Y0114363
X1225700Y0108962
X1262320Y0096012
X1241010Y0110782
X1191020Y0170862
X1173314Y0176452
X1181420Y0157962
X1222593Y0168962
X1210910Y0129502
X1260641Y0114399
X1258539Y0109263
X1214091Y0164962
X1197414Y0161592
X1206664Y0158952
X1226093Y0177962
X1202860Y0120392
X1264098Y0088787
X1270329Y0101011
X1296034Y-0017929
X1299302Y-0017943
X1293024Y-0016637
X1293024Y-0026666
X1296019Y-0025443
X1296034Y-0027958
X1299317Y-0025457
X1299302Y-0027972
X1299317Y-0021583
X1296019Y-0021569
X1296034Y-0037987
X1299302Y-0038001
X1293024Y-0036695
X1299317Y-0031612
X1296019Y-0031598
X1296019Y-0035472
X1299317Y-0035486
X1339019Y-0037001
X1336024Y-0038224
X1332756Y-0038210
X1336009Y-0035709
X1332741Y-0035695
X1336024Y-0032069
X1332726Y-0032055
X1339019Y-0026472
X1336024Y-0027695
X1336009Y-0025180
X1332726Y-0027681
X1332741Y-0025166
X1332726Y-0021526
X1336024Y-0021540
X1336024Y-0017666
X1332726Y-0017652
X1287795Y-0033989
X1287795Y-0029033
X1287795Y-0023989
X1287795Y-0019033
X1344248Y-0029033
X1344248Y-0033989
X1344248Y-0019033
X1344248Y-0023989
X1341752Y-0033211
X1341752Y-0029811
X1290291Y-0033211
X1290291Y-0029811
X1189393Y0060183
X1175926Y0069151
X1174120Y0057111
X1201158Y0057130
X1216176Y0056742
X1258727Y0052061
X1261227Y0052061
X1266464Y0083090
X1263454Y0083060
X1236620Y0058862
X1197520Y0056962
X1228420Y0058862
X1213026Y0056742
X1191700Y0056822
X1188720Y0056755
X1198609Y0049388
X1218609Y0049388
X1238609Y0049388
X1258609Y0049388
X1194478Y0056986
X1341752Y-0023211
X1341752Y-0019811
X1290291Y-0019811
X1290291Y-0023211
X1293024Y0023979
X1299317Y0019033
X1296019Y0019047
X1299302Y0022673
X1296034Y0022687
X1299287Y0025188
X1296019Y0025202
X1293024Y0013450
X1296019Y0008518
X1299317Y0008504
X1299302Y0012144
X1296034Y0012158
X1299317Y0014659
X1296019Y0014673
X1293024Y0003421
X1299317Y-0001525
X1296019Y-0001511
X1299302Y0002115
X1299317Y0004630
X1296034Y0002129
X1296019Y0004644
X1293024Y-0006608
X1299317Y-0011554
X1296019Y-0011540
X1296019Y-0005385
X1296034Y-0007900
X1299317Y-0005399
X1299302Y-0007914
X1296019Y-0015414
X1299317Y-0015428
X1336009Y-0015151
X1332741Y-0015137
X1339019Y-0016443
X1336024Y-0011511
X1332726Y-0011497
X1332741Y-0005108
X1332726Y-0007623
X1336009Y-0005122
X1336024Y-0007637
X1339019Y-0006414
X1336024Y-0001482
X1332726Y-0001468
X1339019Y0003615
X1332741Y0004921
X1332726Y0002406
X1336009Y0004907
X1336024Y0002392
X1336024Y0008547
X1332726Y0008561
X1332741Y0014950
X1332726Y0012435
X1336009Y0014936
X1336024Y0012421
X1339019Y0013644
X1339019Y0023673
X1332741Y0024979
X1332726Y0022464
X1336009Y0024965
X1336024Y0022450
X1336024Y0018576
X1332726Y0018590
X1287795Y-0013989
X1287795Y-0009033
X1287795Y-0003989
X1287795Y0000967
X1344248Y-0009033
X1344248Y-0013989
X1344248Y0000967
X1344248Y-0003989
X1341752Y-0013211
X1341752Y-0009811
X1290291Y-0009811
X1290291Y-0013211
X1333190Y0058825
X1317831Y0068652
X1307120Y0078562
X1310857Y0078542
X1285201Y0058121
X1279580Y0058132
X1282360Y0058132
X1276820Y0058142
X1311960Y0058152
X1289210Y0081232
X1308174Y0068652
X1349480Y0077072
X1311424Y0068652
X1321279Y0058767
X1322248Y0068487
X1293454Y0081232
X1346720Y0082912
X1278300Y0081232
X1330102Y0059025
X1314741Y0068652
X1293860Y0058312
X1291280Y0058262
X1311960Y0049672
X1318609Y0049388
X1338609Y0049388
X1316459Y0058697
X1301820Y0058672
X1322415Y0075480
X1311260Y0083032
X1341752Y-0003211
X1341752Y0000189
X1290291Y0000189
X1290291Y-0003211
X1302060Y0113852
X1302080Y0117032
X1314920Y0135361
X1275820Y0087962
X1315156Y0130656
X1343034Y0141698
X1332497Y0133931
X1286150Y0131092
X1291478Y0137745
X1282764Y0135398
X1366369Y0083820
X1348620Y0136162
X1281093Y0144516
X1277820Y0140682
X1281704Y0095402
X1297605Y0145824
X1279390Y0087697
X1279415Y0090847
X1314059Y0093877
X1308274Y0104162
X1329891Y0099455
X1322906Y0109733
X1278456Y0096187
X1282824Y0108872
X1291704Y0109427
X1300990Y0121812
X1329646Y0104954
X1345583Y0091307
X1336549Y0105970
X1344631Y0127244
X1349570Y0104147
X1353394Y0131812
X1349220Y0140362
X1366369Y0092450
X1366714Y0109506
X1306836Y0108242
X1347640Y0101950
X1294354Y0103166
X1370586Y0176366
X1283425Y0179272
X1283781Y0155788
X1369593Y0147462
X1369916Y0154132
X1357888Y0145893
X1349704Y0145385
X1362793Y0145262
X1366868Y0147341
X1301993Y0140462
X1283781Y0149115
X1323958Y0146227
X1356223Y0131569
X1339280Y0126175
X1330273Y0128373
X1302964Y0124633
X1278949Y0123567
X1275807Y0132922
X1276745Y0125850
X1281600Y0137962
X1284930Y0124922
X1288258Y0145501
X1292293Y0143162
X1285793Y0141562
X1295053Y0140181
X1294354Y0105912
X1279485Y0105752
X1366124Y0101529
X1350550Y0101632
X1316478Y0092970
X1300454Y0095302
X1327920Y0084418
X1293430Y0084072
X1348610Y0084712
X1271954Y0159143
X1288093Y0125962
X1292899Y0098519
X1307244Y0118452
X1314406Y0097756
X1310906Y0097807
X1319968Y0098266
X1292880Y0093162
X1322906Y0094212
X1298640Y0093062
X1275727Y0209597
X1273093Y0213962
X1325769Y0259001
X1320387Y0258901
X1323912Y0245111
X1282654Y0226309
X1282176Y0221436
X1278783Y0221386
X1278093Y0184462
X1272893Y0191262
X1292630Y0240462
X1288637Y0240448
X1290293Y0247562
X1285710Y0249182
X1277661Y0225685
X1279493Y0248662
X1273754Y0256504
X1277771Y0255173
X1276800Y0276562
X1305552Y0257974
X1311275Y0252297
X1309283Y0254162
X1307431Y0256099
X1314685Y0248651
X1313117Y0250605
X1291071Y0278543
X1291071Y0275543
X1369846Y0279848
X1349362Y0283155
X1363846Y0279848
X1343362Y0283155
X1272557Y0272436
X1278557Y0269477
X1278557Y0272436
X1282653Y0269446
X1275557Y0272436
X1275557Y0269477
X1279841Y0253052
X1280223Y0256841
X1282293Y0248962
X1369410Y0224504
X1293893Y0237962
X1286611Y0260908
X1313950Y0261612
X1326493Y0249562
X1328393Y0264262
X1317893Y0257462
X1333811Y0235348
X1361111Y0236448
X1284437Y0230280
X1287943Y0233748
X1282568Y0212722
X1370405Y0186938
X1369479Y0208384
X1370636Y0227292
X1283397Y0202085
X1278320Y0239292
X1275493Y0193962
X1278183Y0201262
X1273093Y0200038
X1278993Y0193262
X1365124Y0282744
X1344684Y0280259
X1368524Y0282744
X1348084Y0280259
X1282645Y0252271
X1282645Y0255671
X1303642Y0292636
X1307042Y0292636
X1291100Y0299692
X1294500Y0299692
X1291500Y0315362
X1291500Y0312862
X1291420Y0318162
X1291420Y0320662
X1290005Y0290268
X1295887Y0315571
X1305909Y0324764
X1312845Y0324764
X1321386Y0319841
X1314450Y0319841
X1336263Y0324461
X1343199Y0324461
X1323312Y0325670
X1330248Y0325670
X1336913Y0334384
X1329977Y0334384
X1350592Y0330749
X1343656Y0330749
X1356603Y0334043
X1363539Y0334043
X1350032Y0339611
X1356968Y0339611
X1303120Y0304162
X1308220Y0304262
X1359902Y0287540
X1353902Y0287540
X1340903Y0290755
X1335947Y0290755
X1329592Y0290920
X1324636Y0290920
X1324081Y0296540
X1319125Y0296540
X1313246Y0287631
X1307798Y0287561
X1302450Y0290072
X1308790Y0290172
X1290322Y0297056
X1295278Y0297056
X1290005Y0293768
X1355224Y0284644
X1358624Y0284644
X1361771Y0332275
X1351800Y0337843
X1345424Y0328981
X1338031Y0322693
X1331745Y0332616
X1328480Y0323902
X1316218Y0318073
X1311077Y0322996
X1358371Y0332275
X1355200Y0337843
X1348824Y0328981
X1341431Y0322693
X1335145Y0332616
X1325080Y0323902
X1319618Y0318073
X1307677Y0322996
X1323303Y0299176
X1319903Y0299176
X1340161Y0293404
X1336761Y0293404
X1328814Y0293556
X1325414Y0293556
X1304042Y0306998
X1307442Y0306998
X1312136Y0284948
X1308736Y0284948
X1339720Y0423162
X1342220Y0423162
X1337220Y0423162
X1344720Y0423162
X1284220Y0463362
X1274420Y0463362
X1291220Y0463362
X1283220Y0477362
X1276220Y0477362
X1301310Y0440862
X1278380Y0463362
X1300220Y0477362
X1295540Y0440902
X1296630Y0463462
X1294440Y0477267
X1272220Y0434362
X1284220Y0429362
X1280270Y0434362
X1272530Y0429362
X1317100Y0553900
X1356220Y0581862
X1335643Y0540048
X1338652Y0543590
X1338652Y0536654
X1327601Y0540049
X1340420Y0541822
X1340420Y0538422
X1333143Y0540049
X1330101Y0540049
X1361727Y0680665
X1370207Y0682245
X1303576Y0659671
X1308600Y0653500
X1358907Y0681262
X1356047Y0680000
X1325210Y0744322
X1328530Y0747702
X1315020Y0739862
X1290520Y0746562
X1305187Y0735630
X1289936Y0732539
X1275576Y0730879
X1292904Y0782048
X1336187Y0755635
X1294937Y0746965
X1311420Y0738262
X1301034Y0784165
X1292572Y0785575
X1297298Y0790982
X1309210Y0792802
X1305117Y0797125
X1292614Y0789910
X1303017Y0785837
X1306701Y0794779
X1309930Y0789852
X1307469Y0787772
X1304260Y0788265
X1365780Y1264328
X1365768Y1261821
X1368369Y1261897
X1368361Y1264594
X1368326Y1267218
X1365776Y1267158
X1365768Y1259321
X1365768Y1256821
X1368439Y1256717
X1368379Y1259287
X1363270Y1264358
X1363258Y1261851
X1349976Y1264403
X1352486Y1264373
X1352486Y1261873
X1349976Y1261903
X1363266Y1267188
X1352426Y1267218
X1349876Y1267158
X1363258Y1259351
X1363258Y1256851
X1349976Y1259403
X1352486Y1259373
X1349964Y1256896
X1352474Y1256866
X1333699Y1277410
X1336261Y1277654
X1333676Y1280218
X1333687Y1274903
X1333687Y1272403
X1333687Y1269903
X1336459Y1267227
X1347366Y1267188
X1336579Y1262057
X1336519Y1264627
X1347371Y1264564
X1347359Y1261857
X1336279Y1272347
X1336339Y1269777
X1333909Y1267167
X1334029Y1261997
X1333969Y1264567
X1336269Y1274957
X1347379Y1256687
X1347419Y1259257
X1331189Y1277440
X1320405Y1277455
X1317895Y1277485
X1320256Y1280218
X1317746Y1280248
X1331166Y1280248
X1331177Y1274933
X1320405Y1274955
X1317895Y1274985
X1331177Y1272433
X1331177Y1269933
X1320405Y1272455
X1320393Y1269948
X1317895Y1272485
X1317883Y1269978
X1320399Y1267117
X1317889Y1267147
X1331399Y1267197
X1331459Y1264597
X1331519Y1262027
X1315181Y1277594
X1315176Y1280218
X1304299Y1280967
X1315229Y1272287
X1315289Y1269717
X1315169Y1274887
X1370438Y1326091
X1368272Y1327721
X1367635Y1320904
X1365376Y1321938
X1370338Y1323091
X1368272Y1324821
X1349666Y1375940
X1352666Y1375940
X1349666Y1381560
X1352666Y1381560
X1349666Y1378560
X1352666Y1378560
X1363098Y1320951
X1360593Y1321872
X1340288Y1375940
X1346193Y1376023
X1343193Y1376023
X1334288Y1375940
X1337288Y1375940
X1337288Y1372440
X1343193Y1372523
X1346193Y1372523
X1340288Y1372440
X1334288Y1372440
X1335504Y1335353
X1333174Y1334603
X1338288Y1336553
X1340410Y1338017
X1340214Y1334853
X1336144Y1338247
X1340488Y1340853
X1338288Y1339653
X1336144Y1341147
X1324491Y1378478
X1324491Y1381478
X1331288Y1378560
X1327491Y1378478
X1327491Y1381478
X1324491Y1375858
X1331288Y1375940
X1327491Y1375858
X1324491Y1372658
X1327491Y1372358
X1331288Y1372440
X1330844Y1335353
X1328514Y1334603
X1301166Y1357637
X1303496Y1358387
X1308616Y1357945
X1304016Y1361045
X1304016Y1363945
X1306182Y1362315
X1306082Y1359315
X1308616Y1360445
X1308616Y1363345
X1296506Y1357637
X1298836Y1358387
X1350238Y1331647
X1318110Y1345073
X1286102Y1368107
X1282928Y1361833
X1314936Y1338799
X1347397Y1325320
X1292840Y1364821
X1279334Y1356089
X1311820Y1333018
X1324848Y1341787
X1343948Y1319592
X1356976Y1328361
X1294312Y1367279
X1326320Y1344245
X1358448Y1330819
X1279812Y1353552
X1311820Y1330518
X1343948Y1317092
X1286102Y1365051
X1318110Y1342017
X1350238Y1328591
X1354238Y1329329
X1322110Y1342755
X1290102Y1365789
X1301691Y1300444
X1301679Y1297937
X1301679Y1295437
X1301679Y1292937
X1304201Y1296624
X1304189Y1293917
X1304196Y1299248
X1301686Y1303268
X1299349Y1287617
X1299319Y1290197
X1304209Y1288747
X1304239Y1286147
X1304269Y1283567
X1301859Y1287587
X1301829Y1290167
X1301889Y1284987
X1304149Y1291317
X1299176Y1303298
X1296576Y1303298
X1276891Y1362891
X1299181Y1300474
X1296581Y1300474
X1299169Y1292967
X1296569Y1292967
X1296569Y1295467
X1296569Y1297967
X1299169Y1297967
X1299169Y1295467
X1296719Y1290197
X1279788Y1304042
X1312650Y1342572
X1344532Y1328161
X1271990Y1358079
X1275856Y1358098
X1272707Y1334865
X1280135Y1337402
X1280135Y1340002
X1280135Y1342602
X1280135Y1345202
X1280312Y1365689
X1288010Y1323307
X1291010Y1323307
X1298150Y1323217
X1295150Y1323217
X1287956Y1352531
X1290436Y1352531
X1292916Y1352531
X1294005Y1348982
X1291405Y1348982
X1293805Y1345875
X1288605Y1345875
X1291205Y1342768
X1288605Y1342768
X1293805Y1342768
X1296405Y1342768
X1286005Y1345875
X1286005Y1342768
X1291205Y1345875
X1294477Y1372651
X1293887Y1370043
X1283280Y1372301
X1287956Y1358131
X1290436Y1358131
X1292916Y1358131
X1304066Y1323578
X1311952Y1321945
X1305056Y1339704
X1305056Y1331904
X1305056Y1329304
X1305056Y1334504
X1307656Y1331904
X1307656Y1329304
X1307656Y1334504
X1305056Y1326704
X1307656Y1326704
X1305056Y1337104
X1307656Y1337104
X1302549Y1342784
X1315058Y1349488
X1302520Y1348762
X1302549Y1345891
X1299605Y1342768
X1312488Y1348353
X1320570Y1319634
X1320570Y1322741
X1328370Y1319634
X1325770Y1319634
X1323170Y1319634
X1331570Y1319634
X1323170Y1322741
X1325770Y1322741
X1317970Y1319634
X1317970Y1322741
X1325970Y1325848
X1323370Y1325848
X1319964Y1335097
X1324924Y1335097
X1322444Y1335097
X1319964Y1329497
X1324924Y1329497
X1322444Y1329497
X1327196Y1349068
X1324945Y1346877
X1344080Y1308519
X1340663Y1301001
X1343968Y1300579
X1337663Y1301001
X1344080Y1305919
X1337184Y1306506
X1339784Y1306506
X1337184Y1311706
X1337184Y1316906
X1337184Y1314306
X1339784Y1311706
X1339784Y1314306
X1339784Y1316906
X1338534Y1319406
X1339784Y1309106
X1337184Y1309106
X1334514Y1319650
X1334514Y1322757
X1343631Y1332568
X1347015Y1335876
X1334414Y1325853
X1350982Y1287048
X1359382Y1287048
X1362382Y1287048
X1353982Y1287048
X1357898Y1306208
X1363698Y1306208
X1360498Y1306208
X1355298Y1306208
X1352698Y1306208
X1350098Y1306208
X1354572Y1321671
X1357052Y1321671
X1354572Y1316071
X1357052Y1316071
X1352092Y1321671
X1352092Y1316071
X1357898Y1309315
X1355298Y1309315
X1358098Y1312422
X1355498Y1312422
X1350098Y1309315
X1352698Y1309315
X1359516Y1334058
X1356983Y1334095
X1369312Y1298280
X1369312Y1295747
X1369312Y1300880
X1366642Y1306224
X1369312Y1303480
X1370662Y1305980
X1366642Y1309331
X1366542Y1312427
X1367620Y1431472
X1370250Y1433715
X1365235Y1428637
X1370041Y1460374
X1367889Y1419235
X1368980Y1457122
X1367316Y1407458
X1367316Y1403458
X1367316Y1399053
X1364800Y1449231
X1368842Y1449261
X1362410Y1445272
X1370891Y1410306
X1349278Y1422674
X1349466Y1414456
X1349466Y1417456
X1349466Y1408456
X1349466Y1411456
X1352166Y1417456
X1352166Y1408456
X1352166Y1411456
X1352166Y1414456
X1352166Y1420456
X1349508Y1420020
X1349426Y1404986
X1352126Y1404986
X1349426Y1401986
X1352126Y1401986
X1334470Y1425148
X1346278Y1422674
X1346178Y1425254
X1343328Y1425164
X1340328Y1425164
X1337328Y1425164
X1334428Y1422584
X1343428Y1422584
X1340428Y1422584
X1337428Y1422584
X1343344Y1417456
X1337386Y1420020
X1340386Y1420020
X1343386Y1420020
X1346386Y1420020
X1334344Y1417456
X1334386Y1420020
X1337344Y1417456
X1340344Y1417456
X1346344Y1417456
X1334344Y1414456
X1346534Y1408496
X1346534Y1411496
X1340344Y1414456
X1343344Y1414456
X1346344Y1414456
X1337344Y1414456
X1337304Y1404986
X1340304Y1404986
X1343304Y1404986
X1346304Y1404986
X1334304Y1404986
X1334304Y1401986
X1337304Y1401986
X1340304Y1401986
X1343304Y1401986
X1346304Y1401986
X1331470Y1425148
X1328092Y1425148
X1325168Y1425194
X1325126Y1422630
X1322312Y1425018
X1328050Y1422584
X1331428Y1422584
X1327966Y1414456
X1327966Y1417456
X1327966Y1411456
X1327966Y1408456
X1331344Y1417456
X1328008Y1420020
X1331386Y1420020
X1330804Y1408536
X1330804Y1411536
X1331344Y1414456
X1325042Y1414502
X1325042Y1417502
X1325042Y1411502
X1325042Y1408502
X1325084Y1420066
X1322270Y1422454
X1322186Y1417326
X1322186Y1414326
X1322186Y1411326
X1322228Y1419890
X1327926Y1404986
X1331304Y1404986
X1331304Y1401986
X1367436Y1414778
X1355357Y1396020
X1365040Y1431142
X1364860Y1455172
X1370577Y1421899
X1367170Y1453142
X1308712Y1578182
X1296652Y1578182
X1284592Y1578182
X1272532Y1578182
X1369012Y1578182
X1356952Y1578182
X1344892Y1578182
X1329432Y1578182
X1320772Y1578182
X1305312Y1578182
X1293252Y1578182
X1281192Y1578182
X1365612Y1578182
X1353552Y1578182
X1341492Y1578182
X1332832Y1578182
X1317372Y1578182
X1364834Y1575592
X1369790Y1575592
X1364834Y1580678
X1369790Y1580678
X1352774Y1580678
X1357730Y1580678
X1352774Y1575686
X1357730Y1575686
X1340714Y1575686
X1345670Y1575686
X1340714Y1580678
X1345670Y1580678
X1333610Y1580678
X1333610Y1575686
X1328654Y1580678
X1328654Y1575686
X1316594Y1575686
X1321550Y1575686
X1316594Y1580678
X1321550Y1580678
X1304534Y1580678
X1309490Y1580678
X1304534Y1575686
X1309490Y1575686
X1297430Y1575686
X1292474Y1575686
X1292474Y1580678
X1297430Y1580678
X1285370Y1580678
X1285370Y1575686
X1280414Y1580678
X1280414Y1575686
X1273310Y1575592
X1273310Y1580678
X1308712Y1590094
X1296652Y1590094
X1284592Y1590094
X1272532Y1590094
X1369012Y1590094
X1356952Y1590094
X1344892Y1590094
X1329432Y1590094
X1320772Y1590094
X1305312Y1590094
X1293252Y1590094
X1281192Y1590094
X1365612Y1590094
X1353552Y1590094
X1341492Y1590094
X1332832Y1590094
X1317372Y1590094
X1277832Y1602380
X1289892Y1602380
X1301952Y1602380
X1314012Y1602380
X1326072Y1602380
X1338132Y1602380
X1350192Y1602380
X1362252Y1602380
X1274432Y1602380
X1286492Y1602380
X1298552Y1602380
X1310612Y1602380
X1322672Y1602380
X1334732Y1602380
X1346792Y1602380
X1358852Y1602380
X1370912Y1602380
X1277832Y1614292
X1289892Y1614292
X1301952Y1614292
X1314012Y1614292
X1326072Y1614292
X1338132Y1614292
X1350192Y1614292
X1362252Y1614292
X1274432Y1614292
X1286492Y1614292
X1298552Y1614292
X1310612Y1614292
X1322672Y1614292
X1334732Y1614292
X1346792Y1614292
X1358852Y1614292
X1370912Y1614292
X1370134Y1616788
X1370134Y1604876
X1370134Y1611796
X1358074Y1604876
X1358074Y1611796
X1358074Y1616788
X1363030Y1604876
X1363030Y1611796
X1363030Y1616788
X1350970Y1616788
X1350970Y1604876
X1350970Y1611796
X1346014Y1616788
X1346014Y1604876
X1346014Y1611796
X1333954Y1604876
X1333954Y1611796
X1333954Y1616788
X1338910Y1604876
X1338910Y1611796
X1338910Y1616788
X1326850Y1616788
X1321894Y1616788
X1326850Y1604876
X1326850Y1611796
X1321894Y1604876
X1321894Y1611796
X1314790Y1604876
X1314790Y1611796
X1314790Y1616788
X1309834Y1604876
X1309834Y1611796
X1309834Y1616788
X1302730Y1616788
X1302730Y1604876
X1302730Y1611796
X1297774Y1616788
X1297774Y1604876
X1297774Y1611796
X1290670Y1604876
X1285714Y1604876
X1290670Y1611796
X1285714Y1611796
X1285714Y1616788
X1290670Y1616788
X1278610Y1616788
X1273654Y1616788
X1278610Y1604876
X1278610Y1611796
X1273654Y1604876
X1273654Y1611796
X1364834Y1587598
X1369790Y1587598
X1364834Y1592590
X1369790Y1592590
X1370134Y1599790
X1352774Y1592590
X1357730Y1592590
X1352774Y1587598
X1357730Y1587598
X1358074Y1599884
X1363030Y1599884
X1350970Y1599884
X1340714Y1587598
X1345670Y1587598
X1340714Y1592590
X1345670Y1592590
X1333610Y1592590
X1333610Y1587598
X1346014Y1599884
X1333954Y1599884
X1338910Y1599884
X1328654Y1592590
X1328654Y1587598
X1316594Y1587598
X1321550Y1587598
X1316594Y1592590
X1321550Y1592590
X1326850Y1599884
X1321894Y1599884
X1304534Y1592590
X1309490Y1592590
X1304534Y1587598
X1309490Y1587598
X1314790Y1599884
X1309834Y1599884
X1302730Y1599884
X1292474Y1587598
X1297430Y1587598
X1292474Y1592590
X1297430Y1592590
X1285370Y1592590
X1285370Y1587598
X1297774Y1599884
X1290670Y1599884
X1285714Y1599884
X1280414Y1592590
X1280414Y1587598
X1273310Y1587598
X1273310Y1592590
X1278610Y1599790
X1273654Y1599790
X1271866Y1737108
X1291866Y1737108
X1311866Y1737108
X1331866Y1737108
X1351866Y1737108
X1371866Y1737108
X1391866Y1737108
X1411866Y1737108
X1431866Y1737108
X1386600Y1641400
X1393000Y1590300
X1446700Y1598400
X1386200Y1645700
X1396900Y1642100
X1400000Y1626362
X1410500Y1638862
X1395325Y1606862
X1401300Y1619917
X1446715Y1679957
X1438220Y1673955
X1448920Y1675062
X1438320Y1668292
X1442587Y1659242
X1442573Y1649862
X1453600Y1595662
X1456120Y1586262
X1381072Y1590094
X1377672Y1590094
X1470995Y1602380
X1467595Y1602380
X1470995Y1614292
X1467595Y1614292
X1465695Y1590094
X1462295Y1590094
X1374312Y1602380
X1386372Y1602380
X1382972Y1602380
X1374312Y1614292
X1386372Y1614292
X1382972Y1614292
X1463767Y1638302
X1448507Y1638212
X1459127Y1638302
X1454167Y1638302
X1431575Y1634842
X1443617Y1638212
X1438547Y1638212
X1400000Y1638362
X1400000Y1634362
X1441800Y1624500
X1441800Y1628700
X1410900Y1624800
X1451500Y1612800
X1430250Y1612812
X1438300Y1602600
X1438300Y1606800
X1456030Y1590302
X1440105Y1593352
X1423700Y1600400
X1419450Y1596150
X1402680Y1597700
X1396600Y1586400
X1396600Y1590200
X1438273Y1671103
X1446380Y1676291
X1446786Y1610639
X1396600Y1594000
X1407200Y1591400
X1438300Y1611000
X1438300Y1598400
X1460441Y1602441
X1419270Y1631000
X1429250Y1623391
X1441800Y1632900
X1441800Y1620300
X1452757Y1671399
X1413230Y1641042
X1400000Y1642362
X1451580Y1627990
X1425770Y1633772
X1400000Y1630362
X1466817Y1616788
X1471773Y1616788
X1471773Y1604876
X1466817Y1604876
X1471773Y1611796
X1466817Y1611796
X1430250Y1608442
X1426680Y1603262
X1411070Y1603282
X1382194Y1604876
X1382194Y1611796
X1387150Y1604876
X1387150Y1611796
X1382194Y1616788
X1387150Y1616788
X1375090Y1616788
X1375090Y1604876
X1375090Y1611796
X1466473Y1592590
X1466473Y1587598
X1466817Y1599884
X1471773Y1599884
X1461517Y1592590
X1461517Y1587598
X1446600Y1595400
X1398700Y1597800
X1381850Y1592590
X1381850Y1587598
X1382194Y1599884
X1387150Y1599884
X1376894Y1592590
X1376894Y1587598
X1375090Y1599790
X1422680Y1582100
X1386790Y1563610
X1402536Y1576097
X1407440Y1557552
X1400160Y1543342
X1427320Y1548575
X1409248Y1528862
X1427120Y1537355
X1400220Y1518862
X1426020Y1521535
X1384840Y1565640
X1391055Y1565037
X1391655Y1570037
X1382600Y1563480
X1433720Y1569762
X1425620Y1556662
X1448620Y1556162
X1416060Y1574922
X1400715Y1565037
X1458200Y1560037
X1400695Y1570037
X1458200Y1565037
X1381072Y1578182
X1377672Y1578182
X1465695Y1578182
X1462295Y1578182
X1457967Y1553729
X1457817Y1542509
X1414740Y1548375
X1414740Y1543475
X1414590Y1537155
X1457577Y1526689
X1414350Y1521335
X1414590Y1532255
X1414350Y1516435
X1444468Y1570610
X1404433Y1570037
X1404433Y1565037
X1422145Y1575362
X1396600Y1582500
X1418241Y1583441
X1466473Y1580678
X1466473Y1575686
X1461517Y1580678
X1461517Y1575686
X1437140Y1576012
X1428403Y1581378
X1381850Y1580678
X1381850Y1575686
X1392475Y1576097
X1376894Y1580678
X1376894Y1575686
X1416800Y1564862
X1436720Y1548192
X1403740Y1543475
X1403590Y1537155
X1403740Y1548375
X1436570Y1536972
X1403350Y1521335
X1403590Y1532255
X1436330Y1521152
X1403350Y1516435
X1387068Y1413991
X1461062Y1413246
X1387074Y1384272
X1390474Y1385142
X1435462Y1396409
X1435462Y1393009
X1387291Y1408163
X1387066Y1401734
X1440440Y1454892
X1390170Y1423942
X1434720Y1454862
X1383429Y1427652
X1445020Y1412672
X1458138Y1409955
X1439742Y1436924
X1460224Y1407545
X1424255Y1396612
X1444997Y1392885
X1377075Y1425014
X1385109Y1410427
X1451198Y1403047
X1459111Y1448669
X1459111Y1445669
X1455006Y1447938
X1467567Y1448669
X1467567Y1445669
X1443112Y1417929
X1423256Y1403728
X1419746Y1435932
X1426872Y1405811
X1389220Y1446708
X1400287Y1444711
X1419991Y1423404
X1421435Y1430415
X1410038Y1434670
X1410477Y1440117
X1398569Y1437860
X1401371Y1434592
X1395443Y1434700
X1395907Y1430227
X1388557Y1431645
X1393630Y1426562
X1418990Y1387452
X1412608Y1391687
X1412961Y1387387
X1415171Y1383692
X1406461Y1383862
X1401655Y1384676
X1396311Y1385712
X1387470Y1418302
X1421864Y1419730
X1421371Y1411719
X1422371Y1407722
X1409680Y1430613
X1413440Y1436774
X1416272Y1433949
X1414786Y1426890
X1392620Y1446708
X1419055Y1392497
X1415620Y1396652
X1414362Y1402191
X1403687Y1444711
X1419995Y1397492
X1390513Y1395452
X1421480Y1415731
X1451176Y1399026
X1437443Y1406289
X1424930Y1433850
X1381066Y1425008
X1378417Y1415292
X1434312Y1415197
X1433750Y1429208
X1430204Y1452014
X1429345Y1433695
X1376686Y1399758
X1376666Y1402778
X1377060Y1411231
X1371960Y1436172
X1396115Y1405289
X1388813Y1393160
X1396615Y1420289
X1396115Y1412789
X1384695Y1425047
X1411115Y1405289
X1403615Y1405289
X1411115Y1420289
X1403615Y1420289
X1411115Y1412789
X1405876Y1453298
X1423829Y1442776
X1419256Y1440258
X1414264Y1439494
X1439155Y1399064
X1443325Y1410068
X1431829Y1412370
X1431717Y1409125
X1431717Y1417125
X1431717Y1420625
X1427349Y1442776
X1431717Y1424125
X1431717Y1427632
X1461377Y1417844
X1459136Y1442241
X1459135Y1439627
X1454829Y1439732
X1465747Y1401405
X1466448Y1421499
X1467536Y1442241
X1467550Y1439642
X1459968Y1402765
X1377054Y1394028
X1443676Y1432624
X1464680Y1328672
X1466919Y1327018
X1469019Y1328418
X1464680Y1325772
X1469019Y1325518
X1469019Y1322618
X1466819Y1324018
X1464016Y1321927
X1459356Y1321927
X1461686Y1321177
X1457026Y1321177
X1436794Y1327491
X1432528Y1327721
X1434694Y1326091
X1431888Y1321927
X1429558Y1321177
X1436794Y1321691
X1434594Y1323091
X1436794Y1324591
X1432528Y1324821
X1427228Y1321927
X1424898Y1321177
X1404666Y1327491
X1400400Y1327721
X1402566Y1326091
X1399760Y1321927
X1397430Y1321177
X1404666Y1321691
X1402466Y1323091
X1404666Y1324591
X1400400Y1324821
X1395100Y1321927
X1392770Y1321177
X1372538Y1327491
X1372538Y1321691
X1372538Y1324591
X1422594Y1383301
X1382366Y1331647
X1414494Y1331647
X1446622Y1331647
X1443448Y1325373
X1411320Y1325373
X1379192Y1325373
X1440332Y1319592
X1453360Y1328361
X1408204Y1319592
X1421232Y1328361
X1376076Y1319592
X1389104Y1328361
X1454832Y1330819
X1422704Y1330819
X1390576Y1330819
X1376076Y1317092
X1408204Y1317092
X1440332Y1317092
X1446622Y1328591
X1414494Y1328591
X1382366Y1328591
X1398680Y1380582
X1418494Y1329329
X1386366Y1329329
X1450622Y1329329
X1377214Y1327653
X1408969Y1327645
X1441332Y1327793
X1372463Y1287048
X1375463Y1287048
X1376208Y1308519
X1376208Y1298119
X1371912Y1298280
X1371912Y1295747
X1376208Y1295586
X1376208Y1300719
X1371912Y1300880
X1376208Y1303319
X1376208Y1305919
X1371912Y1303480
X1375814Y1332653
X1379271Y1335963
X1395826Y1306208
X1392626Y1306208
X1390026Y1306208
X1387426Y1306208
X1384826Y1306208
X1382226Y1306208
X1386700Y1316071
X1389180Y1316071
X1384220Y1321671
X1384220Y1316071
X1387426Y1309315
X1390026Y1309315
X1387626Y1312422
X1390226Y1312422
X1384826Y1309315
X1382226Y1309315
X1389180Y1321671
X1386700Y1321671
X1392076Y1335658
X1390758Y1333473
X1402419Y1287198
X1399419Y1287198
X1407819Y1287198
X1410819Y1287198
X1408336Y1308519
X1401440Y1298280
X1401440Y1295747
X1401440Y1300880
X1402790Y1305980
X1401440Y1303480
X1408336Y1298119
X1404040Y1298280
X1404040Y1295747
X1408336Y1295586
X1408336Y1300719
X1404040Y1300880
X1408336Y1303319
X1408336Y1305919
X1404040Y1303480
X1398770Y1306224
X1398770Y1309331
X1398670Y1312427
X1407719Y1332560
X1411124Y1335924
X1427954Y1306208
X1424754Y1306208
X1422154Y1306208
X1419554Y1306208
X1416954Y1306208
X1414354Y1306208
X1422154Y1309315
X1419754Y1312422
X1422354Y1312422
X1419554Y1309315
X1416954Y1309315
X1414354Y1309315
X1421308Y1321671
X1421308Y1316071
X1416348Y1321671
X1418828Y1321671
X1416348Y1316071
X1418828Y1316071
X1423656Y1335468
X1421294Y1334095
X1440258Y1287198
X1445106Y1287158
X1437258Y1287198
X1437182Y1296458
X1437182Y1301591
X1437182Y1306791
X1437182Y1304191
X1440464Y1308519
X1440536Y1296455
X1440507Y1300230
X1440507Y1302830
X1440507Y1305430
X1434582Y1298991
X1434582Y1296458
X1434582Y1301591
X1434582Y1306791
X1434582Y1304191
X1430898Y1306224
X1437182Y1298991
X1430898Y1309331
X1430798Y1312427
X1440879Y1333085
X1443785Y1335981
X1450366Y1287198
X1461766Y1287198
X1458766Y1287198
X1453366Y1287198
X1454282Y1306208
X1460082Y1306208
X1456882Y1306208
X1451682Y1306208
X1449082Y1306208
X1446482Y1306208
X1448476Y1316071
X1450956Y1316071
X1454282Y1309315
X1454482Y1312422
X1451682Y1309315
X1449082Y1309315
X1451882Y1312422
X1446482Y1309315
X1453436Y1321671
X1453436Y1316071
X1448476Y1321671
X1450956Y1321671
X1455436Y1335598
X1453303Y1334095
X1468296Y1300880
X1465696Y1300880
X1468296Y1303480
X1467046Y1305980
X1465696Y1303480
X1463026Y1306224
X1471180Y1300407
X1463026Y1309331
X1462926Y1312427
X1462482Y1264328
X1462470Y1261821
X1462396Y1267188
X1464981Y1264624
X1464989Y1261927
X1464946Y1267248
X1462470Y1256821
X1462470Y1259321
X1465059Y1256747
X1464999Y1259317
X1459972Y1264358
X1459960Y1261851
X1446678Y1264403
X1449188Y1264373
X1449188Y1261873
X1446678Y1261903
X1446556Y1267298
X1459886Y1267218
X1449106Y1267358
X1459960Y1256851
X1459960Y1259351
X1446678Y1259403
X1449188Y1259373
X1446666Y1256896
X1449176Y1256866
X1430305Y1264328
X1430293Y1261821
X1430296Y1267128
X1432846Y1267188
X1432881Y1264564
X1432889Y1261867
X1444046Y1267328
X1444039Y1261997
X1444051Y1264704
X1430293Y1259321
X1430293Y1256821
X1432959Y1256687
X1444159Y1256827
X1432899Y1259257
X1444099Y1259397
X1427795Y1264358
X1427783Y1261851
X1414501Y1264403
X1417011Y1264373
X1417011Y1261873
X1414501Y1261903
X1427786Y1267158
X1416916Y1267218
X1414366Y1267158
X1427783Y1259351
X1427783Y1256851
X1414501Y1259403
X1417011Y1259373
X1414489Y1256896
X1416999Y1256866
X1397958Y1264328
X1397946Y1261821
X1411856Y1267188
X1411861Y1264564
X1411849Y1261857
X1400486Y1267218
X1397936Y1267158
X1400529Y1261897
X1400521Y1264594
X1400539Y1259287
X1397946Y1259321
X1397946Y1256821
X1411969Y1256687
X1400599Y1256717
X1411909Y1259257
X1395448Y1264358
X1395436Y1261851
X1382154Y1264403
X1384664Y1264373
X1384664Y1261873
X1382154Y1261903
X1382036Y1267218
X1395426Y1267188
X1384586Y1267278
X1395436Y1259351
X1395436Y1256851
X1382154Y1259403
X1384664Y1259373
X1382142Y1256896
X1384652Y1256866
X1379526Y1267248
X1379531Y1264624
X1379519Y1261917
X1379639Y1256747
X1379579Y1259317
X1449649Y1170069
X1447149Y1170069
X1449799Y1153369
X1447299Y1153369
X1449649Y1161569
X1447149Y1161569
X1424119Y1169570
X1426619Y1169570
X1426619Y1153369
X1424119Y1153369
X1426619Y1161520
X1424119Y1161520
X1398831Y1170069
X1398831Y1153369
X1398831Y1161569
X1396081Y1170069
X1396081Y1153369
X1396081Y1161569
X1374938Y1170069
X1374938Y1161569
X1458911Y1161569
X1458911Y1170069
X1433337Y1153369
X1432887Y1161569
X1435837Y1153369
X1435387Y1161569
X1432887Y1170069
X1435387Y1170069
X1410613Y1161569
X1407913Y1153369
X1410413Y1153369
X1407913Y1161569
X1410613Y1170069
X1407913Y1170069
X1386673Y1153340
X1386673Y1161520
X1384089Y1153369
X1384173Y1161549
X1386673Y1169570
X1384173Y1169599
X1460814Y0702892
X1457176Y0692992
X1388976Y0737198
X1378306Y0717608
X1389561Y0720608
X1378306Y0705608
X1389568Y0706108
X1378306Y0693608
X1389568Y0691608
X1460814Y0714892
X1457176Y0704992
X1460814Y0690892
X1385338Y0735098
X1374668Y0719708
X1393199Y0722708
X1374668Y0707708
X1393206Y0708208
X1374668Y0695708
X1393206Y0693708
X1374668Y0683708
X1468876Y0728392
X1457176Y0716992
X1455692Y0731401
X1470841Y0721493
X1460187Y0729805
X1433418Y0729104
X1457714Y0741622
X1457620Y0736195
X1456237Y0726945
X1466451Y0726992
X1457597Y0739035
X1459057Y0733545
X1391408Y0738625
X1382920Y0733725
X1395631Y0724135
X1469651Y0713992
X1463239Y0713492
X1454439Y0718362
X1437177Y0720965
X1387143Y0719235
X1395631Y0709608
X1380731Y0716208
X1372243Y0721108
X1372243Y0709108
X1469477Y0699475
X1463239Y0701492
X1454751Y0706392
X1454751Y0694392
X1387143Y0704708
X1380731Y0704208
X1395631Y0695108
X1380731Y0692208
X1372243Y0697108
X1469651Y0684992
X1463239Y0689492
X1387143Y0690208
X1371931Y0685278
X1457176Y0680992
X1457176Y0668992
X1378306Y0681608
X1389568Y0677108
X1374668Y0671708
X1389568Y0662608
X1378306Y0657608
X1460814Y0654892
X1460814Y0678892
X1460814Y0666892
X1393206Y0679208
X1378306Y0669608
X1393206Y0664708
X1374668Y0659708
X1457176Y0656992
X1469020Y0647102
X1465171Y0647132
X1417022Y0621419
X1463639Y0677562
X1454439Y0682562
X1386931Y0675478
X1396031Y0680678
X1381131Y0680278
X1469439Y0670262
X1463639Y0665662
X1454439Y0670262
X1454889Y0658712
X1386931Y0660978
X1395831Y0666278
X1381131Y0668378
X1371931Y0672978
X1372381Y0661428
X1462010Y0645842
X1469651Y0655992
X1463639Y0653662
X1381131Y0656378
X1466292Y0631634
X1468060Y0633402
X1471460Y0633402
X1391260Y0507082
X1387600Y0499182
X1387550Y0502922
X1392685Y0498992
X1390220Y0497742
X1385190Y0501242
X1469951Y0429251
X1449600Y0402322
X1449296Y0407347
X1456777Y0426546
X1455642Y0409646
X1470942Y0409718
X1469777Y0418396
X1465836Y0408668
X1456777Y0418596
X1469720Y0434542
X1470954Y0406446
X1463277Y0406446
X1449296Y0410497
X1469760Y0452622
X1436320Y0303362
X1436320Y0305862
X1436335Y0309407
X1436120Y0318272
X1436270Y0312592
X1436050Y0321352
X1436120Y0315772
X1436232Y0344176
X1460849Y0343327
X1449777Y0371039
X1463600Y0374462
X1426647Y0329050
X1449777Y0362021
X1455600Y0297200
X1462870Y0355012
X1462790Y0359042
X1455920Y0373941
X1456770Y0342942
X1467700Y0370953
X1436436Y0300319
X1470877Y0374496
X1456700Y0369642
X1462777Y0362021
X1460600Y0352742
X1445777Y0362021
X1459312Y0341130
X1459900Y0370823
X1422030Y0220018
X1418630Y0220018
X1410186Y0197668
X1401406Y0197668
X1392656Y0197668
X1380602Y0197668
X1406786Y0197668
X1398006Y0197668
X1389256Y0197668
X1384002Y0197668
X1400985Y0240929
X1410820Y0220018
X1404385Y0240929
X1407420Y0220018
X1463833Y0235566
X1463330Y0264060
X1431636Y0230448
X1431933Y0238125
X1431431Y0267378
X1463950Y0258172
X1463510Y0273878
X1463808Y0244948
X1390600Y0248262
X1426510Y0184263
X1417350Y0184263
X1408229Y0184263
X1423110Y0184263
X1413950Y0184263
X1404829Y0184263
X1432660Y0220018
X1436060Y0220018
X1381951Y0221420
X1384895Y0221346
X1386138Y0225411
X1384017Y0223697
X1386868Y0222937
X1373493Y0227762
X1375257Y0229756
X1396900Y0228932
X1393460Y0226422
X1395960Y0226422
X1442434Y0210757
X1413847Y0239528
X1375619Y0236261
X1449110Y0233742
X1463833Y0230448
X1415340Y0231812
X1456150Y0214382
X1444570Y0238372
X1467761Y0205982
X1471308Y0230640
X1413900Y0225212
X1459961Y0210432
X1430120Y0225182
X1471690Y0259862
X1471510Y0252878
X1457361Y0205982
X1428336Y0232762
X1431430Y0264060
X1431430Y0256383
X1462561Y0205982
X1453670Y0278170
X1466660Y0273878
X1428940Y0269292
X1386237Y0275200
X1467230Y0252472
X1468620Y0258857
X1430130Y0259342
X1386237Y0265620
X1388908Y0260301
X1377626Y0264914
X1377626Y0258914
X1466958Y0244948
X1446830Y0236232
X1431430Y0251265
X1400207Y0238257
X1405436Y0238378
X1388778Y0250661
X1383734Y0237329
X1383734Y0243329
X1377742Y0250372
X1377742Y0244372
X1378452Y0236055
X1466940Y0230272
X1430000Y0220018
X1438720Y0220018
X1441490Y0224062
X1428640Y0230022
X1416810Y0225422
X1424520Y0225002
X1424690Y0220018
X1416020Y0220018
X1413350Y0220018
X1412270Y0230952
X1404630Y0220018
X1470101Y0207751
X1465179Y0213102
X1453823Y0205982
X1456423Y0209362
X1412851Y0197668
X1404071Y0197668
X1395321Y0197668
X1386780Y0197668
X1377597Y0197604
X1429382Y0184263
X1420222Y0184263
X1411101Y0184263
X1402258Y0184263
X1375300Y0208422
X1381235Y0236020
X1386630Y0242051
X1380638Y0249094
X1388754Y0257203
X1380522Y0263636
X1386273Y0272070
X1386630Y0238651
X1380638Y0245694
X1388754Y0253803
X1380522Y0260236
X1386273Y0268670
X1426020Y0261501
X1447340Y0157402
X1450720Y0173862
X1448820Y0148092
X1449740Y0166912
X1450720Y0161862
X1450720Y0153362
X1450720Y0177862
X1450720Y0181862
X1450270Y0143022
X1398182Y0171470
X1394182Y0171470
X1450720Y0169862
X1406970Y0138742
X1410370Y0138742
X1403778Y0171684
X1407178Y0171684
X1386404Y0149008
X1386684Y0145017
X1412284Y0171696
X1415684Y0171696
X1373591Y0176430
X1376991Y0176430
X1407029Y0156132
X1407029Y0152732
X1470220Y0169862
X1458720Y0145362
X1404741Y0177159
X1401341Y0177159
X1462000Y0153362
X1458720Y0173862
X1458720Y0177862
X1458720Y0181862
X1418268Y0171696
X1401240Y0171672
X1409716Y0171696
X1398770Y0177159
X1407613Y0177159
X1379969Y0176330
X1458720Y0157862
X1458720Y0161862
X1458720Y0165862
X1458720Y0169862
X1409558Y0156904
X1470220Y0145362
X1458720Y0149362
X1458720Y0153362
X1404402Y0138742
X1409558Y0151948
X1412954Y0138742
X1389443Y0147859
X1389609Y0145291
X1378550Y0110692
X1383480Y0088932
X1393250Y0093802
X1378839Y0087626
X1485383Y-0036695
X1491676Y-0031612
X1488378Y-0031598
X1488378Y-0035472
X1488393Y-0037987
X1491676Y-0035486
X1491661Y-0038001
X1485383Y-0026666
X1491676Y-0021583
X1488378Y-0021569
X1488378Y-0025443
X1488393Y-0027958
X1491676Y-0025457
X1491661Y-0027972
X1485383Y-0016637
X1488393Y-0017929
X1491661Y-0017943
X1480154Y-0033989
X1480154Y-0029033
X1480154Y-0023989
X1480154Y-0019033
X1482650Y-0033211
X1482650Y-0029811
X1440800Y0066862
X1432220Y0061862
X1444275Y0057262
X1464200Y0067802
X1438680Y0064412
X1441125Y0057362
X1438609Y0049388
X1458609Y0049388
X1446000Y0067802
X1482650Y-0023211
X1482650Y-0019811
X1434600Y0059262
X1474142Y0061767
X1491676Y-0011554
X1488378Y-0011540
X1488378Y-0015414
X1491676Y-0015428
X1485383Y-0006608
X1491676Y-0001525
X1488378Y-0001511
X1488378Y-0005385
X1488393Y-0007900
X1491676Y-0005399
X1491661Y-0007914
X1488378Y0004644
X1488393Y0002129
X1491676Y0004630
X1491661Y0002115
X1485383Y0003421
X1491676Y0019033
X1488378Y0019047
X1491676Y0008504
X1488378Y0008518
X1485383Y0013450
X1491661Y0012144
X1491676Y0014659
X1491661Y0022673
X1491646Y0025188
X1488378Y0025202
X1488393Y0022687
X1488393Y0012158
X1488378Y0014673
X1485383Y0023979
X1480154Y-0013989
X1480154Y-0009033
X1480154Y-0003989
X1480154Y0000967
X1482650Y-0013211
X1482650Y-0009811
X1535596Y0069297
X1549996Y0075297
X1557596Y0069297
X1538996Y0069297
X1546596Y0075297
X1560996Y0069297
X1568596Y0075297
X1552708Y0026431
X1559813Y0019495
X1566881Y0026431
X1549308Y0026431
X1556413Y0019495
X1563481Y0026431
X1570586Y0019495
X1544010Y0027552
X1536310Y0047492
X1567818Y0072801
X1567818Y0077793
X1565818Y0075297
X1545818Y0072801
X1545818Y0077793
X1550774Y0072801
X1550774Y0077793
X1552774Y0075297
X1543818Y0075297
X1561774Y0071793
X1561774Y0066801
X1563774Y0069297
X1556818Y0071793
X1556818Y0066801
X1554818Y0069297
X1532818Y0069297
X1541774Y0069297
X1539774Y0071793
X1539774Y0066801
X1534818Y0071793
X1534818Y0066801
X1561602Y0048720
X1561602Y0040020
X1568688Y0048720
X1568688Y0040020
X1547429Y0048720
X1547429Y0040020
X1554515Y0048720
X1554515Y0040020
X1568688Y0037106
X1568688Y0028406
X1561602Y0037106
X1561602Y0028406
X1569659Y0025931
X1560703Y0025931
X1562703Y0023935
X1567659Y0023935
X1554515Y0037106
X1554515Y0028406
X1547429Y0037106
X1547429Y0028406
X1555486Y0025931
X1546530Y0025931
X1548530Y0023935
X1553486Y0023935
X1567808Y0019495
X1562591Y0019495
X1569808Y0021991
X1569808Y0016999
X1560591Y0021991
X1560591Y0016999
X1553635Y0019495
X1555635Y0021991
X1555635Y0016999
X1478609Y0049388
X1498609Y0049388
X1518608Y0049377
X1529002Y0032290
X1547768Y0003010
X1567768Y0003010
X1482650Y-0003211
X1482650Y0000189
X1535575Y0118862
X1529500Y0122122
X1542401Y0141561
X1518575Y0138662
X1529500Y0125862
X1530660Y0100162
X1534060Y0100162
X1545763Y0159305
X1535450Y0155262
X1553189Y0127781
X1556049Y0147711
X1529233Y0153162
X1536925Y0129937
X1513900Y0117762
X1535520Y0151562
X1540090Y0122782
X1510500Y0125992
X1522920Y0116180
X1552960Y0124359
X1545447Y0156035
X1526083Y0146225
X1526675Y0140117
X1554239Y0138263
X1529500Y0129602
X1535320Y0113062
X1522920Y0113030
X1529818Y0103093
X1534774Y0103093
X1533520Y0110662
X1473090Y0204502
X1485320Y0260362
X1519833Y0277297
X1498984Y0282797
X1493289Y0280027
X1508049Y0280056
X1514593Y0235116
X1557320Y0203297
X1570675Y0267857
X1559722Y0243110
X1478745Y0281508
X1522258Y0265161
X1522786Y0262558
X1519758Y0265161
X1514593Y0249698
X1490060Y0255378
X1487958Y0236062
X1534194Y0217519
X1527732Y0219488
X1499922Y0211240
X1550353Y0217352
X1503020Y0215802
X1535561Y0225393
X1501840Y0225502
X1529670Y0225522
X1526152Y0225114
X1510017Y0225516
X1508410Y0230842
X1551160Y0189342
X1531824Y0207677
X1526998Y0209645
X1518110Y0215551
X1533148Y0211614
X1522009Y0210825
X1524539Y0215551
X1508959Y0215802
X1504484Y0234562
X1533385Y0193108
X1496720Y0225292
X1506600Y0239092
X1557760Y0214792
X1539150Y0267132
X1531110Y0264862
X1504890Y0249862
X1472335Y0209362
X1521115Y0193262
X1509040Y0243362
X1557900Y0220362
X1510810Y0249742
X1528720Y0199862
X1534720Y0199803
X1504650Y0254392
X1559400Y0229832
X1473820Y0265962
X1474660Y0252878
X1516683Y0278437
X1487058Y0281456
X1513759Y0263676
X1559860Y0240002
X1513110Y0247412
X1507860Y0249792
X1509571Y0239053
X1477700Y0236522
X1532590Y0225432
X1505378Y0225502
X1476858Y0225448
X1529610Y0211614
X1521201Y0215551
X1505821Y0215802
X1557560Y0196912
X1554723Y0200375
X1554723Y0224529
X1554723Y0248945
X1537262Y0197834
X1531750Y0199762
X1524770Y0195792
X1512420Y0239116
X1493120Y0240412
X1514520Y0231116
X1486040Y0368392
X1494784Y0374188
X1517669Y0291516
X1495150Y0369842
X1522258Y0288956
X1509539Y0308467
X1508558Y0291175
X1505922Y0304583
X1481345Y0306308
X1478426Y0306277
X1479745Y0312208
X1481445Y0289708
X1478526Y0289677
X1476826Y0312177
X1475352Y0306308
X1475452Y0289708
X1543858Y0310056
X1546458Y0307856
X1543958Y0307556
X1545768Y0302766
X1545668Y0305266
X1540958Y0307756
X1472758Y0370817
X1498184Y0369798
X1489443Y0372288
X1498184Y0361723
X1481766Y0372288
X1481484Y0361688
X1503450Y0382693
X1497880Y0373062
X1479207Y0374338
X1486884Y0374338
X1496200Y0359522
X1481360Y0358792
X1487658Y0289656
X1484958Y0289656
X1487558Y0305956
X1484858Y0305956
X1487458Y0312356
X1484758Y0312356
X1504602Y0312867
X1511624Y0291175
X1526216Y0306909
X1514369Y0308467
X1520094Y0306543
X1519336Y0303426
X1522883Y0305187
X1534899Y0310447
X1536216Y0306909
X1533716Y0306909
X1528716Y0306909
X1512244Y0311522
X1495527Y0406215
X1489310Y0426822
X1482650Y0411190
X1493384Y0411313
X1503450Y0385843
X1484805Y0427577
X1475250Y0401812
X1490384Y0407292
X1486880Y0416863
X1481766Y0406238
X1481384Y0419392
X1493384Y0419263
X1473310Y0418502
X1488500Y0410152
X1478203Y0406207
X1475790Y0404842
X1567114Y0572792
X1563714Y0572792
X1539720Y0581862
X1552720Y0581862
X1548720Y0581862
X1543720Y0581862
X1547312Y0579080
X1540937Y0576522
X1559354Y0655716
X1559354Y0659116
X1475714Y0673992
X1475714Y0659492
X1472076Y0671892
X1472076Y0657392
X1539720Y0589862
X1552720Y0589862
X1550487Y0681565
X1540377Y0634165
X1553312Y0636815
X1554753Y0628860
X1541211Y0646178
X1559557Y0593290
X1564690Y0663302
X1560717Y0648522
X1561494Y0584292
X1536527Y0589012
X1550417Y0677045
X1478539Y0675462
X1478139Y0660892
X1554727Y0631527
X1473228Y0631634
X1540989Y0616587
X1559387Y0589340
X1562871Y0735716
X1562871Y0732316
X1475714Y0717492
X1475714Y0702992
X1475714Y0688492
X1472514Y0730492
X1472076Y0715392
X1472076Y0700892
X1472076Y0686392
X1550390Y0709885
X1550917Y0704332
X1550320Y0696562
X1504747Y0747293
X1509638Y0738627
X1564768Y0708159
X1567547Y0755485
X1570374Y0760093
X1568490Y0758162
X1571577Y0747145
X1509350Y0741315
X1548479Y0706088
X1524505Y0748912
X1570720Y0729362
X1497770Y0732502
X1474939Y0731892
X1474100Y0735662
X1478139Y0718892
X1550057Y0693485
X1478139Y0704392
X1478139Y0689892
X1515940Y0799215
X1515940Y0795815
X1503514Y0797961
X1503514Y0801361
X1506689Y1283377
X1497161Y1280974
X1497199Y1278277
X1494631Y1277024
X1494641Y1280054
X1494631Y1274144
X1494629Y1271477
X1497259Y1273097
X1497199Y1275667
X1478859Y1276994
X1492091Y1277024
X1481359Y1277024
X1478821Y1280054
X1492101Y1280054
X1481361Y1280054
X1478859Y1274114
X1478859Y1271417
X1492091Y1274144
X1481359Y1274144
X1492039Y1271447
X1481359Y1271447
X1478891Y1267134
X1478879Y1264427
X1478939Y1261827
X1481431Y1267254
X1481419Y1264547
X1481479Y1261947
X1478999Y1259257
X1481539Y1259377
X1476291Y1278104
X1476291Y1272344
X1476279Y1269637
X1476309Y1261807
X1476339Y1267037
X1476339Y1264467
X1476291Y1275224
X1476369Y1259237
X1528272Y1358151
X1533178Y1357915
X1528912Y1363945
X1533178Y1363715
X1531078Y1362315
X1528912Y1361045
X1530978Y1359315
X1533178Y1360815
X1523612Y1358151
X1525942Y1357401
X1521282Y1357401
X1498959Y1342930
X1501033Y1341462
X1496144Y1335353
X1496784Y1338247
X1501149Y1336287
X1498950Y1339517
X1498924Y1334882
X1496784Y1341147
X1491484Y1335353
X1493814Y1334603
X1489154Y1334603
X1510878Y1367871
X1478750Y1345073
X1507704Y1361597
X1475576Y1338799
X1504588Y1355816
X1517616Y1364585
X1472460Y1333043
X1485488Y1341787
X1519088Y1367043
X1486960Y1344245
X1472460Y1330493
X1504588Y1353316
X1510878Y1364815
X1478750Y1342017
X1482750Y1342755
X1514878Y1365553
X1511251Y1295584
X1511251Y1298464
X1511251Y1292704
X1516351Y1298464
X1516351Y1295584
X1513791Y1295584
X1513791Y1298464
X1516351Y1292704
X1513791Y1292704
X1511199Y1290007
X1511289Y1287397
X1513789Y1290037
X1508711Y1292674
X1508711Y1298434
X1508711Y1295554
X1506591Y1294134
X1506591Y1297014
X1506551Y1291254
X1508699Y1289967
X1508759Y1287367
X1506539Y1288557
X1508819Y1284797
X1506569Y1285947
X1473956Y1341068
X1505570Y1364212
X1474180Y1300407
X1472592Y1306345
X1472592Y1311545
X1472592Y1314145
X1472592Y1316745
X1472592Y1308945
X1472361Y1322440
X1475599Y1349468
X1491840Y1300447
X1478610Y1319634
X1478610Y1322741
X1489010Y1319634
X1492210Y1319634
X1481210Y1319634
X1481210Y1322741
X1483810Y1319634
X1486410Y1319634
X1483810Y1322741
X1486410Y1322741
X1480604Y1329497
X1480604Y1335097
X1483084Y1329497
X1485564Y1329497
X1483084Y1335097
X1485564Y1335097
X1486610Y1325848
X1484010Y1325848
X1487386Y1349258
X1485523Y1347521
X1481255Y1382042
X1494840Y1300447
X1499048Y1319946
X1495154Y1319650
X1495154Y1322757
X1504518Y1335982
X1503786Y1326076
X1495054Y1325853
X1504720Y1329143
X1504720Y1344743
X1504720Y1342143
X1505116Y1369724
X1511066Y1312808
X1515066Y1312808
X1518066Y1312808
X1526066Y1312808
X1522066Y1312808
X1517692Y1352295
X1512732Y1352295
X1515212Y1352295
X1516138Y1348646
X1518738Y1348646
X1524338Y1342432
X1521138Y1342432
X1513338Y1342432
X1513338Y1345539
X1515938Y1342432
X1515938Y1345539
X1518538Y1342432
X1518538Y1345539
X1510738Y1342432
X1510738Y1345539
X1518451Y1369919
X1517692Y1357895
X1512732Y1357895
X1515212Y1357895
X1529952Y1337104
X1532552Y1337104
X1537652Y1334504
X1537652Y1325904
X1529952Y1339704
X1532552Y1339704
X1529952Y1334504
X1535052Y1334504
X1532552Y1334504
X1535052Y1325904
X1527182Y1348651
X1538757Y1356355
X1527282Y1342448
X1527282Y1345555
X1535892Y1343754
X1535892Y1346354
X1531302Y1342204
X1538510Y1346392
X1538757Y1365355
X1538757Y1360855
X1481918Y1425579
X1475967Y1448669
X1475967Y1445669
X1484442Y1448557
X1484442Y1445557
X1513657Y1429985
X1507617Y1424045
X1510027Y1425825
X1516137Y1432135
X1512177Y1427795
X1485387Y1420002
X1475959Y1385027
X1476000Y1393027
X1475936Y1442241
X1475935Y1439627
X1481159Y1384727
X1478559Y1385027
X1481155Y1387742
X1479658Y1405397
X1481107Y1393095
X1478600Y1393027
X1481155Y1390342
X1481155Y1398942
X1481155Y1396342
X1482280Y1412202
X1482174Y1406911
X1482201Y1409442
X1479671Y1407911
X1479671Y1412911
X1479671Y1410411
X1485380Y1412202
X1485274Y1406911
X1485301Y1409442
X1484336Y1442241
X1484395Y1439598
X1478320Y1522962
X1482830Y1525162
X1534655Y1578182
X1546715Y1578182
X1558775Y1578182
X1570835Y1578182
X1474355Y1578182
X1486415Y1578182
X1498475Y1578182
X1510535Y1578182
X1522595Y1578182
X1538055Y1578182
X1550115Y1578182
X1562175Y1578182
X1477755Y1578182
X1489815Y1578182
X1501875Y1578182
X1513935Y1578182
X1525995Y1578182
X1562953Y1580678
X1562953Y1575686
X1570057Y1575686
X1570057Y1580678
X1545937Y1575686
X1550893Y1575686
X1545937Y1580678
X1550893Y1580678
X1557997Y1580678
X1557997Y1575686
X1526773Y1575686
X1526773Y1580678
X1538833Y1580678
X1533877Y1580678
X1538833Y1575592
X1533877Y1575592
X1514713Y1580678
X1514713Y1575686
X1521817Y1575686
X1521817Y1580678
X1497697Y1575686
X1502653Y1575686
X1497697Y1580678
X1502653Y1580678
X1509757Y1580678
X1509757Y1575686
X1478533Y1575686
X1478533Y1580678
X1485637Y1580678
X1485637Y1575686
X1490593Y1575686
X1490593Y1580678
X1473577Y1575686
X1473577Y1580678
X1480800Y1663600
X1478061Y1633864
X1543355Y1602380
X1555415Y1602380
X1567475Y1602380
X1483055Y1602380
X1495115Y1602380
X1507175Y1602380
X1519235Y1602380
X1531295Y1602380
X1539955Y1602380
X1552015Y1602380
X1564075Y1602380
X1479655Y1602380
X1491715Y1602380
X1503775Y1602380
X1515835Y1602380
X1527895Y1602380
X1543355Y1614292
X1555415Y1614292
X1567475Y1614292
X1483055Y1614292
X1495115Y1614292
X1507175Y1614292
X1519235Y1614292
X1531295Y1614292
X1539955Y1614292
X1552015Y1614292
X1564075Y1614292
X1479655Y1614292
X1491715Y1614292
X1503775Y1614292
X1515835Y1614292
X1527895Y1614292
X1534655Y1590094
X1546715Y1590094
X1558775Y1590094
X1570835Y1590094
X1474355Y1590094
X1486415Y1590094
X1498475Y1590094
X1510535Y1590094
X1522595Y1590094
X1538055Y1590094
X1550115Y1590094
X1562175Y1590094
X1477755Y1590094
X1489815Y1590094
X1501875Y1590094
X1513935Y1590094
X1525995Y1590094
X1472565Y1623635
X1476570Y1661124
X1476570Y1657974
X1478724Y1637189
X1568253Y1616788
X1563297Y1616788
X1568253Y1611796
X1568253Y1604876
X1563297Y1611796
X1563297Y1604876
X1544133Y1616788
X1544133Y1611796
X1544133Y1604876
X1551237Y1611796
X1556193Y1611796
X1551237Y1604876
X1556193Y1604876
X1556193Y1616788
X1551237Y1616788
X1532073Y1611796
X1532073Y1604876
X1532073Y1616788
X1527117Y1611796
X1527117Y1604876
X1527117Y1616788
X1539177Y1616788
X1539177Y1604876
X1539177Y1611796
X1520013Y1616788
X1515057Y1616788
X1515057Y1611796
X1520013Y1611796
X1515057Y1604876
X1520013Y1604876
X1495893Y1616788
X1495893Y1611796
X1495893Y1604876
X1507953Y1611796
X1507953Y1604876
X1502997Y1611796
X1502997Y1604876
X1507953Y1616788
X1502997Y1616788
X1483833Y1604876
X1478877Y1604876
X1483833Y1611796
X1478877Y1611796
X1478877Y1616788
X1483833Y1616788
X1490937Y1616788
X1490937Y1611796
X1490937Y1604876
X1562953Y1592590
X1562953Y1587598
X1570057Y1587598
X1570057Y1592590
X1568253Y1599884
X1563297Y1599884
X1545937Y1587598
X1550893Y1587598
X1550893Y1592590
X1545937Y1592590
X1557997Y1592590
X1557997Y1587598
X1544133Y1599790
X1551237Y1599884
X1556193Y1599884
X1526773Y1587598
X1526773Y1592590
X1538833Y1592590
X1533877Y1592590
X1538833Y1587598
X1533877Y1587598
X1532073Y1599884
X1527117Y1599884
X1539177Y1599790
X1514713Y1592590
X1514713Y1587598
X1521817Y1587598
X1521817Y1592590
X1515057Y1599884
X1520013Y1599884
X1497697Y1587598
X1502653Y1587598
X1497697Y1592590
X1502653Y1592590
X1509757Y1592590
X1509757Y1587598
X1495893Y1599884
X1507953Y1599884
X1502997Y1599884
X1478533Y1587598
X1478533Y1592590
X1490593Y1592590
X1485637Y1592590
X1485637Y1587598
X1490593Y1587598
X1483833Y1599884
X1478877Y1599884
X1490937Y1599884
X1473577Y1587598
X1473577Y1592590
X1491866Y1737108
X1511866Y1737108
X1531866Y1737108
X1551866Y1737108
X1591866Y1737108
X1611866Y1737108
X1631866Y1737108
X1651866Y1737108
X1579535Y1602380
X1591595Y1602380
X1603655Y1602380
X1615715Y1602380
X1627775Y1602380
X1639835Y1602380
X1648495Y1602380
X1576135Y1602380
X1588195Y1602380
X1600255Y1602380
X1612315Y1602380
X1624375Y1602380
X1636435Y1602380
X1651895Y1602380
X1579535Y1614292
X1591595Y1614292
X1603655Y1614292
X1615715Y1614292
X1627775Y1614292
X1639835Y1614292
X1648495Y1614292
X1576135Y1614292
X1588195Y1614292
X1600255Y1614292
X1612315Y1614292
X1624375Y1614292
X1636435Y1614292
X1651895Y1614292
X1582895Y1590094
X1594955Y1590094
X1607015Y1590094
X1619075Y1590094
X1631135Y1590094
X1643195Y1590094
X1574235Y1590094
X1586295Y1590094
X1598355Y1590094
X1610415Y1590094
X1622475Y1590094
X1634535Y1590094
X1646595Y1590094
X1652673Y1611796
X1652673Y1604876
X1647717Y1611796
X1647717Y1604876
X1652673Y1616788
X1647717Y1616788
X1628553Y1611796
X1628553Y1604876
X1628553Y1616788
X1635657Y1616788
X1640613Y1616788
X1635657Y1611796
X1635657Y1604876
X1640613Y1611796
X1640613Y1604876
X1616493Y1616788
X1611537Y1616788
X1616493Y1611796
X1616493Y1604876
X1611537Y1611796
X1611537Y1604876
X1623597Y1611796
X1623597Y1604876
X1623597Y1616788
X1592373Y1616788
X1592373Y1611796
X1592373Y1604876
X1604433Y1611796
X1604433Y1604876
X1599477Y1611796
X1599477Y1604876
X1604433Y1616788
X1599477Y1616788
X1580313Y1611796
X1580313Y1604876
X1580313Y1616788
X1587417Y1616788
X1587417Y1611796
X1587417Y1604876
X1575357Y1611796
X1575357Y1604876
X1575357Y1616788
X1642417Y1587598
X1647373Y1587598
X1642417Y1592590
X1647373Y1592590
X1652673Y1599884
X1647717Y1599884
X1635313Y1592590
X1630357Y1592590
X1635313Y1587598
X1630357Y1587598
X1628553Y1599884
X1635657Y1599790
X1640613Y1599790
X1611193Y1592590
X1611193Y1587598
X1623253Y1587598
X1618297Y1587598
X1623253Y1592590
X1618297Y1592590
X1616493Y1599884
X1611537Y1599884
X1623597Y1599884
X1599133Y1587598
X1594177Y1587598
X1599133Y1592590
X1594177Y1592590
X1606237Y1592590
X1606237Y1587598
X1592373Y1599884
X1604433Y1599884
X1599477Y1599884
X1587073Y1592590
X1582117Y1592590
X1587073Y1587598
X1582117Y1587598
X1580313Y1599884
X1587417Y1599884
X1575013Y1587598
X1575013Y1592590
X1575357Y1599884
X1666198Y1585321
X1671660Y1569412
X1671673Y1550815
X1646958Y1501553
X1582895Y1578182
X1594955Y1578182
X1607015Y1578182
X1619075Y1578182
X1631135Y1578182
X1643195Y1578182
X1574235Y1578182
X1586295Y1578182
X1598355Y1578182
X1610415Y1578182
X1622475Y1578182
X1634535Y1578182
X1646595Y1578182
X1666198Y1581321
X1666198Y1561557
X1666123Y1557557
X1666123Y1545862
X1666123Y1520862
X1666123Y1533862
X1666123Y1501362
X1666123Y1493362
X1642417Y1575686
X1647373Y1575686
X1642417Y1580678
X1647373Y1580678
X1635313Y1580678
X1630357Y1580678
X1635313Y1575592
X1630357Y1575592
X1611193Y1580678
X1611193Y1575686
X1623253Y1575686
X1618297Y1575686
X1623253Y1580678
X1618297Y1580678
X1599133Y1575686
X1594177Y1575686
X1599133Y1580678
X1594177Y1580678
X1606237Y1580678
X1606237Y1575686
X1587073Y1580678
X1582117Y1580678
X1587073Y1575686
X1582117Y1575686
X1575013Y1575686
X1575013Y1580678
X1666198Y1565557
X1666123Y1553557
X1666123Y1541862
X1666123Y1537862
X1666123Y1524862
X1666110Y1504662
X1665940Y1512862
X1666123Y1497362
X1660860Y1461545
X1660860Y1459045
X1660860Y1464045
X1660860Y1466545
X1660950Y1456210
X1657860Y1461545
X1657860Y1459045
X1657950Y1456210
X1657860Y1464045
X1657860Y1466545
X1660920Y1453405
X1657920Y1453405
X1652295Y1456899
X1655295Y1456899
X1652295Y1453879
X1655295Y1453879
X1648677Y1439120
X1653243Y1438590
X1651143Y1437190
X1653243Y1432790
X1651043Y1434190
X1653243Y1435690
X1648677Y1436220
X1655762Y1429794
X1648037Y1433626
X1643377Y1433626
X1645707Y1432876
X1641047Y1432876
X1613047Y1415669
X1630643Y1443090
X1668786Y1443256
X1665612Y1437072
X1627469Y1437072
X1662496Y1431291
X1637042Y1440215
X1624353Y1431316
X1638785Y1442483
X1624353Y1428766
X1662496Y1428791
X1668786Y1440290
X1630643Y1440290
X1634643Y1442982
X1624853Y1440875
X1662996Y1440922
X1614927Y1429896
X1617215Y1440822
X1615062Y1421241
X1614927Y1426076
X1642645Y1473645
X1643065Y1457645
X1643065Y1460145
X1643065Y1468645
X1643065Y1465645
X1643065Y1462645
X1639645Y1473645
X1635315Y1457745
X1632315Y1457745
X1629815Y1457745
X1632315Y1460245
X1629815Y1460245
X1635315Y1460245
X1635315Y1468745
X1629815Y1462745
X1632315Y1462745
X1629815Y1465745
X1632315Y1465745
X1629815Y1468745
X1632315Y1468745
X1635315Y1462745
X1635315Y1465745
X1606980Y1449922
X1612630Y1418842
X1623448Y1412228
X1623448Y1414828
X1623448Y1417428
X1623448Y1420028
X1614116Y1411169
X1615597Y1433669
X1634683Y1394411
X1629262Y1394418
X1639683Y1394411
X1637183Y1394411
X1625948Y1420028
X1625948Y1414828
X1638303Y1421014
X1638303Y1417907
X1635703Y1421014
X1630503Y1421014
X1633103Y1421014
X1635703Y1417907
X1630503Y1417907
X1633103Y1417907
X1625948Y1412228
X1625948Y1417428
X1637416Y1433353
X1637416Y1427753
X1634986Y1433353
X1634986Y1427753
X1632516Y1433353
X1632516Y1427753
X1638503Y1424121
X1635903Y1424121
X1637478Y1445150
X1627591Y1447796
X1647592Y1394418
X1656188Y1394736
X1640903Y1417907
X1650557Y1417618
X1653168Y1417618
X1650679Y1415018
X1653279Y1415018
X1650679Y1412418
X1653279Y1412418
X1647047Y1421030
X1647047Y1417923
X1644103Y1417907
X1655779Y1415018
X1655779Y1412418
X1655779Y1417618
X1647016Y1424153
X1648947Y1476695
X1659260Y1394693
X1667405Y1394418
X1671246Y1421014
X1671246Y1417907
X1668646Y1421014
X1668646Y1417907
X1663590Y1412418
X1663590Y1417618
X1663590Y1415018
X1660990Y1412418
X1660990Y1417618
X1660990Y1415018
X1660990Y1420218
X1663590Y1420218
X1658390Y1417618
X1658390Y1412418
X1658390Y1415018
X1658390Y1420218
X1657438Y1438156
X1670659Y1433353
X1670659Y1427753
X1667577Y1447545
X1660428Y1447566
X1666753Y1374992
X1664253Y1374992
X1664253Y1377492
X1666753Y1377492
X1664253Y1382492
X1666753Y1382492
X1664253Y1379992
X1666753Y1379992
X1669303Y1374992
X1669303Y1377492
X1669303Y1382492
X1669303Y1379992
X1666753Y1369992
X1664253Y1369992
X1664253Y1367492
X1666753Y1367492
X1669303Y1369992
X1669303Y1367492
X1666753Y1372492
X1664253Y1372492
X1669303Y1372492
X1645721Y1382492
X1645721Y1379992
X1645721Y1374992
X1645721Y1377492
X1650771Y1374992
X1650771Y1377492
X1648271Y1374992
X1648271Y1377492
X1650771Y1382492
X1650771Y1379992
X1648271Y1382492
X1648271Y1379992
X1645721Y1369992
X1648271Y1369992
X1650771Y1369992
X1645721Y1372492
X1650771Y1372492
X1648271Y1372492
X1645721Y1367492
X1648271Y1367492
X1650771Y1367492
X1626153Y1377492
X1626153Y1374992
X1626153Y1382492
X1626153Y1379992
X1631203Y1382492
X1631203Y1379992
X1631203Y1374992
X1631203Y1377492
X1628653Y1374992
X1628653Y1377492
X1628653Y1382492
X1628653Y1379992
X1626153Y1369992
X1628653Y1369992
X1631203Y1369992
X1626153Y1372492
X1631203Y1372492
X1628653Y1372492
X1626153Y1367492
X1628653Y1367492
X1631203Y1367492
X1640812Y1270020
X1638277Y1269065
X1649363Y0717485
X1651481Y0692011
X1651711Y0696277
X1648581Y0692011
X1647081Y0694211
X1645681Y0692011
X1650081Y0694111
X1645917Y0696917
X1645167Y0699247
X1645917Y0701577
X1645167Y0703907
X1648811Y0696277
X1651509Y0756492
X1618788Y0756199
X1614788Y0756199
X1610788Y0756199
X1602788Y0756199
X1606788Y0756199
X1595600Y0736652
X1592760Y0736652
X1598440Y0736692
X1590915Y0755793
X1571920Y0762662
X1655637Y0714311
X1643582Y0720601
X1652351Y0707573
X1643582Y0686601
X1653319Y0710311
X1654809Y0706101
X1652581Y0714311
X1599010Y0724002
X1598850Y0721452
X1596250Y0721452
X1598888Y0713777
X1593888Y0713777
X1596388Y0713777
X1593828Y0716327
X1596328Y0716327
X1593858Y0718837
X1596358Y0718837
X1598828Y0716327
X1598858Y0718837
X1598888Y0691502
X1598858Y0699277
X1596288Y0691502
X1598888Y0694177
X1596358Y0699277
X1593858Y0699277
X1596328Y0696727
X1596388Y0694177
X1593888Y0694177
X1593828Y0696727
X1598828Y0696727
X1598888Y0688902
X1596288Y0688902
X1598908Y0684867
X1596408Y0684867
X1593908Y0684867
X1588888Y0713777
X1588828Y0716327
X1588858Y0718837
X1591388Y0713777
X1591328Y0716327
X1591358Y0718837
X1588858Y0699277
X1591358Y0699277
X1588828Y0696727
X1588888Y0694177
X1591388Y0694177
X1591328Y0696727
X1591408Y0684867
X1588908Y0684867
X1651635Y0685836
X1651635Y0719836
X1641082Y0720601
X1641082Y0686601
X1666686Y0757162
X1634928Y0756199
X1630928Y0756199
X1638928Y0756199
X1659914Y0717681
X1658085Y0707511
X1659458Y0705149
X1659914Y0683681
X1645661Y0712457
X1645661Y0709977
X1645661Y0707497
X1656550Y0687086
X1630198Y0714451
X1633305Y0714451
X1630198Y0711851
X1630198Y0709251
X1633305Y0709251
X1633305Y0711851
X1624709Y0720469
X1629909Y0720469
X1627309Y0720469
X1632509Y0720469
X1636412Y0709051
X1640061Y0709977
X1640061Y0712457
X1640061Y0707497
X1627970Y0694362
X1627970Y0691762
X1630570Y0691762
X1630570Y0694362
X1625370Y0694362
X1625370Y0691762
X1630198Y0700851
X1633305Y0706651
X1630198Y0706651
X1630198Y0704051
X1633321Y0697907
X1630214Y0697907
X1636412Y0706451
X1636417Y0698007
X1627309Y0686469
X1624709Y0686469
X1632509Y0686469
X1629909Y0686469
X1610100Y0725152
X1615580Y0718092
X1612980Y0718092
X1622109Y0720469
X1619509Y0720469
X1612980Y0691762
X1615580Y0691762
X1612980Y0694362
X1615580Y0694362
X1620170Y0694362
X1620170Y0691762
X1622770Y0694362
X1622770Y0691762
X1612980Y0684092
X1615580Y0684092
X1619509Y0686469
X1622109Y0686469
X1660660Y0602273
X1649363Y0683485
X1649363Y0649485
X1670700Y0594562
X1661238Y0592113
X1658738Y0592113
X1651711Y0662277
X1651481Y0658011
X1650081Y0660111
X1645167Y0669907
X1645167Y0665247
X1645917Y0667577
X1645917Y0662917
X1647081Y0660211
X1648811Y0662277
X1648581Y0658011
X1645681Y0658011
X1651711Y0628277
X1650081Y0626111
X1645167Y0635907
X1645167Y0631247
X1645917Y0633577
X1645917Y0628917
X1647081Y0626211
X1648811Y0628277
X1651481Y0624011
X1648581Y0624011
X1645681Y0624011
X1649844Y0598555
X1653774Y0598576
X1653794Y0594956
X1649833Y0594946
X1656238Y0592113
X1663471Y0609837
X1655113Y0680835
X1652351Y0673573
X1653319Y0676311
X1654809Y0672101
X1652581Y0680311
X1598938Y0679807
X1598878Y0682357
X1596378Y0682357
X1593878Y0682357
X1596438Y0679807
X1593938Y0679807
X1598938Y0662727
X1593938Y0662727
X1596438Y0662727
X1598968Y0665237
X1593968Y0665237
X1596468Y0665237
X1598948Y0660177
X1593948Y0660177
X1596448Y0660177
X1596448Y0657677
X1593948Y0657677
X1598948Y0657677
X1591378Y0682357
X1591438Y0679807
X1588878Y0682357
X1588938Y0679807
X1591438Y0662727
X1588938Y0662727
X1591468Y0665237
X1588968Y0665237
X1591448Y0660177
X1588948Y0660177
X1588948Y0657677
X1591448Y0657677
X1653220Y0620662
X1669222Y0604490
X1641082Y0652601
X1669397Y0614064
X1645300Y0612202
X1656955Y0611090
X1664197Y0602191
X1660754Y0609837
X1604430Y0615201
X1601830Y0615201
X1593454Y0613715
X1593424Y0611205
X1593484Y0608655
X1593454Y0595103
X1593484Y0597613
X1607200Y0583962
X1604430Y0590685
X1601830Y0590685
X1593514Y0592553
X1590824Y0611205
X1590854Y0613715
X1583054Y0613715
X1583024Y0611205
X1585624Y0611205
X1585654Y0613715
X1588224Y0611205
X1588254Y0613715
X1590884Y0608655
X1590884Y0597613
X1590854Y0595103
X1583084Y0608655
X1585684Y0608655
X1588284Y0608655
X1583054Y0595103
X1583084Y0597613
X1585684Y0597613
X1585654Y0595103
X1588284Y0597613
X1588254Y0595103
X1590914Y0592553
X1583114Y0592553
X1585714Y0592553
X1588314Y0592553
X1655637Y0646311
X1643582Y0652601
X1652351Y0639573
X1653319Y0642311
X1654809Y0638101
X1652581Y0646311
X1593868Y0653377
X1596368Y0653377
X1598868Y0653377
X1593898Y0645817
X1596398Y0645817
X1598898Y0645817
X1593838Y0648367
X1596338Y0648367
X1593868Y0650877
X1596368Y0650877
X1598838Y0648367
X1598868Y0650877
X1596398Y0631237
X1593898Y0631237
X1598898Y0631237
X1596368Y0628727
X1596428Y0626177
X1593928Y0626177
X1593868Y0628727
X1598928Y0626177
X1598868Y0628727
X1588868Y0653377
X1591368Y0653377
X1588898Y0645817
X1588838Y0648367
X1588868Y0650877
X1591398Y0645817
X1591338Y0648367
X1591368Y0650877
X1588898Y0631237
X1591398Y0631237
X1588868Y0628727
X1588928Y0626177
X1591428Y0626177
X1591368Y0628727
X1651635Y0651836
X1668920Y0617637
X1664410Y0617953
X1658085Y0673511
X1659458Y0671149
X1659914Y0649681
X1658085Y0639511
X1659458Y0637149
X1663720Y0620434
X1657220Y0620662
X1662120Y0604782
X1664997Y0604762
X1645661Y0675977
X1645661Y0678457
X1645661Y0673497
X1645661Y0641977
X1645661Y0644457
X1656550Y0653086
X1645661Y0639497
X1642873Y0610206
X1642340Y0618546
X1649220Y0620662
X1642873Y0595006
X1645625Y0594995
X1645625Y0597795
X1642873Y0598206
X1642873Y0601206
X1645625Y0603295
X1645625Y0600495
X1642873Y0607206
X1642873Y0604206
X1653930Y0602099
X1649117Y0602139
X1653736Y0607033
X1649139Y0604576
X1653929Y0604546
X1649149Y0607022
X1630198Y0680451
X1633305Y0677851
X1633305Y0675251
X1633305Y0680451
X1630198Y0675251
X1630198Y0677851
X1636412Y0675051
X1640061Y0675977
X1640061Y0678457
X1633321Y0663907
X1630214Y0663907
X1630198Y0666851
X1633305Y0672651
X1630198Y0670051
X1630198Y0672651
X1625370Y0660362
X1627970Y0660362
X1630570Y0660362
X1640061Y0673497
X1636417Y0664007
X1636412Y0672451
X1630198Y0646451
X1633305Y0643851
X1633305Y0646451
X1630198Y0643851
X1627309Y0652469
X1624709Y0652469
X1632509Y0652469
X1629909Y0652469
X1625370Y0657762
X1627970Y0657762
X1630570Y0657762
X1640061Y0641977
X1640061Y0644457
X1633321Y0629907
X1630214Y0629907
X1630198Y0632851
X1633305Y0641251
X1633305Y0638651
X1630198Y0641251
X1630198Y0636051
X1630198Y0638651
X1625370Y0626362
X1627970Y0626362
X1630570Y0626362
X1636412Y0641051
X1640061Y0639497
X1636417Y0630007
X1636412Y0638451
X1625370Y0623762
X1627970Y0623762
X1630570Y0623762
X1639606Y0616576
X1637006Y0616576
X1634406Y0616576
X1631806Y0616576
X1629206Y0616576
X1626606Y0616576
X1635067Y0587844
X1635067Y0590444
X1632467Y0587844
X1632467Y0590444
X1629867Y0587844
X1629867Y0590444
X1637667Y0590444
X1637667Y0587844
X1612980Y0660362
X1622770Y0660362
X1620170Y0660362
X1615580Y0660362
X1612980Y0650092
X1612980Y0657762
X1619509Y0652469
X1622109Y0652469
X1622770Y0657762
X1620170Y0657762
X1615580Y0657762
X1615580Y0650092
X1612980Y0626362
X1622770Y0626362
X1620170Y0626362
X1612980Y0623762
X1619980Y0615201
X1622770Y0623762
X1620170Y0623762
X1615800Y0584062
X1619980Y0590685
X1663502Y0555115
X1666902Y0555115
X1653230Y0549322
X1665790Y0523417
X1660243Y0532071
X1657755Y0517910
X1661872Y0534703
X1645530Y0549160
X1659740Y0542222
X1662262Y0537334
X1668917Y0549992
X1651112Y0545572
X1602980Y0560002
X1651851Y0532057
X1651890Y0520540
X1668040Y0569642
X1670004Y0531065
X1670004Y0543065
X1670004Y0537065
X1664040Y0569642
X1660866Y0546749
X1651931Y0536071
X1651931Y0540071
X1667376Y0515531
X1663376Y0515531
X1652138Y0524071
X1652113Y0527325
X1649291Y0556057
X1669770Y0580512
X1661510Y0583442
X1665700Y0583462
X1642720Y0560862
X1664970Y0472112
X1662447Y0480619
X1647310Y0411422
X1650020Y0411452
X1647310Y0408922
X1650020Y0408952
X1639800Y0432982
X1636800Y0432982
X1639800Y0435982
X1636800Y0435982
X1639800Y0438982
X1636800Y0438982
X1639800Y0426982
X1636800Y0426982
X1639800Y0429982
X1636800Y0429982
X1654110Y0434177
X1642135Y0414202
X1652610Y0394727
X1652810Y0407402
X1647110Y0434177
X1663610Y0394727
X1659610Y0394727
X1661110Y0434177
X1572396Y0309450
X1573246Y0306650
X1635835Y0343002
X1576589Y0300927
X1575169Y0303929
X1603530Y0202402
X1603747Y0192951
X1603580Y0206902
X1666690Y0193290
X1632342Y0216015
X1633111Y0206693
X1604270Y0231490
X1603706Y0211526
X1667739Y0187187
X1660861Y0227548
X1664866Y0225162
X1668426Y0222432
X1574760Y0251032
X1573560Y0245078
X1604240Y0238242
X1603726Y0198061
X1603778Y0189943
X1604290Y0242472
X1598030Y0251002
X1670400Y0229462
X1660176Y0231100
X1666074Y0229710
X1604040Y0219692
X1632899Y0213012
X1596444Y0215526
X1668030Y0200580
X1635032Y0196188
X1603920Y0222922
X1604240Y0227892
X1604200Y0234642
X1668100Y0180852
X1623881Y0129627
X1636393Y0181778
X1623881Y0117627
X1601596Y0069297
X1615996Y0075297
X1623596Y0069297
X1639200Y0075297
X1646800Y0069297
X1661200Y0075297
X1668800Y0069297
X1571996Y0075297
X1579596Y0069297
X1593996Y0075297
X1604996Y0069297
X1612596Y0075297
X1626996Y0069297
X1635800Y0075297
X1650200Y0069297
X1657800Y0075297
X1582996Y0069297
X1590596Y0075297
X1595228Y0026431
X1602333Y0019495
X1631094Y0026431
X1638199Y0019495
X1645267Y0026431
X1652372Y0019495
X1573986Y0019495
X1581054Y0026431
X1588159Y0019495
X1591828Y0026431
X1598933Y0019495
X1627694Y0026431
X1634799Y0019495
X1641867Y0026431
X1648972Y0019495
X1671828Y0026431
X1577654Y0026431
X1584759Y0019495
X1621920Y0025962
X1622220Y0049862
X1661978Y0072801
X1661978Y0077793
X1663978Y0075297
X1657022Y0072801
X1657022Y0077793
X1641978Y0075297
X1655022Y0075297
X1635022Y0072801
X1639978Y0072801
X1639978Y0077793
X1635022Y0077793
X1633022Y0075297
X1611818Y0072801
X1611818Y0077793
X1616774Y0072801
X1616774Y0077793
X1618774Y0075297
X1609818Y0075297
X1594774Y0072801
X1594774Y0077793
X1596774Y0075297
X1589818Y0072801
X1589818Y0077793
X1587818Y0075297
X1572774Y0072801
X1572774Y0077793
X1574774Y0075297
X1668022Y0071793
X1668022Y0066801
X1666022Y0069297
X1650978Y0071793
X1650978Y0066801
X1646022Y0071793
X1646022Y0066801
X1652978Y0069297
X1644022Y0069297
X1627774Y0071793
X1627774Y0066801
X1629774Y0069297
X1622818Y0071793
X1622818Y0066801
X1620818Y0069297
X1605774Y0071793
X1605774Y0066801
X1600818Y0071793
X1600818Y0066801
X1607774Y0069297
X1598818Y0069297
X1583774Y0071793
X1583774Y0066801
X1578818Y0071793
X1578818Y0066801
X1585774Y0069297
X1576818Y0069297
X1669948Y0048720
X1669948Y0040020
X1654161Y0048720
X1654161Y0040020
X1647074Y0048720
X1647074Y0040020
X1639988Y0048720
X1639988Y0040020
X1632901Y0048720
X1632901Y0040020
X1625814Y0048720
X1625814Y0040020
X1597035Y0048720
X1597035Y0040020
X1604122Y0048720
X1604122Y0040020
X1575775Y0048720
X1575775Y0040020
X1582862Y0048720
X1582862Y0040020
X1589948Y0048720
X1589948Y0040020
X1669948Y0037106
X1669948Y0028406
X1669050Y0025931
X1671050Y0023935
X1647074Y0037106
X1647074Y0028406
X1654161Y0037106
X1654161Y0028406
X1648045Y0025931
X1646045Y0023935
X1641089Y0023935
X1639988Y0037106
X1639988Y0028406
X1632901Y0037106
X1632901Y0028406
X1625814Y0037106
X1625814Y0028406
X1639089Y0025931
X1633872Y0025931
X1624916Y0025931
X1626916Y0023935
X1631872Y0023935
X1604122Y0037106
X1604122Y0028406
X1597035Y0037106
X1597035Y0028406
X1598006Y0025931
X1596006Y0023935
X1589948Y0037106
X1589948Y0028406
X1582862Y0037106
X1582862Y0028406
X1575775Y0037106
X1575775Y0028406
X1589050Y0025931
X1583832Y0025931
X1591050Y0023935
X1581832Y0023935
X1576876Y0023935
X1574876Y0025931
X1655150Y0019495
X1646194Y0019495
X1640977Y0019495
X1653150Y0021991
X1653150Y0016999
X1648194Y0021991
X1648194Y0016999
X1632021Y0019495
X1638977Y0021991
X1638977Y0016999
X1634021Y0021991
X1634021Y0016999
X1605111Y0019495
X1596155Y0019495
X1603111Y0021991
X1603111Y0016999
X1598155Y0021991
X1598155Y0016999
X1590937Y0019495
X1581981Y0019495
X1576764Y0019495
X1588937Y0021991
X1588937Y0016999
X1583981Y0021991
X1583981Y0016999
X1574764Y0021991
X1574764Y0016999
X1587768Y0003010
X1607768Y0003010
X1757320Y0015872
X1770368Y0072691
X1767990Y0076797
X1717089Y0025862
X1747720Y0034362
X1719589Y0025862
X1747720Y0031862
X1714589Y0021562
X1765260Y0018262
X1761998Y0015187
X1771774Y0053682
X1769274Y0050742
X1769669Y0015244
X1709589Y0026062
X1716875Y0068062
X1683334Y0075297
X1690934Y0069297
X1701934Y0075297
X1672200Y0069297
X1679934Y0075297
X1694334Y0069297
X1705334Y0075297
X1675228Y0026431
X1682333Y0019495
X1689401Y0026431
X1693106Y0019495
X1678933Y0019495
X1686001Y0026431
X1696506Y0019495
X1710106Y0040020
X1710106Y0048720
X1767400Y0039915
X1754620Y0039062
X1740858Y0082330
X1740858Y0074830
X1740858Y0079830
X1740858Y0072330
X1727600Y0052582
X1730140Y0052552
X1736040Y0044292
X1732810Y0052482
X1736040Y0041792
X1730220Y0049862
X1733720Y0049862
X1726720Y0049862
X1758063Y0072623
X1715210Y0018282
X1707220Y0015662
X1720895Y0068062
X1725320Y0067962
X1768026Y0024165
X1767185Y0048817
X1767220Y0026962
X1765238Y0022062
X1762420Y0021562
X1767220Y0053342
X1762738Y0053262
X1751065Y0039017
X1706112Y0072801
X1706112Y0077793
X1708112Y0075297
X1710920Y0082162
X1701156Y0072801
X1701156Y0077793
X1699156Y0075297
X1679156Y0072801
X1679156Y0077793
X1684112Y0072801
X1684112Y0077793
X1686112Y0075297
X1677156Y0075297
X1729620Y0057262
X1729520Y0061762
X1730820Y0076362
X1758063Y0068637
X1764400Y0057462
X1759700Y0057662
X1765068Y0080397
X1758568Y0079697
X1768168Y0080497
X1695112Y0071793
X1695112Y0066801
X1690156Y0071793
X1690156Y0066801
X1697112Y0069297
X1674978Y0069297
X1688156Y0069297
X1672978Y0071793
X1672978Y0066801
X1760485Y0048720
X1753398Y0048720
X1705381Y0048720
X1691208Y0048720
X1691208Y0040020
X1697824Y0039974
X1698295Y0048720
X1684122Y0048720
X1684122Y0040020
X1677035Y0048720
X1677035Y0040020
X1769900Y0037732
X1760475Y0028360
X1748400Y0037262
X1753388Y0028360
X1725320Y0028162
X1728820Y0028162
X1732320Y0028162
X1714520Y0037162
X1705381Y0037106
X1705381Y0028406
X1698295Y0037106
X1698295Y0028406
X1691208Y0037106
X1691208Y0028406
X1692179Y0025931
X1690179Y0023935
X1684122Y0037106
X1684122Y0028406
X1677035Y0037106
X1677035Y0028406
X1683223Y0025931
X1678006Y0025931
X1685223Y0023935
X1676006Y0023935
X1754090Y0016302
X1699284Y0019495
X1690328Y0019495
X1697284Y0021991
X1697284Y0016999
X1692328Y0021991
X1692328Y0016999
X1685111Y0019495
X1676155Y0019495
X1683111Y0021991
X1683111Y0016999
X1678155Y0021991
X1678155Y0016999
X1727768Y0003010
X1747768Y0003010
X1767768Y0003010
X1755272Y0026431
X1758672Y0026431
X1755269Y0050649
X1758669Y0050649
X1700217Y0026459
X1703617Y0026459
X1700170Y0050649
X1703570Y0050649
X1711700Y0140200
X1728999Y0112895
X1717418Y0135327
X1721418Y0135327
X1717140Y0148910
X1723670Y0149102
X1713418Y0130862
X1760478Y0090027
X1750820Y0119972
X1767170Y0083607
X1745010Y0122952
X1739720Y0120892
X1729080Y0118132
X1767300Y0174587
X1765820Y0182282
X1733920Y0151362
X1750920Y0171662
X1754120Y0171562
X1728320Y0169862
X1737470Y0177147
X1719530Y0162950
X1763435Y0166862
X1723090Y0177072
X1719943Y0116667
X1719943Y0112667
X1723090Y0173072
X1718110Y0159040
X1717619Y0165909
X1748720Y0097362
X1740220Y0101862
X1743720Y0101862
X1741720Y0098862
X1745220Y0098862
X1736720Y0101862
X1738220Y0098862
X1714490Y0142920
X1760478Y0106127
X1755978Y0111027
X1755978Y0108427
X1769278Y0113727
X1769278Y0110927
X1769278Y0108027
X1763678Y0106127
X1760978Y0116727
X1757978Y0116727
X1740563Y0112177
X1740563Y0109677
X1744106Y0112177
X1744106Y0109677
X1747650Y0112177
X1747650Y0109677
X1737020Y0109677
X1737020Y0112177
X1723218Y0093267
X1723018Y0101667
X1748465Y0147562
X1751220Y0147562
X1738520Y0151362
X1730765Y0151362
X1712720Y0111862
X1712520Y0117862
X1758300Y0128242
X1737704Y0183139
X1765870Y0179392
X1717280Y0174970
X1768483Y0166260
X1747591Y0171733
X1741222Y0151527
X1714180Y0154790
X1708000Y0099122
X1695950Y0096437
X1726918Y0101967
X1736508Y0134907
X1733378Y0134907
X1754398Y0100307
X1745485Y0119539
X1747482Y0121367
X1758573Y0083607
X1758573Y0087107
X1766278Y0093627
X1764678Y0122927
X1707159Y0210080
X1746484Y0279682
X1720310Y0191252
X1722078Y0189483
X1754234Y0190836
X1755078Y0224428
X1755078Y0221928
X1755078Y0219428
X1768500Y0214062
X1765000Y0214062
X1761500Y0214062
X1755078Y0216928
X1740500Y0220962
X1740500Y0223962
X1740500Y0226962
X1752078Y0219228
X1752078Y0221728
X1752078Y0224228
X1752078Y0226728
X1751800Y0206762
X1744600Y0209062
X1747600Y0209062
X1740500Y0208962
X1740500Y0211962
X1740500Y0214962
X1740500Y0217962
X1752078Y0216728
X1737500Y0220962
X1737500Y0223962
X1737500Y0226962
X1737500Y0208962
X1737500Y0211962
X1737500Y0214962
X1737500Y0217962
X1734857Y0184865
X1707159Y0220080
X1707159Y0225080
X1707159Y0222580
X1707159Y0215080
X1707159Y0217580
X1704185Y0222710
X1701264Y0219958
X1704264Y0219958
X1696225Y0219909
X1698725Y0219909
X1693725Y0219909
X1693466Y0212204
X1693466Y0214704
X1693466Y0209504
X1696066Y0209704
X1698566Y0209704
X1701264Y0214958
X1704264Y0214958
X1701264Y0217458
X1704264Y0217458
X1701164Y0212258
X1696225Y0217409
X1698725Y0217409
X1696066Y0212404
X1698566Y0212404
X1693725Y0217409
X1696066Y0214904
X1698566Y0214904
X1701164Y0209758
X1704223Y0212207
X1704223Y0209707
X1702490Y0204780
X1678994Y0217231
X1672596Y0220541
X1674432Y0216981
X1681900Y0227962
X1676300Y0219762
X1703487Y0232174
X1693987Y0233174
X1693987Y0230174
X1738200Y0193862
X1723240Y0185200
X1741200Y0193862
X1745500Y0193862
X1748500Y0193862
X1752200Y0197762
X1751084Y0190928
X1754307Y0266111
X1751068Y0266048
X1754245Y0269724
X1751068Y0262123
X1754307Y0262186
X1752195Y0276711
X1749595Y0276711
X1751006Y0269661
X1749565Y0273901
X1752165Y0273901
X1754414Y0275329
X1755378Y0233528
X1758500Y0234822
X1758500Y0231822
X1766880Y0231842
X1766880Y0234842
X1757439Y0279611
X1766765Y0279433
X1760398Y0279548
X1763731Y0279517
X1766725Y0282981
X1697725Y0205120
X1698220Y0369652
X1719200Y0371162
X1770220Y0377452
X1744510Y0377452
X1744380Y0382892
X1770220Y0382952
X1756933Y0372452
X1752000Y0306562
X1717220Y0381152
X1713720Y0381152
X1760104Y0301648
X1756204Y0301695
X1769230Y0310478
X1770280Y0372452
X1756800Y0368048
X1728300Y0377787
X1756800Y0364048
X1761936Y0310709
X1749450Y0293862
X1748989Y0380206
X1768757Y0380498
X1770520Y0368148
X1725400Y0372062
X1732660Y0372692
X1737260Y0368132
X1721400Y0374462
X1770520Y0364148
X1745000Y0299862
X1763731Y0283817
X1766655Y0286531
X1759529Y0289864
X1763045Y0289691
X1767309Y0290994
X1759629Y0295164
X1762285Y0295137
X1765053Y0295188
X1768045Y0295238
X1757439Y0283911
X1762549Y0286704
X1759509Y0292434
X1760398Y0283848
X1754963Y0310478
X1758563Y0310478
X1764955Y0301951
X1767455Y0302651
X1771229Y0291064
X1771029Y0295164
X1725344Y0359334
X1737660Y0390620
X1692429Y0403985
X1729810Y0390620
X1707568Y0420370
X1747080Y0435870
X1690208Y0421855
X1707544Y0431745
X1695455Y0422287
X1697161Y0406602
X1694050Y0416643
X1707780Y0410738
X1702959Y0404243
X1701124Y0423802
X1708977Y0458542
X1713977Y0457137
X1708977Y0470804
X1713977Y0470804
X1697220Y0455862
X1715711Y0474399
X1721220Y0458362
X1693236Y0472650
X1689095Y0462640
X1690229Y0481845
X1689943Y0479304
X1716134Y0478443
X1702127Y0468719
X1717220Y0384652
X1717220Y0388152
X1717220Y0391652
X1713720Y0388152
X1713720Y0384652
X1713720Y0391652
X1733780Y0390620
X1727700Y0417265
X1684940Y0463030
X1725522Y0482869
X1730954Y0478062
X1721936Y0469263
X1757650Y0461393
X1757066Y0435721
X1706500Y0415862
X1709000Y0415862
X1706500Y0413362
X1709000Y0413362
X1690140Y0434160
X1695579Y0403985
X1699809Y0403985
X1746720Y0464862
X1734290Y0423820
X1693720Y0455862
X1737434Y0398990
X1727760Y0420415
X1682810Y0465940
X1767300Y0465893
X1765670Y0458012
X1767300Y0461393
X1725473Y0474859
X1708760Y0478031
X1711477Y0468379
X1711477Y0465229
X1696760Y0478207
X1702760Y0478207
X1693648Y0463724
X1697648Y0463724
X1700846Y0455894
X1684356Y0476290
X1683476Y0473378
X1683394Y0469878
X1725500Y0383662
X1686154Y0434160
X1704444Y0407045
X1698014Y0424055
X1697914Y0427155
X1704624Y0433650
X1697214Y0433655
X1701124Y0433650
X1707444Y0407045
X1711144Y0425945
X1739316Y0480939
X1716110Y0532632
X1766060Y0539042
X1768560Y0539042
X1707716Y0513562
X1683369Y0566098
X1683369Y0562698
X1707552Y0506731
X1707552Y0503331
X1716278Y0491676
X1709680Y0545432
X1689506Y0539882
X1716156Y0487685
X1709356Y0541144
X1689544Y0543874
X1716087Y0495665
X1703306Y0550064
X1699553Y0513107
X1701726Y0518107
X1690999Y0513107
X1688768Y0518107
X1690999Y0525507
X1709844Y0516106
X1689769Y0537339
X1704886Y0534564
X1707346Y0547504
X1733354Y0486869
X1733354Y0490869
X1691445Y0535011
X1691104Y0530503
X1676600Y0523902
X1683702Y0514687
X1678860Y0556752
X1679941Y0552222
X1675664Y0513802
X1681817Y0495290
X1716148Y0483720
X1687238Y0485496
X1691151Y0493678
X1685779Y0491230
X1707200Y0498962
X1707610Y0534113
X1699251Y0533642
X1699666Y0541507
X1699265Y0521507
X1691129Y0501697
X1717987Y0569705
X1693711Y0498527
X1694050Y0501422
X1697210Y0500802
X1699300Y0498632
X1701635Y0497177
X1701811Y0501318
X1702270Y0552742
X1710500Y0538162
X1740886Y0493960
X1740831Y0489362
X1699297Y0549507
X1699251Y0529507
X1699291Y0537507
X1693701Y0515607
X1696851Y0515607
X1699265Y0525507
X1676040Y0569627
X1672040Y0569642
X1676004Y0531065
X1682004Y0531065
X1676004Y0543065
X1682180Y0543065
X1682004Y0537065
X1708760Y0484207
X1708760Y0490207
X1703720Y0509362
X1696120Y0506937
X1696760Y0484207
X1696760Y0490207
X1702760Y0490207
X1681612Y0499290
X1677464Y0491790
X1684356Y0485628
X1681602Y0485180
X1672770Y0580512
X1702930Y0526102
X1699107Y0555783
X1679244Y0650145
X1681864Y0652686
X1681864Y0650086
X1681864Y0647486
X1681864Y0644886
X1679244Y0647545
X1679244Y0644945
X1681864Y0642286
X1679244Y0642345
X1676644Y0650145
X1676644Y0647545
X1676644Y0644945
X1676624Y0642404
X1679244Y0652745
X1681864Y0655286
X1679244Y0655345
X1676644Y0652745
X1676644Y0655345
X1672500Y0596462
X1698302Y0657840
X1700922Y0657781
X1698232Y0642040
X1700852Y0641981
X1703452Y0641981
X1698232Y0652600
X1698232Y0650000
X1698232Y0647400
X1698232Y0644800
X1698232Y0655200
X1700852Y0644741
X1700852Y0652541
X1700852Y0649941
X1700852Y0647341
X1703452Y0644741
X1703452Y0652541
X1703452Y0649941
X1703452Y0647341
X1700852Y0655141
X1698232Y0639440
X1700852Y0639381
X1703452Y0639381
X1709027Y0655141
X1681810Y0752955
X1713920Y0700962
X1698020Y0702962
X1703310Y0749455
X1690620Y0760702
X1705035Y0729210
X1710122Y0703509
X1709828Y0719283
X1701320Y0705678
X1696402Y0709533
X1716480Y0691410
X1757612Y0712248
X1757572Y0720508
X1755112Y0712248
X1755072Y0720508
X1757612Y0695648
X1757612Y0703948
X1755013Y0692967
X1755112Y0695648
X1755112Y0703948
X1752316Y0712269
X1752276Y0720529
X1752217Y0692988
X1752316Y0695669
X1752316Y0703969
X1704973Y0753019
X1713450Y0728222
X1712824Y0696476
X1699110Y0727452
X1710550Y0691327
X1761612Y0712248
X1764112Y0712248
X1761572Y0720508
X1764072Y0720508
X1761612Y0695648
X1763570Y0693192
X1764112Y0695648
X1761612Y0703948
X1764112Y0703948
X1709107Y0728449
X1706720Y0703762
X1698537Y0766015
X1691021Y0722158
X1695367Y0719345
X1701087Y0719055
X1698137Y0718345
X1699307Y0722465
X1695227Y0722325
X1698920Y0698562
X1692883Y0703943
X1680401Y0722158
X1683121Y0722158
X1688301Y0722158
X1768317Y0686375
X1698048Y0705662
X1673860Y0726522
X1691412Y1379992
X1691412Y1382492
X1691412Y1374992
X1691412Y1377492
X1691412Y1369992
X1691412Y1367492
X1691412Y1372492
X1686362Y1377492
X1686362Y1374992
X1686362Y1382492
X1686362Y1379992
X1688912Y1379992
X1688912Y1382492
X1688912Y1374992
X1688912Y1377492
X1688912Y1369992
X1688912Y1367492
X1686362Y1369992
X1686362Y1367492
X1686362Y1372492
X1688912Y1372492
X1724431Y1336311
X1760165Y1310422
X1757165Y1310422
X1769165Y1298422
X1766165Y1298422
X1763165Y1298422
X1757165Y1298422
X1760165Y1298422
X1757165Y1295422
X1760165Y1295422
X1763165Y1295422
X1766165Y1295422
X1769165Y1295422
X1760165Y1301422
X1757165Y1301422
X1763165Y1301422
X1766165Y1301422
X1769165Y1301422
X1757165Y1307422
X1760165Y1307422
X1760165Y1304422
X1757165Y1304422
X1754165Y1310422
X1754165Y1298422
X1754165Y1295422
X1754165Y1301422
X1754165Y1307422
X1754165Y1304422
X1742714Y1287244
X1747814Y1287344
X1738014Y1287344
X1758352Y1322168
X1758352Y1317368
X1769829Y1351858
X1769829Y1349148
X1769829Y1343348
X1769829Y1346248
X1766829Y1343348
X1769829Y1340448
X1769829Y1337548
X1766829Y1340448
X1766829Y1337548
X1763829Y1337548
X1759987Y1328275
X1759987Y1325375
X1745111Y1463262
X1691086Y1439190
X1693392Y1429808
X1691086Y1433390
X1691086Y1436290
X1686820Y1439420
X1688986Y1437790
X1688886Y1434790
X1686820Y1436520
X1686180Y1433626
X1681520Y1433626
X1683850Y1432876
X1679190Y1432876
X1675185Y1440215
X1676928Y1442483
X1672786Y1442982
X1731600Y1457230
X1740200Y1462932
X1738740Y1451742
X1734717Y1404340
X1736400Y1455442
X1736400Y1458942
X1736700Y1462932
X1733200Y1462932
X1729700Y1462932
X1719727Y1472088
X1746970Y1451872
X1750970Y1456172
X1750970Y1459172
X1763730Y1480712
X1760160Y1476032
X1673226Y1394411
X1673129Y1433353
X1673129Y1427753
X1678426Y1394411
X1675926Y1394411
X1686135Y1394418
X1673846Y1421014
X1673846Y1417907
X1685190Y1421030
X1676446Y1421014
X1682246Y1417907
X1679046Y1417907
X1676446Y1417907
X1685190Y1417923
X1687860Y1412579
X1689210Y1417679
X1687860Y1415179
X1674046Y1424121
X1675559Y1433353
X1675559Y1427753
X1685159Y1424153
X1676646Y1424121
X1675621Y1445150
X1699150Y1393613
X1690809Y1393970
X1693404Y1421939
X1692960Y1412579
X1692960Y1415179
X1691918Y1417676
X1690460Y1412579
X1690460Y1415179
X1699437Y1431295
X1699545Y1425868
X1697820Y1423616
X1699593Y1428384
X1699457Y1447805
X1699457Y1439185
X1680720Y1487062
X1678340Y1500862
X1677930Y1520362
X1678340Y1541362
X1679508Y1498303
X1679508Y1517803
X1679508Y1538803
X1726149Y1496270
X1727674Y1505895
X1724649Y1505895
X1735310Y1520951
X1729310Y1520951
X1727674Y1513945
X1724649Y1513945
X1732310Y1520951
X1726310Y1520951
X1735310Y1530445
X1729310Y1530445
X1732310Y1530445
X1726310Y1530445
X1744677Y1507388
X1747677Y1507388
X1744304Y1524976
X1747304Y1524976
X1726120Y1490262
X1705003Y1564057
X1704723Y1541362
X1704723Y1520362
X1704723Y1500862
X1691988Y1558262
X1679508Y1563380
X1691988Y1538803
X1679508Y1543921
X1679508Y1522921
X1691988Y1517803
X1691988Y1498303
X1679508Y1503421
X1717149Y1505895
X1718149Y1496270
X1720174Y1513945
X1717149Y1513945
X1711988Y1520951
X1717988Y1520951
X1720174Y1505895
X1711988Y1530445
X1708988Y1530445
X1714988Y1530445
X1717988Y1530445
X1708988Y1520951
X1714988Y1520951
X1763730Y1483712
X1763830Y1487782
X1763830Y1490782
X1674220Y1585321
X1678230Y1590542
X1705723Y1583821
X1679508Y1583880
X1671866Y1737108
X1691866Y1737108
X1711866Y1737108
X1731866Y1737108
X1751866Y1737108
X1771866Y1737108
X1828880Y1686595
X1830466Y1606658
X1828880Y1626595
X1828880Y1646595
X1828880Y1666595
X1840691Y1589470
X1800450Y1505230
X1813994Y1507891
X1818289Y1501591
X1811494Y1505349
X1795561Y1524729
X1807150Y1505675
X1813700Y1494762
X1824995Y1502201
X1832114Y1500807
X1832114Y1498198
X1829514Y1500807
X1829514Y1498198
X1795484Y1496401
X1792645Y1511423
X1801450Y1527830
X1801450Y1524830
X1798450Y1524830
X1803517Y1495567
X1818524Y1528991
X1814210Y1525815
X1814370Y1528900
X1807850Y1524830
X1804650Y1524830
X1804650Y1527830
X1807850Y1527830
X1811250Y1527830
X1811250Y1524830
X1812250Y1521830
X1818410Y1525815
X1823426Y1507916
X1821710Y1525915
X1828510Y1525915
X1835334Y1520921
X1831994Y1525977
X1840691Y1489470
X1840691Y1509470
X1840691Y1529470
X1840691Y1549470
X1840691Y1569470
X1840691Y1409470
X1840691Y1429470
X1840691Y1449470
X1840691Y1469470
X1814537Y1322105
X1781165Y1312922
X1781165Y1310422
X1784165Y1312922
X1784165Y1310422
X1778165Y1312922
X1778165Y1310422
X1781165Y1298422
X1781165Y1295422
X1781165Y1301422
X1784165Y1298422
X1784165Y1295422
X1784165Y1301422
X1781165Y1304422
X1781165Y1307422
X1784165Y1304422
X1784165Y1307422
X1778165Y1298422
X1775165Y1298422
X1772165Y1298422
X1772165Y1295422
X1775165Y1295422
X1778165Y1295422
X1772165Y1301422
X1775165Y1301422
X1778165Y1301422
X1778165Y1304422
X1778165Y1307422
X1778829Y1354758
X1775829Y1354758
X1772829Y1354758
X1778829Y1351858
X1775829Y1351858
X1772829Y1351858
X1778829Y1349148
X1775829Y1349148
X1772829Y1349148
X1778829Y1343348
X1775829Y1343348
X1772829Y1343348
X1778829Y1346248
X1775829Y1346248
X1772829Y1346248
X1781829Y1354758
X1781829Y1351858
X1781829Y1349148
X1781829Y1343348
X1781829Y1346248
X1772829Y1340448
X1775829Y1340448
X1778829Y1340448
X1775829Y1337548
X1772829Y1337548
X1778829Y1337548
X1778829Y1327348
X1778829Y1330248
X1778829Y1333148
X1784829Y1340448
X1784829Y1337548
X1781829Y1340448
X1781829Y1337548
X1784829Y1327348
X1784829Y1330248
X1784829Y1333148
X1781829Y1327348
X1781829Y1330248
X1781829Y1333148
X1778829Y1324448
X1784829Y1324448
X1781829Y1324448
X1840691Y1329470
X1800107Y1256426
X1791888Y0683805
X1781720Y0592742
X1778310Y0591152
X1776160Y0592792
X1840691Y0589470
X1840691Y0669470
X1840691Y0489470
X1840691Y0509470
X1840691Y0529470
X1840691Y0549470
X1840691Y0569470
X1810792Y0417432
X1834600Y0406442
X1781470Y0452065
X1821280Y0413432
X1812161Y0472521
X1838379Y0453921
X1782420Y0447137
X1826914Y0431718
X1815724Y0423932
X1782324Y0418932
X1782324Y0425432
X1834005Y0401421
X1816994Y0398052
X1816224Y0410432
X1782324Y0403932
X1782324Y0410432
X1792507Y0403932
X1792450Y0410615
X1792335Y0418775
X1792220Y0425432
X1791494Y0386536
X1796020Y0451162
X1829434Y0406348
X1818816Y0468872
X1838020Y0459121
X1773870Y0438222
X1782420Y0443987
X1818874Y0423932
X1795468Y0421334
X1819374Y0410432
X1795479Y0408056
X1820144Y0398052
X1802929Y0385293
X1840691Y0389470
X1840691Y0409470
X1840691Y0429470
X1840691Y0449470
X1840691Y0469470
X1800340Y0387062
X1836294Y0383592
X1829189Y0363731
X1777354Y0295489
X1789093Y0294441
X1791619Y0294441
X1790743Y0287641
X1793269Y0287641
X1783563Y0287641
X1786089Y0287641
X1800160Y0362542
X1828204Y0328654
X1783018Y0301729
X1817157Y0373829
X1836750Y0373632
X1829026Y0367701
X1820307Y0373829
X1803129Y0362293
X1772863Y0310478
X1791289Y0308671
X1788763Y0308671
X1798289Y0308671
X1795763Y0308671
X1802763Y0308671
X1805289Y0308671
X1809823Y0308734
X1812349Y0308734
X1850331Y0311946
X1840691Y0329470
X1840691Y0349470
X1840691Y0369470
X1854470Y0292379
X1838880Y0195162
X1835760Y0185772
X1783878Y0221928
X1783878Y0219428
X1783878Y0226928
X1783878Y0224428
X1778778Y0221928
X1778778Y0219428
X1772000Y0214062
X1783878Y0216928
X1778778Y0216928
X1837895Y0228933
X1837895Y0231433
X1837895Y0233933
X1837895Y0223733
X1837895Y0226333
X1834895Y0228933
X1834895Y0231433
X1834895Y0233933
X1824095Y0228933
X1827095Y0228933
X1824095Y0231433
X1827095Y0231433
X1832295Y0228933
X1829695Y0228933
X1832295Y0231433
X1829695Y0231433
X1824095Y0233933
X1827095Y0233933
X1829695Y0233933
X1832295Y0233933
X1829695Y0223733
X1832295Y0223733
X1827095Y0223733
X1824095Y0223733
X1834895Y0223733
X1834895Y0226333
X1824095Y0226333
X1827095Y0226333
X1832295Y0226333
X1829695Y0226333
X1775140Y0231792
X1775140Y0234792
X1783800Y0234762
X1783800Y0231762
X1786690Y0231782
X1786690Y0234782
X1786089Y0273471
X1783563Y0273471
X1779226Y0275604
X1793089Y0273471
X1790563Y0273471
X1800189Y0269571
X1797663Y0269571
X1804723Y0269634
X1807249Y0269634
X1811823Y0269634
X1814349Y0269634
X1843134Y0244362
X1838910Y0185772
X1854470Y0192379
X1854470Y0212379
X1854470Y0232379
X1854470Y0252379
X1854470Y0272379
X1813335Y0155435
X1773611Y0088293
X1808910Y0143902
X1781485Y0088192
X1787790Y0085132
X1779500Y0171692
X1782600Y0175932
X1806920Y0150862
X1780320Y0153162
X1807220Y0179897
X1777520Y0173903
X1777520Y0178403
X1803215Y0154032
X1848435Y0172187
X1846691Y0166450
X1825762Y0167662
X1784178Y0113927
X1784178Y0111127
X1784178Y0108227
X1778478Y0090627
X1778578Y0097927
X1844157Y0182210
X1813325Y0177257
X1774950Y0167392
X1823508Y0158868
X1819939Y0177243
X1780320Y0177602
X1828777Y0156520
X1806365Y0154032
X1810835Y0163986
X1797324Y0161465
X1841257Y0151402
X1784238Y0150744
X1854470Y0112379
X1854470Y0152379
X1854470Y0172379
X1785178Y0086927
X1785178Y0089927
X1771915Y0123393
X1771915Y0125893
X1782000Y0123455
X1782000Y0125955
X1771915Y0128393
X1782000Y0128455
X1788238Y0074912
X1779411Y0050692
X1785142Y0076032
X1775580Y0073330
X1776710Y0053562
X1774274Y0050742
X1775556Y0021471
X1782305Y0013647
X1777754Y0037746
X1788238Y0078062
X1788238Y0082292
X1779778Y0072927
X1774328Y0062987
X1779778Y0070027
X1774328Y0060087
X1799920Y0052594
X1775830Y0026522
X1807580Y0059397
X1807549Y0056415
X1793061Y0024659
X1794910Y0044573
X1814322Y0049388
X1834322Y0049388
X1854096Y0052383
X1787768Y0003010
X1781774Y0054462
M00
X0230906Y1734212
X0246654Y1734212
X0262402Y1734212
X0230906Y1724763
X0246654Y1724763
X0262402Y1724763
X0230906Y1720039
X0246654Y1720039
X0262402Y1720039
X0230906Y1710590
X0246654Y1710590
X0262402Y1710590
X0230906Y1705866
X0246654Y1705866
X0262402Y1705866
X0230906Y1696417
X0246654Y1696417
X0262402Y1696417
X0230906Y1691692
X0246654Y1691692
X0262402Y1691692
X0238780Y1728700
X0254528Y1728700
X0270276Y1728700
X0238780Y1723976
X0254528Y1723976
X0270276Y1723976
X0238780Y1714527
X0254528Y1714527
X0270276Y1714527
X0238780Y1709803
X0254528Y1709803
X0270276Y1709803
X0238780Y1700354
X0254528Y1700354
X0270276Y1700354
X0238780Y1695629
X0254528Y1695629
X0270276Y1695629
X0238780Y1686180
X0254528Y1686180
X0270276Y1686180
X0230906Y1682244
X0246654Y1682244
X0262402Y1682244
X0230906Y1677519
X0246654Y1677519
X0262402Y1677519
X0230906Y1668070
X0246654Y1668070
X0262402Y1668070
X0230906Y1663346
X0246654Y1663346
X0262402Y1663346
X0230906Y1653897
X0246654Y1653897
X0262402Y1653897
X0230906Y1649173
X0246654Y1649173
X0262402Y1649173
X0238780Y1681456
X0254528Y1681456
X0270276Y1681456
X0238780Y1672007
X0254528Y1672007
X0270276Y1672007
X0238780Y1667283
X0254528Y1667283
X0270276Y1667283
X0238780Y1657834
X0254528Y1657834
X0270276Y1657834
X0238780Y1653110
X0254528Y1653110
X0270276Y1653110
X0238780Y1643661
X0254528Y1643661
X0270276Y1643661
X0352953Y1681456
X0345079Y1682244
X0337205Y1681456
X0329331Y1682244
X0321457Y1681456
X0313583Y1682244
X0305709Y1681456
X0297835Y1682244
X0345079Y1677519
X0329331Y1677519
X0313583Y1677519
X0297835Y1677519
X0352953Y1672007
X0337205Y1672007
X0321457Y1672007
X0305709Y1672007
X0278150Y1682244
X0278150Y1677519
X0278150Y1668070
X0278150Y1663346
X0278150Y1653897
X0278150Y1649173
X0286024Y1681456
X0286024Y1672007
X0286024Y1667283
X0286024Y1657834
X0286024Y1653110
X0286024Y1643661
X0345079Y1734212
X0329331Y1734212
X0313583Y1734212
X0297835Y1734212
X0352953Y1728700
X0337205Y1728700
X0321457Y1728700
X0305709Y1728700
X0352953Y1723976
X0345079Y1724763
X0337205Y1723976
X0329331Y1724763
X0321457Y1723976
X0313583Y1724763
X0305709Y1723976
X0297835Y1724763
X0345079Y1720039
X0329331Y1720039
X0313583Y1720039
X0297835Y1720039
X0352953Y1714527
X0337205Y1714527
X0321457Y1714527
X0305709Y1714527
X0352953Y1709803
X0345079Y1710590
X0337205Y1709803
X0329331Y1710590
X0321457Y1709803
X0313583Y1710590
X0305709Y1709803
X0297835Y1710590
X0345079Y1705866
X0329331Y1705866
X0313583Y1705866
X0297835Y1705866
X0352953Y1700354
X0337205Y1700354
X0321457Y1700354
X0305709Y1700354
X0352953Y1695629
X0345079Y1696417
X0337205Y1695629
X0329331Y1696417
X0321457Y1695629
X0313583Y1696417
X0305709Y1695629
X0297835Y1696417
X0345079Y1691692
X0329331Y1691692
X0313583Y1691692
X0297835Y1691692
X0352953Y1686180
X0337205Y1686180
X0321457Y1686180
X0305709Y1686180
X0278150Y1734212
X0278150Y1724763
X0278150Y1720039
X0278150Y1710590
X0278150Y1705866
X0278150Y1696417
X0278150Y1691692
X0286024Y1728700
X0286024Y1723976
X0286024Y1714527
X0286024Y1709803
X0286024Y1700354
X0286024Y1695629
X0286024Y1686180
X0550197Y1681456
X0542323Y1682244
X0534449Y1681456
X0526575Y1682244
X0518701Y1681456
X0510827Y1682244
X0502953Y1681456
X0495079Y1682244
X0542323Y1677519
X0526575Y1677519
X0510827Y1677519
X0495079Y1677519
X0550197Y1672007
X0534449Y1672007
X0518701Y1672007
X0502953Y1672007
X0569882Y1681456
X0562008Y1682244
X0562008Y1677519
X0569882Y1672007
X0542323Y1734212
X0526575Y1734212
X0510827Y1734212
X0495079Y1734212
X0550197Y1728700
X0534449Y1728700
X0518701Y1728700
X0502953Y1728700
X0550197Y1723976
X0542323Y1724763
X0534449Y1723976
X0526575Y1724763
X0518701Y1723976
X0510827Y1724763
X0502953Y1723976
X0495079Y1724763
X0542323Y1720039
X0526575Y1720039
X0510827Y1720039
X0495079Y1720039
X0550197Y1714527
X0534449Y1714527
X0518701Y1714527
X0502953Y1714527
X0550197Y1709803
X0542323Y1710590
X0534449Y1709803
X0526575Y1710590
X0518701Y1709803
X0510827Y1710590
X0502953Y1709803
X0495079Y1710590
X0542323Y1705866
X0526575Y1705866
X0510827Y1705866
X0495079Y1705866
X0550197Y1700354
X0534449Y1700354
X0518701Y1700354
X0502953Y1700354
X0550197Y1695629
X0542323Y1696417
X0534449Y1695629
X0526575Y1696417
X0518701Y1695629
X0510827Y1696417
X0502953Y1695629
X0495079Y1696417
X0542323Y1691692
X0526575Y1691692
X0510827Y1691692
X0495079Y1691692
X0550197Y1686180
X0534449Y1686180
X0518701Y1686180
X0502953Y1686180
X0562008Y1734212
X0569882Y1728700
X0569882Y1723976
X0562008Y1724763
X0562008Y1720039
X0569882Y1714527
X0569882Y1709803
X0562008Y1710590
X0562008Y1705866
X0569882Y1700354
X0569882Y1695629
X0562008Y1696417
X0562008Y1691692
X0569882Y1686180
X0609252Y1734212
X0593504Y1734212
X0577756Y1734212
X0617126Y1728700
X0601378Y1728700
X0585630Y1728700
X0617126Y1723976
X0609252Y1724763
X0601378Y1723976
X0593504Y1724763
X0585630Y1723976
X0577756Y1724763
X0609252Y1720039
X0593504Y1720039
X0577756Y1720039
X0617126Y1714527
X0601378Y1714527
X0585630Y1714527
X0617126Y1709803
X0609252Y1710590
X0601378Y1709803
X0593504Y1710590
X0585630Y1709803
X0577756Y1710590
X0609252Y1705866
X0593504Y1705866
X0577756Y1705866
X0617126Y1700354
X0601378Y1700354
X0585630Y1700354
X0617126Y1695629
X0609252Y1696417
X0601378Y1695629
X0593504Y1696417
X0585630Y1695629
X0577756Y1696417
X0609252Y1691692
X0593504Y1691692
X0577756Y1691692
X0617126Y1686180
X0601378Y1686180
X0585630Y1686180
X0617126Y1681456
X0609252Y1682244
X0601378Y1681456
X0593504Y1682244
X0585630Y1681456
X0577756Y1682244
X0609252Y1677519
X0593504Y1677519
X0577756Y1677519
X0617126Y1672007
X0601378Y1672007
X0585630Y1672007
X1270276Y1734212
X1254528Y1734212
X1238780Y1734212
X1262402Y1728700
X1246654Y1728700
X1270276Y1724763
X1262402Y1723976
X1254528Y1724763
X1246654Y1723976
X1238780Y1724763
X1270276Y1720039
X1254528Y1720039
X1238780Y1720039
X1262402Y1714527
X1246654Y1714527
X1270276Y1710590
X1262402Y1709803
X1254528Y1710590
X1246654Y1709803
X1238780Y1710590
X1270276Y1705866
X1254528Y1705866
X1238780Y1705866
X1262402Y1700354
X1246654Y1700354
X1270276Y1696417
X1262402Y1695629
X1254528Y1696417
X1246654Y1695629
X1238780Y1696417
X1270276Y1691692
X1254528Y1691692
X1238780Y1691692
X1262402Y1686180
X1246654Y1686180
X1270276Y1682244
X1262402Y1681456
X1254528Y1682244
X1246654Y1681456
X1238780Y1682244
X1270276Y1677519
X1254528Y1677519
X1238780Y1677519
X1262402Y1672007
X1246654Y1672007
X1360827Y1681456
X1352953Y1682244
X1345079Y1681456
X1337205Y1682244
X1329331Y1681456
X1321457Y1682244
X1313583Y1681456
X1305709Y1682244
X1352953Y1677519
X1337205Y1677519
X1321457Y1677519
X1305709Y1677519
X1360827Y1672007
X1345079Y1672007
X1329331Y1672007
X1313583Y1672007
X1293898Y1681456
X1286024Y1682244
X1278150Y1681456
X1286024Y1677519
X1293898Y1672007
X1278150Y1672007
X1352953Y1734212
X1337205Y1734212
X1321457Y1734212
X1305709Y1734212
X1360827Y1728700
X1345079Y1728700
X1329331Y1728700
X1313583Y1728700
X1360827Y1723976
X1352953Y1724763
X1345079Y1723976
X1337205Y1724763
X1329331Y1723976
X1321457Y1724763
X1313583Y1723976
X1305709Y1724763
X1352953Y1720039
X1337205Y1720039
X1321457Y1720039
X1305709Y1720039
X1360827Y1714527
X1345079Y1714527
X1329331Y1714527
X1313583Y1714527
X1360827Y1709803
X1352953Y1710590
X1345079Y1709803
X1337205Y1710590
X1329331Y1709803
X1321457Y1710590
X1313583Y1709803
X1305709Y1710590
X1352953Y1705866
X1337205Y1705866
X1321457Y1705866
X1305709Y1705866
X1360827Y1700354
X1345079Y1700354
X1329331Y1700354
X1313583Y1700354
X1360827Y1695629
X1352953Y1696417
X1345079Y1695629
X1337205Y1696417
X1329331Y1695629
X1321457Y1696417
X1313583Y1695629
X1305709Y1696417
X1352953Y1691692
X1337205Y1691692
X1321457Y1691692
X1305709Y1691692
X1360827Y1686180
X1345079Y1686180
X1329331Y1686180
X1313583Y1686180
X1286024Y1734212
X1293898Y1728700
X1278150Y1728700
X1293898Y1723976
X1286024Y1724763
X1278150Y1723976
X1286024Y1720039
X1293898Y1714527
X1278150Y1714527
X1293898Y1709803
X1286024Y1710590
X1278150Y1709803
X1286024Y1705866
X1293898Y1700354
X1278150Y1700354
X1293898Y1695629
X1286024Y1696417
X1278150Y1695629
X1286024Y1691692
X1293898Y1686180
X1278150Y1686180
X1558071Y1681456
X1550197Y1682244
X1542323Y1681456
X1534449Y1682244
X1526575Y1681456
X1518701Y1682244
X1510827Y1681456
X1502953Y1682244
X1550197Y1677519
X1534449Y1677519
X1518701Y1677519
X1502953Y1677519
X1558071Y1672007
X1542323Y1672007
X1526575Y1672007
X1510827Y1672007
X1569882Y1682244
X1569882Y1677519
X1550197Y1734212
X1534449Y1734212
X1518701Y1734212
X1502953Y1734212
X1558071Y1728700
X1542323Y1728700
X1526575Y1728700
X1510827Y1728700
X1558071Y1723976
X1550197Y1724763
X1542323Y1723976
X1534449Y1724763
X1526575Y1723976
X1518701Y1724763
X1510827Y1723976
X1502953Y1724763
X1550197Y1720039
X1534449Y1720039
X1518701Y1720039
X1502953Y1720039
X1558071Y1714527
X1542323Y1714527
X1526575Y1714527
X1510827Y1714527
X1558071Y1709803
X1550197Y1710590
X1542323Y1709803
X1534449Y1710590
X1526575Y1709803
X1518701Y1710590
X1510827Y1709803
X1502953Y1710590
X1550197Y1705866
X1534449Y1705866
X1518701Y1705866
X1502953Y1705866
X1558071Y1700354
X1542323Y1700354
X1526575Y1700354
X1510827Y1700354
X1558071Y1695629
X1550197Y1696417
X1542323Y1695629
X1534449Y1696417
X1526575Y1695629
X1518701Y1696417
X1510827Y1695629
X1502953Y1696417
X1550197Y1691692
X1534449Y1691692
X1518701Y1691692
X1502953Y1691692
X1558071Y1686180
X1542323Y1686180
X1526575Y1686180
X1510827Y1686180
X1569882Y1734212
X1569882Y1724763
X1569882Y1720039
X1569882Y1710590
X1569882Y1705866
X1569882Y1696417
X1569882Y1691692
X1617126Y1734212
X1601378Y1734212
X1585630Y1734212
X1625000Y1728700
X1609252Y1728700
X1593504Y1728700
X1577756Y1728700
X1625000Y1723976
X1617126Y1724763
X1609252Y1723976
X1601378Y1724763
X1593504Y1723976
X1585630Y1724763
X1577756Y1723976
X1617126Y1720039
X1601378Y1720039
X1585630Y1720039
X1625000Y1714527
X1609252Y1714527
X1593504Y1714527
X1577756Y1714527
X1625000Y1709803
X1617126Y1710590
X1609252Y1709803
X1601378Y1710590
X1593504Y1709803
X1585630Y1710590
X1577756Y1709803
X1617126Y1705866
X1601378Y1705866
X1585630Y1705866
X1625000Y1700354
X1609252Y1700354
X1593504Y1700354
X1577756Y1700354
X1625000Y1695629
X1617126Y1696417
X1609252Y1695629
X1601378Y1696417
X1593504Y1695629
X1585630Y1696417
X1577756Y1695629
X1617126Y1691692
X1601378Y1691692
X1585630Y1691692
X1625000Y1686180
X1609252Y1686180
X1593504Y1686180
X1577756Y1686180
X1625000Y1681456
X1617126Y1682244
X1609252Y1681456
X1601378Y1682244
X1593504Y1681456
X1585630Y1682244
X1577756Y1681456
X1617126Y1677519
X1601378Y1677519
X1585630Y1677519
X1625000Y1672007
X1609252Y1672007
X1593504Y1672007
X1577756Y1672007
M00
X0230906Y1729488
X0246654Y1729488
X0262402Y1729488
X0230906Y1715314
X0246654Y1715314
X0262402Y1715314
X0230906Y1701141
X0246654Y1701141
X0262402Y1701141
X0230906Y1686968
X0246654Y1686968
X0262402Y1686968
X0238780Y1733425
X0254528Y1733425
X0270276Y1733425
X0238780Y1719251
X0254528Y1719251
X0270276Y1719251
X0238780Y1705078
X0254528Y1705078
X0270276Y1705078
X0238780Y1690905
X0254528Y1690905
X0270276Y1690905
X0230906Y1672795
X0246654Y1672795
X0262402Y1672795
X0230906Y1658621
X0246654Y1658621
X0262402Y1658621
X0230906Y1644448
X0246654Y1644448
X0262402Y1644448
X0238780Y1676732
X0254528Y1676732
X0270276Y1676732
X0238780Y1662558
X0254528Y1662558
X0270276Y1662558
X0238780Y1648385
X0254528Y1648385
X0270276Y1648385
X0352953Y1676732
X0337205Y1676732
X0321457Y1676732
X0305709Y1676732
X0345079Y1672795
X0329331Y1672795
X0313583Y1672795
X0297835Y1672795
X0278150Y1672795
X0278150Y1658621
X0278150Y1644448
X0286024Y1676732
X0286024Y1662558
X0286024Y1648385
X0352953Y1733425
X0337205Y1733425
X0321457Y1733425
X0305709Y1733425
X0345079Y1729488
X0329331Y1729488
X0313583Y1729488
X0297835Y1729488
X0352953Y1719251
X0337205Y1719251
X0321457Y1719251
X0305709Y1719251
X0345079Y1715314
X0329331Y1715314
X0313583Y1715314
X0297835Y1715314
X0352953Y1705078
X0337205Y1705078
X0321457Y1705078
X0305709Y1705078
X0345079Y1701141
X0329331Y1701141
X0313583Y1701141
X0297835Y1701141
X0352953Y1690905
X0337205Y1690905
X0321457Y1690905
X0305709Y1690905
X0345079Y1686968
X0329331Y1686968
X0313583Y1686968
X0297835Y1686968
X0278150Y1729488
X0278150Y1715314
X0278150Y1701141
X0278150Y1686968
X0286024Y1733425
X0286024Y1719251
X0286024Y1705078
X0286024Y1690905
X0550197Y1676732
X0534449Y1676732
X0518701Y1676732
X0502953Y1676732
X0542323Y1672795
X0526575Y1672795
X0510827Y1672795
X0495079Y1672795
X0569882Y1676732
X0562008Y1672795
X0550197Y1733425
X0534449Y1733425
X0518701Y1733425
X0502953Y1733425
X0542323Y1729488
X0526575Y1729488
X0510827Y1729488
X0495079Y1729488
X0550197Y1719251
X0534449Y1719251
X0518701Y1719251
X0502953Y1719251
X0542323Y1715314
X0526575Y1715314
X0510827Y1715314
X0495079Y1715314
X0550197Y1705078
X0534449Y1705078
X0518701Y1705078
X0502953Y1705078
X0542323Y1701141
X0526575Y1701141
X0510827Y1701141
X0495079Y1701141
X0550197Y1690905
X0534449Y1690905
X0518701Y1690905
X0502953Y1690905
X0542323Y1686968
X0526575Y1686968
X0510827Y1686968
X0495079Y1686968
X0569882Y1733425
X0562008Y1729488
X0569882Y1719251
X0562008Y1715314
X0569882Y1705078
X0562008Y1701141
X0569882Y1690905
X0562008Y1686968
X0617126Y1733425
X0601378Y1733425
X0585630Y1733425
X0609252Y1729488
X0593504Y1729488
X0577756Y1729488
X0617126Y1719251
X0601378Y1719251
X0585630Y1719251
X0609252Y1715314
X0593504Y1715314
X0577756Y1715314
X0617126Y1705078
X0601378Y1705078
X0585630Y1705078
X0609252Y1701141
X0593504Y1701141
X0577756Y1701141
X0617126Y1690905
X0601378Y1690905
X0585630Y1690905
X0609252Y1686968
X0593504Y1686968
X0577756Y1686968
X0617126Y1676732
X0601378Y1676732
X0585630Y1676732
X0609252Y1672795
X0593504Y1672795
X0577756Y1672795
X1262402Y1733425
X1246654Y1733425
X1270276Y1729488
X1254528Y1729488
X1238780Y1729488
X1262402Y1719251
X1246654Y1719251
X1270276Y1715314
X1254528Y1715314
X1238780Y1715314
X1262402Y1705078
X1246654Y1705078
X1270276Y1701141
X1254528Y1701141
X1238780Y1701141
X1262402Y1690905
X1246654Y1690905
X1270276Y1686968
X1254528Y1686968
X1238780Y1686968
X1262402Y1676732
X1246654Y1676732
X1270276Y1672795
X1254528Y1672795
X1238780Y1672795
X1360827Y1676732
X1345079Y1676732
X1329331Y1676732
X1313583Y1676732
X1352953Y1672795
X1337205Y1672795
X1321457Y1672795
X1305709Y1672795
X1293898Y1676732
X1278150Y1676732
X1286024Y1672795
X1360827Y1733425
X1345079Y1733425
X1329331Y1733425
X1313583Y1733425
X1352953Y1729488
X1337205Y1729488
X1321457Y1729488
X1305709Y1729488
X1360827Y1719251
X1345079Y1719251
X1329331Y1719251
X1313583Y1719251
X1352953Y1715314
X1337205Y1715314
X1321457Y1715314
X1305709Y1715314
X1360827Y1705078
X1345079Y1705078
X1329331Y1705078
X1313583Y1705078
X1352953Y1701141
X1337205Y1701141
X1321457Y1701141
X1305709Y1701141
X1360827Y1690905
X1345079Y1690905
X1329331Y1690905
X1313583Y1690905
X1352953Y1686968
X1337205Y1686968
X1321457Y1686968
X1305709Y1686968
X1293898Y1733425
X1278150Y1733425
X1286024Y1729488
X1293898Y1719251
X1278150Y1719251
X1286024Y1715314
X1293898Y1705078
X1278150Y1705078
X1286024Y1701141
X1293898Y1690905
X1278150Y1690905
X1286024Y1686968
X1558071Y1676732
X1542323Y1676732
X1526575Y1676732
X1510827Y1676732
X1550197Y1672795
X1534449Y1672795
X1518701Y1672795
X1502953Y1672795
X1569882Y1672795
X1558071Y1733425
X1542323Y1733425
X1526575Y1733425
X1510827Y1733425
X1550197Y1729488
X1534449Y1729488
X1518701Y1729488
X1502953Y1729488
X1558071Y1719251
X1542323Y1719251
X1526575Y1719251
X1510827Y1719251
X1550197Y1715314
X1534449Y1715314
X1518701Y1715314
X1502953Y1715314
X1558071Y1705078
X1542323Y1705078
X1526575Y1705078
X1510827Y1705078
X1550197Y1701141
X1534449Y1701141
X1518701Y1701141
X1502953Y1701141
X1558071Y1690905
X1542323Y1690905
X1526575Y1690905
X1510827Y1690905
X1550197Y1686968
X1534449Y1686968
X1518701Y1686968
X1502953Y1686968
X1569882Y1729488
X1569882Y1715314
X1569882Y1701141
X1569882Y1686968
X1625000Y1733425
X1609252Y1733425
X1593504Y1733425
X1577756Y1733425
X1617126Y1729488
X1601378Y1729488
X1585630Y1729488
X1625000Y1719251
X1609252Y1719251
X1593504Y1719251
X1577756Y1719251
X1617126Y1715314
X1601378Y1715314
X1585630Y1715314
X1625000Y1705078
X1609252Y1705078
X1593504Y1705078
X1577756Y1705078
X1617126Y1701141
X1601378Y1701141
X1585630Y1701141
X1625000Y1690905
X1609252Y1690905
X1593504Y1690905
X1577756Y1690905
X1617126Y1686968
X1601378Y1686968
X1585630Y1686968
X1625000Y1676732
X1609252Y1676732
X1593504Y1676732
X1577756Y1676732
X1617126Y1672795
X1601378Y1672795
X1585630Y1672795
M00
X0854090Y1420330
X0850326Y1429416
X0841240Y1433180
X0832154Y1429416
X0828390Y1420330
X0832154Y1411244
X0841240Y1407480
X0850326Y1411244
X0805690Y0220472
X0793879Y0214567
X0789942Y0204724
X0793879Y0194881
X0805690Y0188976
X0817501Y0194881
X0821438Y0204724
X0817501Y0214567
X0911494Y0321653
X0916545Y0309459
X0928739Y0304408
X0940933Y0309459
X0945984Y0321653
X0940933Y0333847
X0928739Y0338898
X0916545Y0333847
X1029090Y1420330
X1025326Y1429416
X1016240Y1433180
X1007154Y1429416
X1003390Y1420330
X1007154Y1411244
X1016240Y1407480
X1025326Y1411244
X1057658Y0220472
X1045847Y0214567
X1041910Y0204724
X1045847Y0194881
X1057658Y0188976
X1069469Y0194881
X1069469Y0214567
X1073406Y0204724
M00
X1077638Y0133866
M00
X0195316Y1430034
X0205159Y1430034
X0174393Y0678354
X0174393Y0668511
X0174685Y0647210
X0174685Y0637367
X0412990Y1354446
X0422833Y1354446
X0443326Y1354446
X0453169Y1354446
X0383224Y1354446
X0393067Y1354446
X0458600Y1379662
X0468443Y1379662
X0472700Y1353962
X0482543Y1353962
X0526478Y1449795
X0526478Y1439952
X0708795Y1429579
X0718638Y1429579
X1168627Y1466363
X1178470Y1466363
X1359365Y1353946
X1369208Y1353946
X1389131Y1353946
X1398974Y1353946
X1449233Y1353946
X1459076Y1353946
X1419467Y1353946
X1429310Y1353946
X1434200Y1379362
X1444043Y1379362
X1502956Y1449373
X1502956Y1439530
X1670101Y1463655
X1769790Y0204632
X1769790Y0194789
X1682882Y0678952
X1682882Y0669109
X1682882Y0628017
X1682882Y0618174
X1679944Y1463655
X1826405Y0299056
X1836248Y0299056
X1826405Y0269763
X1836248Y0269763
X1799350Y0204632
X1799350Y0194789
M00
X0853780Y1714890
X0863780Y1714890
X0853780Y1684890
X0853780Y1694890
X0853780Y1704890
X0863780Y1684890
X0863780Y1694890
X0863780Y1704890
X0818780Y1714890
X0828780Y1714890
X0818780Y1684890
X0818780Y1694890
X0818780Y1704890
X0828780Y1684890
X0828780Y1694890
X0828780Y1704890
X0938780Y1714890
X0928780Y1714890
X0918780Y1714890
X0938780Y1704890
X0928780Y1704890
X0918780Y1704890
X0938780Y1694890
X0928780Y1694890
X0918780Y1694890
X0938780Y1684890
X0928780Y1684890
X0918780Y1684890
X0958780Y1714890
X0968780Y1714890
X0958780Y1684890
X0958780Y1694890
X0958780Y1704890
X0968780Y1684890
X0968780Y1694890
X0968780Y1704890
X0898780Y1714890
X0898780Y1704890
X0898780Y1694890
X0898780Y1684890
X0888780Y1714890
X0888780Y1704890
X0888780Y1694890
X0888780Y1684890
X1038780Y1714890
X1038780Y1704890
X1038780Y1694890
X1038780Y1684890
X1028780Y1714890
X1028780Y1704890
X1028780Y1694890
X1028780Y1684890
X1003780Y1714890
X1003780Y1704890
X1003780Y1694890
X1003780Y1684890
X0993780Y1714890
X0993780Y1704890
X0993780Y1694890
X0993780Y1684890
M00
X0470000Y0278543
X0460000Y0278543
X0450000Y0278543
X0520000Y0278543
X0510000Y0278543
X0500000Y0278543
X0490000Y0278543
X0480000Y0278543
X0473500Y0246362
X0483500Y0246362
X0493500Y0246362
X0498563Y0607067
X0508563Y0607067
X0518563Y0607067
X0549236Y1441207
X0559236Y1441207
X0569236Y1441207
X0688500Y1621900
X0688500Y1611900
X0688500Y1601900
X1056225Y0163131
X1056225Y0153131
X1056225Y0143131
X1041435Y0163357
X1041435Y0153357
X1041435Y0143357
X1099970Y1722570
X1099970Y1712570
X1099970Y1702570
X1679646Y0175669
X1679646Y0165669
X1679646Y0155669
X1679646Y0145669
X1679646Y0135669
X1679646Y0125669
X1679646Y0115669
X1689646Y0175669
X1689646Y0165669
X1689646Y0155669
X1689646Y0145669
X1689646Y0135669
X1689646Y0125669
X1689646Y0115669
X1771457Y1624646
X1771457Y1634646
X1771457Y1644646
M00
X0159474Y1328627
X0159474Y1320753
X0208247Y1328652
X0208247Y1320778
X0183847Y1328652
X0183847Y1320778
X0270252Y0700414
X0270252Y0676260
X0275289Y0575702
X0275289Y0631889
X0275289Y0624015
X0278126Y0676260
X0275289Y0656043
X0275289Y0648169
X0275289Y0607735
X0275289Y0599861
X0275289Y0583576
X0278126Y0700414
X0412297Y1242785
X0420171Y1242785
X0436619Y1242785
X0444493Y1242785
X0461019Y1242785
X0468893Y1242785
X0387897Y1242785
X0395771Y1242785
X0485419Y1242785
X0493293Y1242785
X0697466Y1328677
X0697466Y1320803
X0673093Y1328652
X0673093Y1320778
X0721866Y1328677
X0721866Y1320803
X1100700Y0275788
X1100800Y0259362
X1100800Y0251488
X1100700Y0283662
X1131100Y1364962
X1131100Y1357088
X1155500Y1364962
X1155500Y1357088
X1179900Y1364962
X1179900Y1357088
X1364038Y1242785
X1371912Y1242785
X1388438Y1242785
X1396312Y1242785
X1412760Y1242785
X1420634Y1242785
X1437160Y1242785
X1445034Y1242785
X1461560Y1242785
X1469434Y1242785
X1634259Y1362248
X1634259Y1354374
X1658632Y1362273
X1658632Y1354399
X1577000Y0697662
X1577000Y0689788
X1577000Y0722162
X1577000Y0714288
X1577000Y0599762
X1577000Y0591888
X1577000Y0624262
X1577000Y0616388
X1577000Y0648762
X1577000Y0640888
X1577000Y0673162
X1577000Y0665288
X1683032Y1362273
X1683032Y1354399
M00
X0057646Y0012480
X0137272Y0012480
X0266858Y0012480
X0186622Y0012480
X0315598Y0012480
X0502528Y0033268
X0631504Y0033268
X0582154Y0033268
X0760480Y0033268
X0711740Y0033268
X1156378Y0133866
X1532055Y0012480
X1661031Y0012480
X1611681Y0012480
X1741267Y0012480
X1790007Y0012480
M00
X1876720Y1001463
X1886720Y1001463
X1881720Y0988279
X1907608Y1001506
X1897608Y1001506
X1902608Y0988322
X1885836Y1303980
X1875836Y1303980
X1880836Y1317164
X1876211Y1364167
X1886211Y1364167
X1881211Y1350983
X1898086Y1305044
X1908086Y1305044
X1903086Y1318228
X1907682Y1364479
X1897682Y1364479
X1902682Y1351295
X1925200Y1362732
X1935200Y1362732
X1930200Y1349548
X1956178Y1362781
X1946178Y1362781
X1951178Y1349597
X1967697Y1362790
X1886165Y1669023
X1876165Y1669023
X1881165Y1682207
X1897402Y1670072
X1907402Y1670072
X1902402Y1683256
X1934695Y1670036
X1924695Y1670036
X1929695Y1683220
X1945484Y1670313
X1955484Y1670313
X1950484Y1683497
X1966555Y1669946
X1971555Y1683130
X1976555Y1669946
X1988147Y1669691
X1998147Y1669691
X1993147Y1682875
X1977697Y1362790
X1972697Y1349606
X1998618Y1363081
X1988618Y1363081
X1993618Y1349897
M00
X0944684Y0155216
X0900196Y0175197
M00
X0322500Y1391830
X0537477Y1395413
X1298642Y1391830
X1513618Y1395413
M00
X0277098Y0185236
X0395208Y0185236
M00
X1133779Y1653543
M00
X0051181Y1714961
X0040708Y1368897
X0040708Y0631890
X0027559Y0087795
X0395670Y1714961
X0373622Y0087795
X0661023Y0631890
X0707677Y1714961
X0800787Y0087795
X0931692Y0757874
X0931692Y1072834
X0931692Y1387795
X1045865Y0087795
X1155708Y1714961
X1271260Y0631890
X1461805Y1714961
X1499606Y0087795
X1806299Y1714961
X1816771Y1368897
X1816771Y0631890
X1829921Y0087795
M00
X1131715Y1532913
X1175215Y1532913
M00
X0070472Y0236220
X0070472Y0173228
M00
X0730760Y-0016500
X0705760Y-0016500
X0730760Y-0026500
X0730760Y-0016500
X0705760Y-0026500
X0705760Y-0016500
X0730760Y-0006500
X0705760Y-0006500
X0847720Y0023500
X0847720Y0013500
X0822720Y0023500
X0822720Y0013500
X0847720Y0003500
X0847720Y0013500
X0822720Y0003500
X0822720Y0013500
X0973180Y0013500
X0973180Y0023500
X0998180Y0013500
X0998180Y0023500
X0973180Y0013500
X0973180Y0003500
X0998180Y0013500
X0998180Y0003500
X1040152Y0023489
X1040152Y0013489
X1015152Y0023489
X1015152Y0013489
X1040152Y0003489
X1040152Y0013489
X1015152Y0003489
X1015152Y0013489
X1040152Y0003489
X1040152Y-0006511
X1015152Y0003489
X1015152Y-0006511
X0973180Y-0006500
X0998180Y-0006500
X1040152Y-0006511
X1015152Y-0006511
X1040152Y-0016511
X1040152Y-0026511
X1015152Y-0016511
X1015152Y-0026511
X0973180Y-0016500
X0998180Y-0016500
X0973180Y-0016500
X0973180Y-0026500
X0998180Y-0016500
X0998180Y-0026500
X1040152Y-0036511
X1040152Y-0026511
X1015152Y-0036511
X1015152Y-0026511
X1040152Y-0016511
X1015152Y-0016511
X1349471Y-0016511
X1349471Y-0026511
X1324471Y-0016511
X1324471Y-0026511
X1282572Y-0026511
X1282572Y-0016511
X1307572Y-0026511
X1307572Y-0016511
X1349471Y-0036511
X1349471Y-0026511
X1324471Y-0036511
X1324471Y-0026511
X1349471Y-0016511
X1324471Y-0016511
X1282572Y-0016511
X1307572Y-0016511
X1282572Y-0026511
X1282572Y-0036511
X1307572Y-0026511
X1307572Y-0036511
X1349471Y0023489
X1349471Y0013489
X1324471Y0023489
X1324471Y0013489
X1349471Y0003489
X1349471Y0013489
X1324471Y0003489
X1324471Y0013489
X1349471Y0003489
X1349471Y-0006511
X1324471Y0003489
X1324471Y-0006511
X1282572Y0013489
X1282572Y0023489
X1307572Y0013489
X1307572Y0023489
X1282572Y0013489
X1282572Y0003489
X1307572Y0013489
X1307572Y0003489
X1282572Y-0006511
X1282572Y0003489
X1307572Y-0006511
X1307572Y0003489
X1349471Y-0006511
X1324471Y-0006511
X1282572Y-0006511
X1307572Y-0006511
X1474931Y-0026511
X1474931Y-0016511
X1499931Y-0026511
X1499931Y-0016511
X1474931Y-0026511
X1474931Y-0036511
X1499931Y-0026511
X1499931Y-0036511
X1474931Y-0016511
X1499931Y-0016511
X1474931Y0013489
X1474931Y0023489
X1499931Y0013489
X1499931Y0023489
X1474931Y0013489
X1474931Y0003489
X1499931Y0013489
X1499931Y0003489
X1474931Y-0006511
X1474931Y0003489
X1499931Y-0006511
X1499931Y0003489
X1474931Y-0006511
X1499931Y-0006511
X1565236Y0264035
X1565236Y0184783
M00
X0060303Y0020354
X0312921Y0024291
X0505185Y0041142
X0757803Y0045079
X0929331Y0160413
X0922441Y0237697
X1534712Y0020354
X1787330Y0024291
M00
X0676508Y0224606
M00
X0676508Y0145866
M00
X0791280Y1704890
X1066280Y1704890
M00
X1247638Y0269488
X1405118Y0112008
X1766929Y1714960
M00
X0041870Y1511291
X0049280Y0337402
X1808192Y1569255
X1812980Y0502472
M00
X0441043Y1698268
X0441043Y1718465
X0441043Y1672205
X1416437Y1698267
X1416437Y1718464
X1416437Y1672204
M00
X0350099Y0811121
X0306772Y0991220
X0356063Y1171318
X0531240Y0811121
X0525276Y1171318
X0574567Y0991220
X1326240Y0811121
X1282914Y0991220
X1332205Y1171318
X1507382Y0811121
X1550709Y0991220
X1501418Y1171318
M00
X0841240Y1420330
X1016240Y1420330
M00
X0805690Y0204724
X1057658Y0204724
M00
X0038346Y1420330
X0117932Y0605380
X0763601Y0605413
X1094074Y0605380
X1739706Y0605455
X1819208Y1420330
M30
